(lib_symbols
	(symbol "+1V8_1"
			(power)
			(pin_numbers hide)
			(pin_names hide)
			(exclude_from_sim no)
			(in_bom yes)
			(on_board yes)
			(property "Reference" "#PWR"
				(at 15.24 -2.54 0)
				(effects
					(font
						(size 1.27 1.27)
						(thickness 0.15)
					)
					(justify left bottom)
					(hide yes)
				)
			)
			(property "Value" "+1V8_1"
				(at -3.175 2.54 0)
				(effects
					(font
						(size 1.27 1.27)
						(thickness 0.15)
					)
					(justify left bottom)
				)
			)
			(property "Footprint" ""
				(at 15.24 -7.62 0)
				(effects
					(font
						(size 1.27 1.27)
						(thickness 0.15)
					)
					(justify left bottom)
					(hide yes)
				)
			)
			(property "Datasheet" ""
				(at 15.24 -10.16 0)
				(effects
					(font
						(size 1.27 1.27)
						(thickness 0.15)
					)
					(justify left bottom)
					(hide yes)
				)
			)
			(property "Description" ""
				(at 0 0 0)
				(effects
					(font
						(size 1.27 1.27)
					)
					(hide yes)
				)
			)
			(property "Author" "Antmicro"
				(at 15.24 -5.08 0)
				(effects
					(font
						(size 1.27 1.27)
						(thickness 0.15)
					)
					(justify left bottom)
					(hide yes)
				)
			)
			(property "License" "Apache-2.0"
				(at 15.24 -7.62 0)
				(effects
					(font
						(size 1.27 1.27)
						(thickness 0.15)
					)
					(justify left bottom)
					(hide yes)
				)
			)
			(symbol "+1V8_1_1_1"
				(polyline
					(pts
						(xy -0.762 1.27) (xy 0 2.54)
					)
					(stroke
						(width 0)
						(type default)
					)
					(fill
						(type background)
					)
				)
				(polyline
					(pts
						(xy 0 0) (xy 0 2.54)
					)
					(stroke
						(width 0)
						(type default)
					)
					(fill
						(type background)
					)
				)
				(polyline
					(pts
						(xy 0 2.54) (xy 0.762 1.27)
					)
					(stroke
						(width 0)
						(type default)
					)
					(fill
						(type background)
					)
				)
				(pin power_in line
					(at 0 0 90)
					(length 0) hide
					(name "+1V8"
						(effects
							(font
								(size 1.27 1.27)
							)
						)
					)
					(number "1"
						(effects
							(font
								(size 1.27 1.27)
							)
						)
					)
				)
			)
		)
	(symbol "+3V3_1"
			(power)
			(pin_numbers hide)
			(pin_names hide)
			(exclude_from_sim no)
			(in_bom yes)
			(on_board yes)
			(property "Reference" "#PWR"
				(at 15.24 0 0)
				(effects
					(font
						(size 1.27 1.27)
						(thickness 0.15)
					)
					(justify left bottom)
					(hide yes)
				)
			)
			(property "Value" "+3V3_1"
				(at -3.175 2.54 0)
				(effects
					(font
						(size 1.27 1.27)
						(thickness 0.15)
					)
					(justify left bottom)
				)
			)
			(property "Footprint" ""
				(at 15.24 -7.62 0)
				(effects
					(font
						(size 1.27 1.27)
						(thickness 0.15)
					)
					(justify left bottom)
					(hide yes)
				)
			)
			(property "Datasheet" ""
				(at 15.24 -10.16 0)
				(effects
					(font
						(size 1.27 1.27)
						(thickness 0.15)
					)
					(justify left bottom)
					(hide yes)
				)
			)
			(property "Description" ""
				(at 0 0 0)
				(effects
					(font
						(size 1.27 1.27)
					)
					(hide yes)
				)
			)
			(property "Author" "Antmicro"
				(at 15.24 -2.54 0)
				(effects
					(font
						(size 1.27 1.27)
						(thickness 0.15)
					)
					(justify left bottom)
					(hide yes)
				)
			)
			(property "License" "Apache-2.0"
				(at 15.24 -5.08 0)
				(effects
					(font
						(size 1.27 1.27)
						(thickness 0.15)
					)
					(justify left bottom)
					(hide yes)
				)
			)
			(symbol "+3V3_1_0_1"
				(polyline
					(pts
						(xy 0 0) (xy 0 2.54)
					)
					(stroke
						(width 0)
						(type default)
					)
					(fill
						(type none)
					)
				)
				(polyline
					(pts
						(xy 0 2.54) (xy -0.762 1.27)
					)
					(stroke
						(width 0)
						(type default)
					)
					(fill
						(type none)
					)
				)
				(polyline
					(pts
						(xy 0 2.54) (xy 0.762 1.27)
					)
					(stroke
						(width 0)
						(type default)
					)
					(fill
						(type none)
					)
				)
			)
			(symbol "+3V3_1_1_1"
				(pin power_in line
					(at 0 0 90)
					(length 0) hide
					(name "+3V3"
						(effects
							(font
								(size 1.27 1.27)
							)
						)
					)
					(number "1"
						(effects
							(font
								(size 1.27 1.27)
							)
						)
					)
				)
			)
		)
	(symbol "+3V3_2"
			(power)
			(pin_numbers hide)
			(pin_names hide)
			(exclude_from_sim no)
			(in_bom yes)
			(on_board yes)
			(property "Reference" "#PWR"
				(at 15.24 0 0)
				(effects
					(font
						(size 1.27 1.27)
						(thickness 0.15)
					)
					(justify left bottom)
					(hide yes)
				)
			)
			(property "Value" "+3V3_2"
				(at -3.175 2.54 0)
				(effects
					(font
						(size 1.27 1.27)
						(thickness 0.15)
					)
					(justify left bottom)
				)
			)
			(property "Footprint" ""
				(at 15.24 -7.62 0)
				(effects
					(font
						(size 1.27 1.27)
						(thickness 0.15)
					)
					(justify left bottom)
					(hide yes)
				)
			)
			(property "Datasheet" ""
				(at 15.24 -10.16 0)
				(effects
					(font
						(size 1.27 1.27)
						(thickness 0.15)
					)
					(justify left bottom)
					(hide yes)
				)
			)
			(property "Description" ""
				(at 0 0 0)
				(effects
					(font
						(size 1.27 1.27)
					)
					(hide yes)
				)
			)
			(property "Author" "Antmicro"
				(at 15.24 -2.54 0)
				(effects
					(font
						(size 1.27 1.27)
						(thickness 0.15)
					)
					(justify left bottom)
					(hide yes)
				)
			)
			(property "License" "Apache-2.0"
				(at 15.24 -5.08 0)
				(effects
					(font
						(size 1.27 1.27)
						(thickness 0.15)
					)
					(justify left bottom)
					(hide yes)
				)
			)
			(symbol "+3V3_2_0_1"
				(polyline
					(pts
						(xy 0 0) (xy 0 2.54)
					)
					(stroke
						(width 0)
						(type default)
					)
					(fill
						(type none)
					)
				)
				(polyline
					(pts
						(xy 0 2.54) (xy -0.762 1.27)
					)
					(stroke
						(width 0)
						(type default)
					)
					(fill
						(type none)
					)
				)
				(polyline
					(pts
						(xy 0 2.54) (xy 0.762 1.27)
					)
					(stroke
						(width 0)
						(type default)
					)
					(fill
						(type none)
					)
				)
			)
			(symbol "+3V3_2_1_1"
				(pin power_in line
					(at 0 0 90)
					(length 0) hide
					(name "+3V3"
						(effects
							(font
								(size 1.27 1.27)
							)
						)
					)
					(number "1"
						(effects
							(font
								(size 1.27 1.27)
							)
						)
					)
				)
			)
		)
	(symbol "+3V3_3"
			(power)
			(pin_numbers hide)
			(pin_names hide)
			(exclude_from_sim no)
			(in_bom yes)
			(on_board yes)
			(property "Reference" "#PWR"
				(at 15.24 0 0)
				(effects
					(font
						(size 1.27 1.27)
						(thickness 0.15)
					)
					(justify left bottom)
					(hide yes)
				)
			)
			(property "Value" "+3V3_3"
				(at -3.175 2.54 0)
				(effects
					(font
						(size 1.27 1.27)
						(thickness 0.15)
					)
					(justify left bottom)
				)
			)
			(property "Footprint" ""
				(at 15.24 -7.62 0)
				(effects
					(font
						(size 1.27 1.27)
						(thickness 0.15)
					)
					(justify left bottom)
					(hide yes)
				)
			)
			(property "Datasheet" ""
				(at 15.24 -10.16 0)
				(effects
					(font
						(size 1.27 1.27)
						(thickness 0.15)
					)
					(justify left bottom)
					(hide yes)
				)
			)
			(property "Description" ""
				(at 0 0 0)
				(effects
					(font
						(size 1.27 1.27)
					)
					(hide yes)
				)
			)
			(property "Author" "Antmicro"
				(at 15.24 -2.54 0)
				(effects
					(font
						(size 1.27 1.27)
						(thickness 0.15)
					)
					(justify left bottom)
					(hide yes)
				)
			)
			(property "License" "Apache-2.0"
				(at 15.24 -5.08 0)
				(effects
					(font
						(size 1.27 1.27)
						(thickness 0.15)
					)
					(justify left bottom)
					(hide yes)
				)
			)
			(symbol "+3V3_3_0_1"
				(polyline
					(pts
						(xy 0 0) (xy 0 2.54)
					)
					(stroke
						(width 0)
						(type default)
					)
					(fill
						(type none)
					)
				)
				(polyline
					(pts
						(xy 0 2.54) (xy -0.762 1.27)
					)
					(stroke
						(width 0)
						(type default)
					)
					(fill
						(type none)
					)
				)
				(polyline
					(pts
						(xy 0 2.54) (xy 0.762 1.27)
					)
					(stroke
						(width 0)
						(type default)
					)
					(fill
						(type none)
					)
				)
			)
			(symbol "+3V3_3_1_1"
				(pin power_in line
					(at 0 0 90)
					(length 0) hide
					(name "+3V3"
						(effects
							(font
								(size 1.27 1.27)
							)
						)
					)
					(number "1"
						(effects
							(font
								(size 1.27 1.27)
							)
						)
					)
				)
			)
		)
	(symbol "+3V3_4"
			(power)
			(pin_numbers hide)
			(pin_names hide)
			(exclude_from_sim no)
			(in_bom yes)
			(on_board yes)
			(property "Reference" "#PWR"
				(at 15.24 0 0)
				(effects
					(font
						(size 1.27 1.27)
						(thickness 0.15)
					)
					(justify left bottom)
					(hide yes)
				)
			)
			(property "Value" "+3V3_4"
				(at -3.175 2.54 0)
				(effects
					(font
						(size 1.27 1.27)
						(thickness 0.15)
					)
					(justify left bottom)
				)
			)
			(property "Footprint" ""
				(at 15.24 -7.62 0)
				(effects
					(font
						(size 1.27 1.27)
						(thickness 0.15)
					)
					(justify left bottom)
					(hide yes)
				)
			)
			(property "Datasheet" ""
				(at 15.24 -10.16 0)
				(effects
					(font
						(size 1.27 1.27)
						(thickness 0.15)
					)
					(justify left bottom)
					(hide yes)
				)
			)
			(property "Description" ""
				(at 0 0 0)
				(effects
					(font
						(size 1.27 1.27)
					)
					(hide yes)
				)
			)
			(property "Author" "Antmicro"
				(at 15.24 -2.54 0)
				(effects
					(font
						(size 1.27 1.27)
						(thickness 0.15)
					)
					(justify left bottom)
					(hide yes)
				)
			)
			(property "License" "Apache-2.0"
				(at 15.24 -5.08 0)
				(effects
					(font
						(size 1.27 1.27)
						(thickness 0.15)
					)
					(justify left bottom)
					(hide yes)
				)
			)
			(symbol "+3V3_4_0_1"
				(polyline
					(pts
						(xy 0 0) (xy 0 2.54)
					)
					(stroke
						(width 0)
						(type default)
					)
					(fill
						(type none)
					)
				)
				(polyline
					(pts
						(xy 0 2.54) (xy -0.762 1.27)
					)
					(stroke
						(width 0)
						(type default)
					)
					(fill
						(type none)
					)
				)
				(polyline
					(pts
						(xy 0 2.54) (xy 0.762 1.27)
					)
					(stroke
						(width 0)
						(type default)
					)
					(fill
						(type none)
					)
				)
			)
			(symbol "+3V3_4_1_1"
				(pin power_in line
					(at 0 0 90)
					(length 0) hide
					(name "+3V3"
						(effects
							(font
								(size 1.27 1.27)
							)
						)
					)
					(number "1"
						(effects
							(font
								(size 1.27 1.27)
							)
						)
					)
				)
			)
		)
	(symbol "+5V_1"
			(power)
			(pin_numbers hide)
			(pin_names hide)
			(exclude_from_sim no)
			(in_bom yes)
			(on_board yes)
			(property "Reference" "#PWR"
				(at 15.24 -2.54 0)
				(effects
					(font
						(size 1.27 1.27)
						(thickness 0.15)
					)
					(justify left bottom)
					(hide yes)
				)
			)
			(property "Value" "+5V_1"
				(at 15.24 -5.08 0)
				(effects
					(font
						(size 1.27 1.27)
						(thickness 0.15)
					)
					(justify left bottom)
				)
			)
			(property "Footprint" ""
				(at 15.24 -7.62 0)
				(effects
					(font
						(size 1.27 1.27)
						(thickness 0.15)
					)
					(justify left bottom)
					(hide yes)
				)
			)
			(property "Datasheet" ""
				(at 15.24 -10.16 0)
				(effects
					(font
						(size 1.27 1.27)
						(thickness 0.15)
					)
					(justify left bottom)
					(hide yes)
				)
			)
			(property "Description" ""
				(at 0 0 0)
				(effects
					(font
						(size 1.27 1.27)
					)
					(hide yes)
				)
			)
			(property "Author" "Antmicro"
				(at 15.24 -7.62 0)
				(effects
					(font
						(size 1.27 1.27)
						(thickness 0.15)
					)
					(justify left bottom)
					(hide yes)
				)
			)
			(property "License" "Apache-2.0"
				(at 15.24 -10.16 0)
				(effects
					(font
						(size 1.27 1.27)
						(thickness 0.15)
					)
					(justify left bottom)
					(hide yes)
				)
			)
			(symbol "+5V_1_1_1"
				(polyline
					(pts
						(xy -0.762 1.27) (xy 0 2.54)
					)
					(stroke
						(width 0)
						(type default)
					)
					(fill
						(type background)
					)
				)
				(polyline
					(pts
						(xy 0 0) (xy 0 2.54)
					)
					(stroke
						(width 0)
						(type default)
					)
					(fill
						(type background)
					)
				)
				(polyline
					(pts
						(xy 0 2.54) (xy 0.762 1.27)
					)
					(stroke
						(width 0)
						(type default)
					)
					(fill
						(type background)
					)
				)
				(pin power_in line
					(at 0 0 90)
					(length 0)
					(name "+5V"
						(effects
							(font
								(size 1.27 1.27)
							)
						)
					)
					(number "1"
						(effects
							(font
								(size 1.27 1.27)
							)
						)
					)
				)
			)
		)
	(symbol "+5V_2"
			(power)
			(pin_numbers hide)
			(pin_names hide)
			(exclude_from_sim no)
			(in_bom yes)
			(on_board yes)
			(property "Reference" "#PWR"
				(at 15.24 -2.54 0)
				(effects
					(font
						(size 1.27 1.27)
						(thickness 0.15)
					)
					(justify left bottom)
					(hide yes)
				)
			)
			(property "Value" "+5V_2"
				(at 15.24 -5.08 0)
				(effects
					(font
						(size 1.27 1.27)
						(thickness 0.15)
					)
					(justify left bottom)
				)
			)
			(property "Footprint" ""
				(at 15.24 -7.62 0)
				(effects
					(font
						(size 1.27 1.27)
						(thickness 0.15)
					)
					(justify left bottom)
					(hide yes)
				)
			)
			(property "Datasheet" ""
				(at 15.24 -10.16 0)
				(effects
					(font
						(size 1.27 1.27)
						(thickness 0.15)
					)
					(justify left bottom)
					(hide yes)
				)
			)
			(property "Description" ""
				(at 0 0 0)
				(effects
					(font
						(size 1.27 1.27)
					)
					(hide yes)
				)
			)
			(property "Author" "Antmicro"
				(at 15.24 -7.62 0)
				(effects
					(font
						(size 1.27 1.27)
						(thickness 0.15)
					)
					(justify left bottom)
					(hide yes)
				)
			)
			(property "License" "Apache-2.0"
				(at 15.24 -10.16 0)
				(effects
					(font
						(size 1.27 1.27)
						(thickness 0.15)
					)
					(justify left bottom)
					(hide yes)
				)
			)
			(symbol "+5V_2_1_1"
				(polyline
					(pts
						(xy -0.762 1.27) (xy 0 2.54)
					)
					(stroke
						(width 0)
						(type default)
					)
					(fill
						(type background)
					)
				)
				(polyline
					(pts
						(xy 0 0) (xy 0 2.54)
					)
					(stroke
						(width 0)
						(type default)
					)
					(fill
						(type background)
					)
				)
				(polyline
					(pts
						(xy 0 2.54) (xy 0.762 1.27)
					)
					(stroke
						(width 0)
						(type default)
					)
					(fill
						(type background)
					)
				)
				(pin power_in line
					(at 0 0 90)
					(length 0)
					(name "+5V"
						(effects
							(font
								(size 1.27 1.27)
							)
						)
					)
					(number "1"
						(effects
							(font
								(size 1.27 1.27)
							)
						)
					)
				)
			)
		)
	(symbol "+5V_3"
			(power)
			(pin_numbers hide)
			(pin_names hide)
			(exclude_from_sim no)
			(in_bom yes)
			(on_board yes)
			(property "Reference" "#PWR"
				(at 15.24 -2.54 0)
				(effects
					(font
						(size 1.27 1.27)
						(thickness 0.15)
					)
					(justify left bottom)
					(hide yes)
				)
			)
			(property "Value" "+5V_3"
				(at 15.24 -5.08 0)
				(effects
					(font
						(size 1.27 1.27)
						(thickness 0.15)
					)
					(justify left bottom)
				)
			)
			(property "Footprint" ""
				(at 15.24 -7.62 0)
				(effects
					(font
						(size 1.27 1.27)
						(thickness 0.15)
					)
					(justify left bottom)
					(hide yes)
				)
			)
			(property "Datasheet" ""
				(at 15.24 -10.16 0)
				(effects
					(font
						(size 1.27 1.27)
						(thickness 0.15)
					)
					(justify left bottom)
					(hide yes)
				)
			)
			(property "Description" ""
				(at 0 0 0)
				(effects
					(font
						(size 1.27 1.27)
					)
					(hide yes)
				)
			)
			(property "Author" "Antmicro"
				(at 15.24 -7.62 0)
				(effects
					(font
						(size 1.27 1.27)
						(thickness 0.15)
					)
					(justify left bottom)
					(hide yes)
				)
			)
			(property "License" "Apache-2.0"
				(at 15.24 -10.16 0)
				(effects
					(font
						(size 1.27 1.27)
						(thickness 0.15)
					)
					(justify left bottom)
					(hide yes)
				)
			)
			(symbol "+5V_3_1_1"
				(polyline
					(pts
						(xy -0.762 1.27) (xy 0 2.54)
					)
					(stroke
						(width 0)
						(type default)
					)
					(fill
						(type background)
					)
				)
				(polyline
					(pts
						(xy 0 0) (xy 0 2.54)
					)
					(stroke
						(width 0)
						(type default)
					)
					(fill
						(type background)
					)
				)
				(polyline
					(pts
						(xy 0 2.54) (xy 0.762 1.27)
					)
					(stroke
						(width 0)
						(type default)
					)
					(fill
						(type background)
					)
				)
				(pin power_in line
					(at 0 0 90)
					(length 0)
					(name "+5V"
						(effects
							(font
								(size 1.27 1.27)
							)
						)
					)
					(number "1"
						(effects
							(font
								(size 1.27 1.27)
							)
						)
					)
				)
			)
		)
	(symbol "AP22615A_TSOT26_1"
			(exclude_from_sim no)
			(in_bom yes)
			(on_board yes)
			(property "Reference" "U"
				(at 30.48 -2.54 0)
				(effects
					(font
						(size 1.27 1.27)
						(thickness 0.15)
					)
					(justify left bottom)
				)
			)
			(property "Value" "AP22615A_TSOT26"
				(at 30.48 -5.08 0)
				(effects
					(font
						(size 1.27 1.27)
						(thickness 0.15)
					)
					(justify left bottom)
					(hide yes)
				)
			)
			(property "Footprint" "antmicro-footprints:TSOT23-6"
				(at 30.48 -7.62 0)
				(effects
					(font
						(size 1.27 1.27)
						(thickness 0.15)
					)
					(justify left bottom)
					(hide yes)
				)
			)
			(property "Datasheet" "https://www.mouser.com/datasheet/2/115/DIOD_S_A0008958405_1-2543193.pdf"
				(at 30.48 -10.16 0)
				(effects
					(font
						(size 1.27 1.27)
						(thickness 0.15)
					)
					(justify left bottom)
					(hide yes)
				)
			)
			(property "Description" "Power Load Distribution Switch, High Side, Active High, 1 Output, 5.5 V, 3.6 A, 0.04 ohm, TSOT-26-6"
				(at 0 0 0)
				(effects
					(font
						(size 1.27 1.27)
					)
					(hide yes)
				)
			)
			(property "MPN" "AP22615AWU-7"
				(at 30.48 -12.7 0)
				(effects
					(font
						(size 1.27 1.27)
						(thickness 0.15)
					)
					(justify left bottom)
				)
			)
			(property "Manufacturer" "Diodes Incorporated"
				(at 30.48 -15.24 0)
				(effects
					(font
						(size 1.27 1.27)
						(thickness 0.15)
					)
					(justify left bottom)
					(hide yes)
				)
			)
			(property "Author" "Antmicro"
				(at 30.48 -17.78 0)
				(effects
					(font
						(size 1.27 1.27)
						(thickness 0.15)
					)
					(justify left bottom)
					(hide yes)
				)
			)
			(property "License" "Apache-2.0"
				(at 30.48 -20.32 0)
				(effects
					(font
						(size 1.27 1.27)
						(thickness 0.15)
					)
					(justify left bottom)
					(hide yes)
				)
			)
			(property "ki_keywords" "SMT, PMIC, IC, VOLTAGE"
				(at 0 0 0)
				(effects
					(font
						(size 1.27 1.27)
					)
					(hide yes)
				)
			)
			(symbol "AP22615A_TSOT26_1_1_1"
				(rectangle
					(start 2.54 2.54)
					(end 12.7 -7.62)
					(stroke
						(width 0.254)
						(type default)
					)
					(fill
						(type background)
					)
				)
				(pin power_out line
					(at 15.24 0 180)
					(length 2.54)
					(name "OUT"
						(effects
							(font
								(size 1.27 1.27)
							)
						)
					)
					(number "1"
						(effects
							(font
								(size 1.27 1.27)
							)
						)
					)
				)
				(pin power_in line
					(at 15.24 -5.08 180)
					(length 2.54)
					(name "GND"
						(effects
							(font
								(size 1.27 1.27)
							)
						)
					)
					(number "2"
						(effects
							(font
								(size 1.27 1.27)
							)
						)
					)
				)
				(pin output line
					(at 0 -2.54 0)
					(length 2.54)
					(name "FLG"
						(effects
							(font
								(size 1.27 1.27)
							)
						)
					)
					(number "3"
						(effects
							(font
								(size 1.27 1.27)
							)
						)
					)
				)
				(pin input line
					(at 0 -5.08 0)
					(length 2.54)
					(name "EN"
						(effects
							(font
								(size 1.27 1.27)
							)
						)
					)
					(number "4"
						(effects
							(font
								(size 1.27 1.27)
							)
						)
					)
				)
				(pin passive line
					(at 15.24 -2.54 180)
					(length 2.54)
					(name "ISET"
						(effects
							(font
								(size 1.27 1.27)
							)
						)
					)
					(number "5"
						(effects
							(font
								(size 1.27 1.27)
							)
						)
					)
				)
				(pin power_in line
					(at 0 0 0)
					(length 2.54)
					(name "IN"
						(effects
							(font
								(size 1.27 1.27)
							)
						)
					)
					(number "6"
						(effects
							(font
								(size 1.27 1.27)
							)
						)
					)
				)
			)
		)
	(symbol "C_100n_0402_1"
			(pin_numbers hide)
			(pin_names hide)
			(exclude_from_sim no)
			(in_bom yes)
			(on_board yes)
			(property "Reference" "C"
				(at 20.32 -5.08 0)
				(effects
					(font
						(size 1.27 1.27)
						(thickness 0.15)
					)
					(justify left bottom)
				)
			)
			(property "Value" "C_100n_0402"
				(at 20.32 -10.16 0)
				(effects
					(font
						(size 1.27 1.27)
						(thickness 0.15)
					)
					(justify left bottom)
					(hide yes)
				)
			)
			(property "Footprint" "antmicro-footprints:C_0402_1005Metric"
				(at 20.32 -12.7 0)
				(effects
					(font
						(size 1.27 1.27)
						(thickness 0.15)
					)
					(justify left bottom)
					(hide yes)
				)
			)
			(property "Datasheet" "https://www.murata.com/products/productdetail?partno=GRM155R61H104KE14%23"
				(at 20.32 -15.24 0)
				(effects
					(font
						(size 1.27 1.27)
						(thickness 0.15)
					)
					(justify left bottom)
					(hide yes)
				)
			)
			(property "Description" "SMD Multilayer Ceramic Capacitor, 0.1 µF, 50 V, 0402 [1005 Metric], ± 10%, X5R, GRM Series"
				(at 0 0 0)
				(effects
					(font
						(size 1.27 1.27)
					)
					(hide yes)
				)
			)
			(property "MPN" "GRM155R61H104KE14D"
				(at 20.32 -17.78 0)
				(effects
					(font
						(size 1.27 1.27)
						(thickness 0.15)
					)
					(justify left bottom)
					(hide yes)
				)
			)
			(property "Manufacturer" "Murata"
				(at 20.32 -20.32 0)
				(effects
					(font
						(size 1.27 1.27)
						(thickness 0.15)
					)
					(justify left bottom)
					(hide yes)
				)
			)
			(property "License" "Apache-2.0"
				(at 20.32 -22.86 0)
				(effects
					(font
						(size 1.27 1.27)
						(thickness 0.15)
					)
					(justify left bottom)
					(hide yes)
				)
			)
			(property "Author" "Antmicro"
				(at 20.32 -25.4 0)
				(effects
					(font
						(size 1.27 1.27)
						(thickness 0.15)
					)
					(justify left bottom)
					(hide yes)
				)
			)
			(property "Val" "100n"
				(at 20.32 -7.62 0)
				(effects
					(font
						(size 1.27 1.27)
						(thickness 0.15)
					)
					(justify left bottom)
				)
			)
			(property "Voltage" "50V"
				(at 20.32 -27.94 0)
				(effects
					(font
						(size 1.27 1.27)
					)
					(justify left bottom)
					(hide yes)
				)
			)
			(property "Dielectric" "X5R"
				(at 20.32 -30.48 0)
				(effects
					(font
						(size 1.27 1.27)
					)
					(justify left bottom)
					(hide yes)
				)
			)
			(property "ki_keywords" "0402, SMT, CAPACITOR, PASSIVE, CERAMIC, MLCC"
				(at 0 0 0)
				(effects
					(font
						(size 1.27 1.27)
					)
					(hide yes)
				)
			)
			(symbol "C_100n_0402_1_0_1"
				(polyline
					(pts
						(xy 2.032 -1.524) (xy 2.032 1.524)
					)
					(stroke
						(width 0.3048)
						(type default)
					)
					(fill
						(type none)
					)
				)
				(polyline
					(pts
						(xy 3.048 -1.524) (xy 3.048 1.524)
					)
					(stroke
						(width 0.3302)
						(type default)
					)
					(fill
						(type none)
					)
				)
			)
			(symbol "C_100n_0402_1_1_1"
				(pin passive line
					(at 0 0 0)
					(length 2.032)
					(name "~"
						(effects
							(font
								(size 1.27 1.27)
							)
						)
					)
					(number "1"
						(effects
							(font
								(size 1.27 1.27)
							)
						)
					)
				)
				(pin passive line
					(at 5.08 0 180)
					(length 2.032)
					(name "~"
						(effects
							(font
								(size 1.27 1.27)
							)
						)
					)
					(number "2"
						(effects
							(font
								(size 1.27 1.27)
							)
						)
					)
				)
			)
		)
	(symbol "C_100n_0402_2"
			(pin_numbers hide)
			(pin_names hide)
			(exclude_from_sim no)
			(in_bom yes)
			(on_board yes)
			(property "Reference" "C"
				(at 20.32 -5.08 0)
				(effects
					(font
						(size 1.27 1.27)
						(thickness 0.15)
					)
					(justify left bottom)
				)
			)
			(property "Value" "C_100n_0402"
				(at 20.32 -10.16 0)
				(effects
					(font
						(size 1.27 1.27)
						(thickness 0.15)
					)
					(justify left bottom)
					(hide yes)
				)
			)
			(property "Footprint" "antmicro-footprints:C_0402_1005Metric"
				(at 20.32 -12.7 0)
				(effects
					(font
						(size 1.27 1.27)
						(thickness 0.15)
					)
					(justify left bottom)
					(hide yes)
				)
			)
			(property "Datasheet" "https://www.murata.com/products/productdetail?partno=GRM155R61H104KE14%23"
				(at 20.32 -15.24 0)
				(effects
					(font
						(size 1.27 1.27)
						(thickness 0.15)
					)
					(justify left bottom)
					(hide yes)
				)
			)
			(property "Description" "SMD Multilayer Ceramic Capacitor, 0.1 µF, 50 V, 0402 [1005 Metric], ± 10%, X5R, GRM Series"
				(at 0 0 0)
				(effects
					(font
						(size 1.27 1.27)
					)
					(hide yes)
				)
			)
			(property "MPN" "GRM155R61H104KE14D"
				(at 20.32 -17.78 0)
				(effects
					(font
						(size 1.27 1.27)
						(thickness 0.15)
					)
					(justify left bottom)
					(hide yes)
				)
			)
			(property "Manufacturer" "Murata"
				(at 20.32 -20.32 0)
				(effects
					(font
						(size 1.27 1.27)
						(thickness 0.15)
					)
					(justify left bottom)
					(hide yes)
				)
			)
			(property "License" "Apache-2.0"
				(at 20.32 -22.86 0)
				(effects
					(font
						(size 1.27 1.27)
						(thickness 0.15)
					)
					(justify left bottom)
					(hide yes)
				)
			)
			(property "Author" "Antmicro"
				(at 20.32 -25.4 0)
				(effects
					(font
						(size 1.27 1.27)
						(thickness 0.15)
					)
					(justify left bottom)
					(hide yes)
				)
			)
			(property "Val" "100n"
				(at 20.32 -7.62 0)
				(effects
					(font
						(size 1.27 1.27)
						(thickness 0.15)
					)
					(justify left bottom)
				)
			)
			(property "Voltage" "50V"
				(at 20.32 -27.94 0)
				(effects
					(font
						(size 1.27 1.27)
					)
					(justify left bottom)
					(hide yes)
				)
			)
			(property "Dielectric" "X5R"
				(at 20.32 -30.48 0)
				(effects
					(font
						(size 1.27 1.27)
					)
					(justify left bottom)
					(hide yes)
				)
			)
			(property "ki_keywords" "0402, SMT, CAPACITOR, PASSIVE, CERAMIC, MLCC"
				(at 0 0 0)
				(effects
					(font
						(size 1.27 1.27)
					)
					(hide yes)
				)
			)
			(symbol "C_100n_0402_2_0_1"
				(polyline
					(pts
						(xy 2.032 -1.524) (xy 2.032 1.524)
					)
					(stroke
						(width 0.3048)
						(type default)
					)
					(fill
						(type none)
					)
				)
				(polyline
					(pts
						(xy 3.048 -1.524) (xy 3.048 1.524)
					)
					(stroke
						(width 0.3302)
						(type default)
					)
					(fill
						(type none)
					)
				)
			)
			(symbol "C_100n_0402_2_1_1"
				(pin passive line
					(at 0 0 0)
					(length 2.032)
					(name "~"
						(effects
							(font
								(size 1.27 1.27)
							)
						)
					)
					(number "1"
						(effects
							(font
								(size 1.27 1.27)
							)
						)
					)
				)
				(pin passive line
					(at 5.08 0 180)
					(length 2.032)
					(name "~"
						(effects
							(font
								(size 1.27 1.27)
							)
						)
					)
					(number "2"
						(effects
							(font
								(size 1.27 1.27)
							)
						)
					)
				)
			)
		)
	(symbol "C_100n_0402_3"
			(pin_numbers hide)
			(pin_names hide)
			(exclude_from_sim no)
			(in_bom yes)
			(on_board yes)
			(property "Reference" "C"
				(at 20.32 -5.08 0)
				(effects
					(font
						(size 1.27 1.27)
						(thickness 0.15)
					)
					(justify left bottom)
				)
			)
			(property "Value" "C_100n_0402"
				(at 20.32 -10.16 0)
				(effects
					(font
						(size 1.27 1.27)
						(thickness 0.15)
					)
					(justify left bottom)
					(hide yes)
				)
			)
			(property "Footprint" "antmicro-footprints:C_0402_1005Metric"
				(at 20.32 -12.7 0)
				(effects
					(font
						(size 1.27 1.27)
						(thickness 0.15)
					)
					(justify left bottom)
					(hide yes)
				)
			)
			(property "Datasheet" "https://www.murata.com/products/productdetail?partno=GRM155R61H104KE14%23"
				(at 20.32 -15.24 0)
				(effects
					(font
						(size 1.27 1.27)
						(thickness 0.15)
					)
					(justify left bottom)
					(hide yes)
				)
			)
			(property "Description" "SMD Multilayer Ceramic Capacitor, 0.1 µF, 50 V, 0402 [1005 Metric], ± 10%, X5R, GRM Series"
				(at 0 0 0)
				(effects
					(font
						(size 1.27 1.27)
					)
					(hide yes)
				)
			)
			(property "MPN" "GRM155R61H104KE14D"
				(at 20.32 -17.78 0)
				(effects
					(font
						(size 1.27 1.27)
						(thickness 0.15)
					)
					(justify left bottom)
					(hide yes)
				)
			)
			(property "Manufacturer" "Murata"
				(at 20.32 -20.32 0)
				(effects
					(font
						(size 1.27 1.27)
						(thickness 0.15)
					)
					(justify left bottom)
					(hide yes)
				)
			)
			(property "License" "Apache-2.0"
				(at 20.32 -22.86 0)
				(effects
					(font
						(size 1.27 1.27)
						(thickness 0.15)
					)
					(justify left bottom)
					(hide yes)
				)
			)
			(property "Author" "Antmicro"
				(at 20.32 -25.4 0)
				(effects
					(font
						(size 1.27 1.27)
						(thickness 0.15)
					)
					(justify left bottom)
					(hide yes)
				)
			)
			(property "Val" "100n"
				(at 20.32 -7.62 0)
				(effects
					(font
						(size 1.27 1.27)
						(thickness 0.15)
					)
					(justify left bottom)
				)
			)
			(property "Voltage" "50V"
				(at 20.32 -27.94 0)
				(effects
					(font
						(size 1.27 1.27)
					)
					(justify left bottom)
					(hide yes)
				)
			)
			(property "Dielectric" "X5R"
				(at 20.32 -30.48 0)
				(effects
					(font
						(size 1.27 1.27)
					)
					(justify left bottom)
					(hide yes)
				)
			)
			(property "ki_keywords" "0402, SMT, CAPACITOR, PASSIVE, CERAMIC, MLCC"
				(at 0 0 0)
				(effects
					(font
						(size 1.27 1.27)
					)
					(hide yes)
				)
			)
			(symbol "C_100n_0402_3_0_1"
				(polyline
					(pts
						(xy 2.032 -1.524) (xy 2.032 1.524)
					)
					(stroke
						(width 0.3048)
						(type default)
					)
					(fill
						(type none)
					)
				)
				(polyline
					(pts
						(xy 3.048 -1.524) (xy 3.048 1.524)
					)
					(stroke
						(width 0.3302)
						(type default)
					)
					(fill
						(type none)
					)
				)
			)
			(symbol "C_100n_0402_3_1_1"
				(pin passive line
					(at 0 0 0)
					(length 2.032)
					(name "~"
						(effects
							(font
								(size 1.27 1.27)
							)
						)
					)
					(number "1"
						(effects
							(font
								(size 1.27 1.27)
							)
						)
					)
				)
				(pin passive line
					(at 5.08 0 180)
					(length 2.032)
					(name "~"
						(effects
							(font
								(size 1.27 1.27)
							)
						)
					)
					(number "2"
						(effects
							(font
								(size 1.27 1.27)
							)
						)
					)
				)
			)
		)
	(symbol "C_100n_0402_4"
			(pin_numbers hide)
			(pin_names hide)
			(exclude_from_sim no)
			(in_bom yes)
			(on_board yes)
			(property "Reference" "C"
				(at 20.32 -5.08 0)
				(effects
					(font
						(size 1.27 1.27)
						(thickness 0.15)
					)
					(justify left bottom)
				)
			)
			(property "Value" "C_100n_0402"
				(at 20.32 -10.16 0)
				(effects
					(font
						(size 1.27 1.27)
						(thickness 0.15)
					)
					(justify left bottom)
					(hide yes)
				)
			)
			(property "Footprint" "antmicro-footprints:C_0402_1005Metric"
				(at 20.32 -12.7 0)
				(effects
					(font
						(size 1.27 1.27)
						(thickness 0.15)
					)
					(justify left bottom)
					(hide yes)
				)
			)
			(property "Datasheet" "https://www.murata.com/products/productdetail?partno=GRM155R61H104KE14%23"
				(at 20.32 -15.24 0)
				(effects
					(font
						(size 1.27 1.27)
						(thickness 0.15)
					)
					(justify left bottom)
					(hide yes)
				)
			)
			(property "Description" "SMD Multilayer Ceramic Capacitor, 0.1 µF, 50 V, 0402 [1005 Metric], ± 10%, X5R, GRM Series"
				(at 0 0 0)
				(effects
					(font
						(size 1.27 1.27)
					)
					(hide yes)
				)
			)
			(property "MPN" "GRM155R61H104KE14D"
				(at 20.32 -17.78 0)
				(effects
					(font
						(size 1.27 1.27)
						(thickness 0.15)
					)
					(justify left bottom)
					(hide yes)
				)
			)
			(property "Manufacturer" "Murata"
				(at 20.32 -20.32 0)
				(effects
					(font
						(size 1.27 1.27)
						(thickness 0.15)
					)
					(justify left bottom)
					(hide yes)
				)
			)
			(property "License" "Apache-2.0"
				(at 20.32 -22.86 0)
				(effects
					(font
						(size 1.27 1.27)
						(thickness 0.15)
					)
					(justify left bottom)
					(hide yes)
				)
			)
			(property "Author" "Antmicro"
				(at 20.32 -25.4 0)
				(effects
					(font
						(size 1.27 1.27)
						(thickness 0.15)
					)
					(justify left bottom)
					(hide yes)
				)
			)
			(property "Val" "100n"
				(at 20.32 -7.62 0)
				(effects
					(font
						(size 1.27 1.27)
						(thickness 0.15)
					)
					(justify left bottom)
				)
			)
			(property "Voltage" "50V"
				(at 20.32 -27.94 0)
				(effects
					(font
						(size 1.27 1.27)
					)
					(justify left bottom)
					(hide yes)
				)
			)
			(property "Dielectric" "X5R"
				(at 20.32 -30.48 0)
				(effects
					(font
						(size 1.27 1.27)
					)
					(justify left bottom)
					(hide yes)
				)
			)
			(property "ki_keywords" "0402, SMT, CAPACITOR, PASSIVE, CERAMIC, MLCC"
				(at 0 0 0)
				(effects
					(font
						(size 1.27 1.27)
					)
					(hide yes)
				)
			)
			(symbol "C_100n_0402_4_0_1"
				(polyline
					(pts
						(xy 2.032 -1.524) (xy 2.032 1.524)
					)
					(stroke
						(width 0.3048)
						(type default)
					)
					(fill
						(type none)
					)
				)
				(polyline
					(pts
						(xy 3.048 -1.524) (xy 3.048 1.524)
					)
					(stroke
						(width 0.3302)
						(type default)
					)
					(fill
						(type none)
					)
				)
			)
			(symbol "C_100n_0402_4_1_1"
				(pin passive line
					(at 0 0 0)
					(length 2.032)
					(name "~"
						(effects
							(font
								(size 1.27 1.27)
							)
						)
					)
					(number "1"
						(effects
							(font
								(size 1.27 1.27)
							)
						)
					)
				)
				(pin passive line
					(at 5.08 0 180)
					(length 2.032)
					(name "~"
						(effects
							(font
								(size 1.27 1.27)
							)
						)
					)
					(number "2"
						(effects
							(font
								(size 1.27 1.27)
							)
						)
					)
				)
			)
		)
	(symbol "C_100n_0402_5"
			(pin_numbers hide)
			(pin_names hide)
			(exclude_from_sim no)
			(in_bom yes)
			(on_board yes)
			(property "Reference" "C"
				(at 20.32 -5.08 0)
				(effects
					(font
						(size 1.27 1.27)
						(thickness 0.15)
					)
					(justify left bottom)
				)
			)
			(property "Value" "C_100n_0402"
				(at 20.32 -10.16 0)
				(effects
					(font
						(size 1.27 1.27)
						(thickness 0.15)
					)
					(justify left bottom)
					(hide yes)
				)
			)
			(property "Footprint" "antmicro-footprints:C_0402_1005Metric"
				(at 20.32 -12.7 0)
				(effects
					(font
						(size 1.27 1.27)
						(thickness 0.15)
					)
					(justify left bottom)
					(hide yes)
				)
			)
			(property "Datasheet" "https://www.murata.com/products/productdetail?partno=GRM155R61H104KE14%23"
				(at 20.32 -15.24 0)
				(effects
					(font
						(size 1.27 1.27)
						(thickness 0.15)
					)
					(justify left bottom)
					(hide yes)
				)
			)
			(property "Description" "SMD Multilayer Ceramic Capacitor, 0.1 µF, 50 V, 0402 [1005 Metric], ± 10%, X5R, GRM Series"
				(at 0 0 0)
				(effects
					(font
						(size 1.27 1.27)
					)
					(hide yes)
				)
			)
			(property "MPN" "GRM155R61H104KE14D"
				(at 20.32 -17.78 0)
				(effects
					(font
						(size 1.27 1.27)
						(thickness 0.15)
					)
					(justify left bottom)
					(hide yes)
				)
			)
			(property "Manufacturer" "Murata"
				(at 20.32 -20.32 0)
				(effects
					(font
						(size 1.27 1.27)
						(thickness 0.15)
					)
					(justify left bottom)
					(hide yes)
				)
			)
			(property "License" "Apache-2.0"
				(at 20.32 -22.86 0)
				(effects
					(font
						(size 1.27 1.27)
						(thickness 0.15)
					)
					(justify left bottom)
					(hide yes)
				)
			)
			(property "Author" "Antmicro"
				(at 20.32 -25.4 0)
				(effects
					(font
						(size 1.27 1.27)
						(thickness 0.15)
					)
					(justify left bottom)
					(hide yes)
				)
			)
			(property "Val" "100n"
				(at 20.32 -7.62 0)
				(effects
					(font
						(size 1.27 1.27)
						(thickness 0.15)
					)
					(justify left bottom)
				)
			)
			(property "Voltage" "50V"
				(at 20.32 -27.94 0)
				(effects
					(font
						(size 1.27 1.27)
					)
					(justify left bottom)
					(hide yes)
				)
			)
			(property "Dielectric" "X5R"
				(at 20.32 -30.48 0)
				(effects
					(font
						(size 1.27 1.27)
					)
					(justify left bottom)
					(hide yes)
				)
			)
			(property "ki_keywords" "0402, SMT, CAPACITOR, PASSIVE, CERAMIC, MLCC"
				(at 0 0 0)
				(effects
					(font
						(size 1.27 1.27)
					)
					(hide yes)
				)
			)
			(symbol "C_100n_0402_5_0_1"
				(polyline
					(pts
						(xy 2.032 -1.524) (xy 2.032 1.524)
					)
					(stroke
						(width 0.3048)
						(type default)
					)
					(fill
						(type none)
					)
				)
				(polyline
					(pts
						(xy 3.048 -1.524) (xy 3.048 1.524)
					)
					(stroke
						(width 0.3302)
						(type default)
					)
					(fill
						(type none)
					)
				)
			)
			(symbol "C_100n_0402_5_1_1"
				(pin passive line
					(at 0 0 0)
					(length 2.032)
					(name "~"
						(effects
							(font
								(size 1.27 1.27)
							)
						)
					)
					(number "1"
						(effects
							(font
								(size 1.27 1.27)
							)
						)
					)
				)
				(pin passive line
					(at 5.08 0 180)
					(length 2.032)
					(name "~"
						(effects
							(font
								(size 1.27 1.27)
							)
						)
					)
					(number "2"
						(effects
							(font
								(size 1.27 1.27)
							)
						)
					)
				)
			)
		)
	(symbol "C_100n_0402_6"
			(pin_numbers hide)
			(pin_names hide)
			(exclude_from_sim no)
			(in_bom yes)
			(on_board yes)
			(property "Reference" "C"
				(at 20.32 -5.08 0)
				(effects
					(font
						(size 1.27 1.27)
						(thickness 0.15)
					)
					(justify left bottom)
				)
			)
			(property "Value" "C_100n_0402"
				(at 20.32 -10.16 0)
				(effects
					(font
						(size 1.27 1.27)
						(thickness 0.15)
					)
					(justify left bottom)
					(hide yes)
				)
			)
			(property "Footprint" "antmicro-footprints:C_0402_1005Metric"
				(at 20.32 -12.7 0)
				(effects
					(font
						(size 1.27 1.27)
						(thickness 0.15)
					)
					(justify left bottom)
					(hide yes)
				)
			)
			(property "Datasheet" "https://www.murata.com/products/productdetail?partno=GRM155R61H104KE14%23"
				(at 20.32 -15.24 0)
				(effects
					(font
						(size 1.27 1.27)
						(thickness 0.15)
					)
					(justify left bottom)
					(hide yes)
				)
			)
			(property "Description" "SMD Multilayer Ceramic Capacitor, 0.1 µF, 50 V, 0402 [1005 Metric], ± 10%, X5R, GRM Series"
				(at 0 0 0)
				(effects
					(font
						(size 1.27 1.27)
					)
					(hide yes)
				)
			)
			(property "MPN" "GRM155R61H104KE14D"
				(at 20.32 -17.78 0)
				(effects
					(font
						(size 1.27 1.27)
						(thickness 0.15)
					)
					(justify left bottom)
					(hide yes)
				)
			)
			(property "Manufacturer" "Murata"
				(at 20.32 -20.32 0)
				(effects
					(font
						(size 1.27 1.27)
						(thickness 0.15)
					)
					(justify left bottom)
					(hide yes)
				)
			)
			(property "License" "Apache-2.0"
				(at 20.32 -22.86 0)
				(effects
					(font
						(size 1.27 1.27)
						(thickness 0.15)
					)
					(justify left bottom)
					(hide yes)
				)
			)
			(property "Author" "Antmicro"
				(at 20.32 -25.4 0)
				(effects
					(font
						(size 1.27 1.27)
						(thickness 0.15)
					)
					(justify left bottom)
					(hide yes)
				)
			)
			(property "Val" "100n"
				(at 20.32 -7.62 0)
				(effects
					(font
						(size 1.27 1.27)
						(thickness 0.15)
					)
					(justify left bottom)
				)
			)
			(property "Voltage" "50V"
				(at 20.32 -27.94 0)
				(effects
					(font
						(size 1.27 1.27)
					)
					(justify left bottom)
					(hide yes)
				)
			)
			(property "Dielectric" "X5R"
				(at 20.32 -30.48 0)
				(effects
					(font
						(size 1.27 1.27)
					)
					(justify left bottom)
					(hide yes)
				)
			)
			(property "ki_keywords" "0402, SMT, CAPACITOR, PASSIVE, CERAMIC, MLCC"
				(at 0 0 0)
				(effects
					(font
						(size 1.27 1.27)
					)
					(hide yes)
				)
			)
			(symbol "C_100n_0402_6_0_1"
				(polyline
					(pts
						(xy 2.032 -1.524) (xy 2.032 1.524)
					)
					(stroke
						(width 0.3048)
						(type default)
					)
					(fill
						(type none)
					)
				)
				(polyline
					(pts
						(xy 3.048 -1.524) (xy 3.048 1.524)
					)
					(stroke
						(width 0.3302)
						(type default)
					)
					(fill
						(type none)
					)
				)
			)
			(symbol "C_100n_0402_6_1_1"
				(pin passive line
					(at 0 0 0)
					(length 2.032)
					(name "~"
						(effects
							(font
								(size 1.27 1.27)
							)
						)
					)
					(number "1"
						(effects
							(font
								(size 1.27 1.27)
							)
						)
					)
				)
				(pin passive line
					(at 5.08 0 180)
					(length 2.032)
					(name "~"
						(effects
							(font
								(size 1.27 1.27)
							)
						)
					)
					(number "2"
						(effects
							(font
								(size 1.27 1.27)
							)
						)
					)
				)
			)
		)
	(symbol "C_100n_0402_7"
			(pin_numbers hide)
			(pin_names hide)
			(exclude_from_sim no)
			(in_bom yes)
			(on_board yes)
			(property "Reference" "C"
				(at 20.32 -5.08 0)
				(effects
					(font
						(size 1.27 1.27)
						(thickness 0.15)
					)
					(justify left bottom)
				)
			)
			(property "Value" "C_100n_0402"
				(at 20.32 -10.16 0)
				(effects
					(font
						(size 1.27 1.27)
						(thickness 0.15)
					)
					(justify left bottom)
					(hide yes)
				)
			)
			(property "Footprint" "antmicro-footprints:C_0402_1005Metric"
				(at 20.32 -12.7 0)
				(effects
					(font
						(size 1.27 1.27)
						(thickness 0.15)
					)
					(justify left bottom)
					(hide yes)
				)
			)
			(property "Datasheet" "https://www.murata.com/products/productdetail?partno=GRM155R61H104KE14%23"
				(at 20.32 -15.24 0)
				(effects
					(font
						(size 1.27 1.27)
						(thickness 0.15)
					)
					(justify left bottom)
					(hide yes)
				)
			)
			(property "Description" "SMD Multilayer Ceramic Capacitor, 0.1 µF, 50 V, 0402 [1005 Metric], ± 10%, X5R, GRM Series"
				(at 0 0 0)
				(effects
					(font
						(size 1.27 1.27)
					)
					(hide yes)
				)
			)
			(property "MPN" "GRM155R61H104KE14D"
				(at 20.32 -17.78 0)
				(effects
					(font
						(size 1.27 1.27)
						(thickness 0.15)
					)
					(justify left bottom)
					(hide yes)
				)
			)
			(property "Manufacturer" "Murata"
				(at 20.32 -20.32 0)
				(effects
					(font
						(size 1.27 1.27)
						(thickness 0.15)
					)
					(justify left bottom)
					(hide yes)
				)
			)
			(property "License" "Apache-2.0"
				(at 20.32 -22.86 0)
				(effects
					(font
						(size 1.27 1.27)
						(thickness 0.15)
					)
					(justify left bottom)
					(hide yes)
				)
			)
			(property "Author" "Antmicro"
				(at 20.32 -25.4 0)
				(effects
					(font
						(size 1.27 1.27)
						(thickness 0.15)
					)
					(justify left bottom)
					(hide yes)
				)
			)
			(property "Val" "100n"
				(at 20.32 -7.62 0)
				(effects
					(font
						(size 1.27 1.27)
						(thickness 0.15)
					)
					(justify left bottom)
				)
			)
			(property "Voltage" "50V"
				(at 20.32 -27.94 0)
				(effects
					(font
						(size 1.27 1.27)
					)
					(justify left bottom)
					(hide yes)
				)
			)
			(property "Dielectric" "X5R"
				(at 20.32 -30.48 0)
				(effects
					(font
						(size 1.27 1.27)
					)
					(justify left bottom)
					(hide yes)
				)
			)
			(property "ki_keywords" "0402, SMT, CAPACITOR, PASSIVE, CERAMIC, MLCC"
				(at 0 0 0)
				(effects
					(font
						(size 1.27 1.27)
					)
					(hide yes)
				)
			)
			(symbol "C_100n_0402_7_0_1"
				(polyline
					(pts
						(xy 2.032 -1.524) (xy 2.032 1.524)
					)
					(stroke
						(width 0.3048)
						(type default)
					)
					(fill
						(type none)
					)
				)
				(polyline
					(pts
						(xy 3.048 -1.524) (xy 3.048 1.524)
					)
					(stroke
						(width 0.3302)
						(type default)
					)
					(fill
						(type none)
					)
				)
			)
			(symbol "C_100n_0402_7_1_1"
				(pin passive line
					(at 0 0 0)
					(length 2.032)
					(name "~"
						(effects
							(font
								(size 1.27 1.27)
							)
						)
					)
					(number "1"
						(effects
							(font
								(size 1.27 1.27)
							)
						)
					)
				)
				(pin passive line
					(at 5.08 0 180)
					(length 2.032)
					(name "~"
						(effects
							(font
								(size 1.27 1.27)
							)
						)
					)
					(number "2"
						(effects
							(font
								(size 1.27 1.27)
							)
						)
					)
				)
			)
		)
	(symbol "C_100n_0402_8"
			(pin_numbers hide)
			(pin_names hide)
			(exclude_from_sim no)
			(in_bom yes)
			(on_board yes)
			(property "Reference" "C"
				(at 20.32 -5.08 0)
				(effects
					(font
						(size 1.27 1.27)
						(thickness 0.15)
					)
					(justify left bottom)
				)
			)
			(property "Value" "C_100n_0402"
				(at 20.32 -10.16 0)
				(effects
					(font
						(size 1.27 1.27)
						(thickness 0.15)
					)
					(justify left bottom)
					(hide yes)
				)
			)
			(property "Footprint" "antmicro-footprints:C_0402_1005Metric"
				(at 20.32 -12.7 0)
				(effects
					(font
						(size 1.27 1.27)
						(thickness 0.15)
					)
					(justify left bottom)
					(hide yes)
				)
			)
			(property "Datasheet" "https://www.murata.com/products/productdetail?partno=GRM155R61H104KE14%23"
				(at 20.32 -15.24 0)
				(effects
					(font
						(size 1.27 1.27)
						(thickness 0.15)
					)
					(justify left bottom)
					(hide yes)
				)
			)
			(property "Description" "SMD Multilayer Ceramic Capacitor, 0.1 µF, 50 V, 0402 [1005 Metric], ± 10%, X5R, GRM Series"
				(at 0 0 0)
				(effects
					(font
						(size 1.27 1.27)
					)
					(hide yes)
				)
			)
			(property "MPN" "GRM155R61H104KE14D"
				(at 20.32 -17.78 0)
				(effects
					(font
						(size 1.27 1.27)
						(thickness 0.15)
					)
					(justify left bottom)
					(hide yes)
				)
			)
			(property "Manufacturer" "Murata"
				(at 20.32 -20.32 0)
				(effects
					(font
						(size 1.27 1.27)
						(thickness 0.15)
					)
					(justify left bottom)
					(hide yes)
				)
			)
			(property "License" "Apache-2.0"
				(at 20.32 -22.86 0)
				(effects
					(font
						(size 1.27 1.27)
						(thickness 0.15)
					)
					(justify left bottom)
					(hide yes)
				)
			)
			(property "Author" "Antmicro"
				(at 20.32 -25.4 0)
				(effects
					(font
						(size 1.27 1.27)
						(thickness 0.15)
					)
					(justify left bottom)
					(hide yes)
				)
			)
			(property "Val" "100n"
				(at 20.32 -7.62 0)
				(effects
					(font
						(size 1.27 1.27)
						(thickness 0.15)
					)
					(justify left bottom)
				)
			)
			(property "Voltage" "50V"
				(at 20.32 -27.94 0)
				(effects
					(font
						(size 1.27 1.27)
					)
					(justify left bottom)
					(hide yes)
				)
			)
			(property "Dielectric" "X5R"
				(at 20.32 -30.48 0)
				(effects
					(font
						(size 1.27 1.27)
					)
					(justify left bottom)
					(hide yes)
				)
			)
			(property "ki_keywords" "0402, SMT, CAPACITOR, PASSIVE, CERAMIC, MLCC"
				(at 0 0 0)
				(effects
					(font
						(size 1.27 1.27)
					)
					(hide yes)
				)
			)
			(symbol "C_100n_0402_8_0_1"
				(polyline
					(pts
						(xy 2.032 -1.524) (xy 2.032 1.524)
					)
					(stroke
						(width 0.3048)
						(type default)
					)
					(fill
						(type none)
					)
				)
				(polyline
					(pts
						(xy 3.048 -1.524) (xy 3.048 1.524)
					)
					(stroke
						(width 0.3302)
						(type default)
					)
					(fill
						(type none)
					)
				)
			)
			(symbol "C_100n_0402_8_1_1"
				(pin passive line
					(at 0 0 0)
					(length 2.032)
					(name "~"
						(effects
							(font
								(size 1.27 1.27)
							)
						)
					)
					(number "1"
						(effects
							(font
								(size 1.27 1.27)
							)
						)
					)
				)
				(pin passive line
					(at 5.08 0 180)
					(length 2.032)
					(name "~"
						(effects
							(font
								(size 1.27 1.27)
							)
						)
					)
					(number "2"
						(effects
							(font
								(size 1.27 1.27)
							)
						)
					)
				)
			)
		)
	(symbol "C_10u_0603_1"
			(pin_numbers hide)
			(pin_names hide)
			(exclude_from_sim no)
			(in_bom yes)
			(on_board yes)
			(property "Reference" "C"
				(at 20.32 -5.08 0)
				(effects
					(font
						(size 1.27 1.27)
						(thickness 0.15)
					)
					(justify left bottom)
				)
			)
			(property "Value" "C_10u_0603"
				(at 20.32 -10.16 0)
				(effects
					(font
						(size 1.27 1.27)
						(thickness 0.15)
					)
					(justify left bottom)
					(hide yes)
				)
			)
			(property "Footprint" "antmicro-footprints:C_0603_1608Metric"
				(at 20.32 -12.7 0)
				(effects
					(font
						(size 1.27 1.27)
						(thickness 0.15)
					)
					(justify left bottom)
					(hide yes)
				)
			)
			(property "Datasheet" "https://www.murata.com/products/productdetail?partno=GRM188R61A106KE69%23"
				(at 20.32 -15.24 0)
				(effects
					(font
						(size 1.27 1.27)
						(thickness 0.15)
					)
					(justify left bottom)
					(hide yes)
				)
			)
			(property "Description" "SMD Multilayer Ceramic Capacitor, 10 µF, 10 V, 0603 [1608 Metric], ± 10%, X5R, GRM Series"
				(at 0 0 0)
				(effects
					(font
						(size 1.27 1.27)
					)
					(hide yes)
				)
			)
			(property "MPN" "GRM188R61A106KE69D"
				(at 20.32 -17.78 0)
				(effects
					(font
						(size 1.27 1.27)
						(thickness 0.15)
					)
					(justify left bottom)
					(hide yes)
				)
			)
			(property "Manufacturer" "Murata"
				(at 20.32 -20.32 0)
				(effects
					(font
						(size 1.27 1.27)
						(thickness 0.15)
					)
					(justify left bottom)
					(hide yes)
				)
			)
			(property "License" "Apache-2.0"
				(at 20.32 -22.86 0)
				(effects
					(font
						(size 1.27 1.27)
						(thickness 0.15)
					)
					(justify left bottom)
					(hide yes)
				)
			)
			(property "Author" "Antmicro"
				(at 20.32 -25.4 0)
				(effects
					(font
						(size 1.27 1.27)
						(thickness 0.15)
					)
					(justify left bottom)
					(hide yes)
				)
			)
			(property "Val" "10u"
				(at 20.32 -7.62 0)
				(effects
					(font
						(size 1.27 1.27)
						(thickness 0.15)
					)
					(justify left bottom)
				)
			)
			(property "Voltage" ""
				(at 20.32 -27.94 0)
				(effects
					(font
						(size 1.27 1.27)
					)
					(justify left bottom)
					(hide yes)
				)
			)
			(property "Dielectric" "template_dielectric"
				(at 20.32 -30.48 0)
				(effects
					(font
						(size 1.27 1.27)
					)
					(justify left bottom)
					(hide yes)
				)
			)
			(property "ki_keywords" "0603, SMT, CAPACITOR, PASSIVE, CERAMIC, MLCC"
				(at 0 0 0)
				(effects
					(font
						(size 1.27 1.27)
					)
					(hide yes)
				)
			)
			(symbol "C_10u_0603_1_0_1"
				(polyline
					(pts
						(xy 2.032 -1.524) (xy 2.032 1.524)
					)
					(stroke
						(width 0.3048)
						(type default)
					)
					(fill
						(type none)
					)
				)
				(polyline
					(pts
						(xy 3.048 -1.524) (xy 3.048 1.524)
					)
					(stroke
						(width 0.3302)
						(type default)
					)
					(fill
						(type none)
					)
				)
			)
			(symbol "C_10u_0603_1_1_1"
				(pin passive line
					(at 0 0 0)
					(length 2.032)
					(name "~"
						(effects
							(font
								(size 1.27 1.27)
							)
						)
					)
					(number "1"
						(effects
							(font
								(size 1.27 1.27)
							)
						)
					)
				)
				(pin passive line
					(at 5.08 0 180)
					(length 2.032)
					(name "~"
						(effects
							(font
								(size 1.27 1.27)
							)
						)
					)
					(number "2"
						(effects
							(font
								(size 1.27 1.27)
							)
						)
					)
				)
			)
		)
	(symbol "C_10u_0603_2"
			(pin_numbers hide)
			(pin_names hide)
			(exclude_from_sim no)
			(in_bom yes)
			(on_board yes)
			(property "Reference" "C"
				(at 20.32 -5.08 0)
				(effects
					(font
						(size 1.27 1.27)
						(thickness 0.15)
					)
					(justify left bottom)
				)
			)
			(property "Value" "C_10u_0603"
				(at 20.32 -10.16 0)
				(effects
					(font
						(size 1.27 1.27)
						(thickness 0.15)
					)
					(justify left bottom)
					(hide yes)
				)
			)
			(property "Footprint" "antmicro-footprints:C_0603_1608Metric"
				(at 20.32 -12.7 0)
				(effects
					(font
						(size 1.27 1.27)
						(thickness 0.15)
					)
					(justify left bottom)
					(hide yes)
				)
			)
			(property "Datasheet" "https://www.murata.com/products/productdetail?partno=GRM188R61A106KE69%23"
				(at 20.32 -15.24 0)
				(effects
					(font
						(size 1.27 1.27)
						(thickness 0.15)
					)
					(justify left bottom)
					(hide yes)
				)
			)
			(property "Description" "SMD Multilayer Ceramic Capacitor, 10 µF, 10 V, 0603 [1608 Metric], ± 10%, X5R, GRM Series"
				(at 0 0 0)
				(effects
					(font
						(size 1.27 1.27)
					)
					(hide yes)
				)
			)
			(property "MPN" "GRM188R61A106KE69D"
				(at 20.32 -17.78 0)
				(effects
					(font
						(size 1.27 1.27)
						(thickness 0.15)
					)
					(justify left bottom)
					(hide yes)
				)
			)
			(property "Manufacturer" "Murata"
				(at 20.32 -20.32 0)
				(effects
					(font
						(size 1.27 1.27)
						(thickness 0.15)
					)
					(justify left bottom)
					(hide yes)
				)
			)
			(property "License" "Apache-2.0"
				(at 20.32 -22.86 0)
				(effects
					(font
						(size 1.27 1.27)
						(thickness 0.15)
					)
					(justify left bottom)
					(hide yes)
				)
			)
			(property "Author" "Antmicro"
				(at 20.32 -25.4 0)
				(effects
					(font
						(size 1.27 1.27)
						(thickness 0.15)
					)
					(justify left bottom)
					(hide yes)
				)
			)
			(property "Val" "10u"
				(at 20.32 -7.62 0)
				(effects
					(font
						(size 1.27 1.27)
						(thickness 0.15)
					)
					(justify left bottom)
				)
			)
			(property "Voltage" ""
				(at 20.32 -27.94 0)
				(effects
					(font
						(size 1.27 1.27)
					)
					(justify left bottom)
					(hide yes)
				)
			)
			(property "Dielectric" "template_dielectric"
				(at 20.32 -30.48 0)
				(effects
					(font
						(size 1.27 1.27)
					)
					(justify left bottom)
					(hide yes)
				)
			)
			(property "ki_keywords" "0603, SMT, CAPACITOR, PASSIVE, CERAMIC, MLCC"
				(at 0 0 0)
				(effects
					(font
						(size 1.27 1.27)
					)
					(hide yes)
				)
			)
			(symbol "C_10u_0603_2_0_1"
				(polyline
					(pts
						(xy 2.032 -1.524) (xy 2.032 1.524)
					)
					(stroke
						(width 0.3048)
						(type default)
					)
					(fill
						(type none)
					)
				)
				(polyline
					(pts
						(xy 3.048 -1.524) (xy 3.048 1.524)
					)
					(stroke
						(width 0.3302)
						(type default)
					)
					(fill
						(type none)
					)
				)
			)
			(symbol "C_10u_0603_2_1_1"
				(pin passive line
					(at 0 0 0)
					(length 2.032)
					(name "~"
						(effects
							(font
								(size 1.27 1.27)
							)
						)
					)
					(number "1"
						(effects
							(font
								(size 1.27 1.27)
							)
						)
					)
				)
				(pin passive line
					(at 5.08 0 180)
					(length 2.032)
					(name "~"
						(effects
							(font
								(size 1.27 1.27)
							)
						)
					)
					(number "2"
						(effects
							(font
								(size 1.27 1.27)
							)
						)
					)
				)
			)
		)
	(symbol "C_10u_0603_3"
			(pin_numbers hide)
			(pin_names hide)
			(exclude_from_sim no)
			(in_bom yes)
			(on_board yes)
			(property "Reference" "C"
				(at 20.32 -5.08 0)
				(effects
					(font
						(size 1.27 1.27)
						(thickness 0.15)
					)
					(justify left bottom)
				)
			)
			(property "Value" "C_10u_0603"
				(at 20.32 -10.16 0)
				(effects
					(font
						(size 1.27 1.27)
						(thickness 0.15)
					)
					(justify left bottom)
					(hide yes)
				)
			)
			(property "Footprint" "antmicro-footprints:C_0603_1608Metric"
				(at 20.32 -12.7 0)
				(effects
					(font
						(size 1.27 1.27)
						(thickness 0.15)
					)
					(justify left bottom)
					(hide yes)
				)
			)
			(property "Datasheet" "https://www.murata.com/products/productdetail?partno=GRM188R61A106KE69%23"
				(at 20.32 -15.24 0)
				(effects
					(font
						(size 1.27 1.27)
						(thickness 0.15)
					)
					(justify left bottom)
					(hide yes)
				)
			)
			(property "Description" "SMD Multilayer Ceramic Capacitor, 10 µF, 10 V, 0603 [1608 Metric], ± 10%, X5R, GRM Series"
				(at 0 0 0)
				(effects
					(font
						(size 1.27 1.27)
					)
					(hide yes)
				)
			)
			(property "MPN" "GRM188R61A106KE69D"
				(at 20.32 -17.78 0)
				(effects
					(font
						(size 1.27 1.27)
						(thickness 0.15)
					)
					(justify left bottom)
					(hide yes)
				)
			)
			(property "Manufacturer" "Murata"
				(at 20.32 -20.32 0)
				(effects
					(font
						(size 1.27 1.27)
						(thickness 0.15)
					)
					(justify left bottom)
					(hide yes)
				)
			)
			(property "License" "Apache-2.0"
				(at 20.32 -22.86 0)
				(effects
					(font
						(size 1.27 1.27)
						(thickness 0.15)
					)
					(justify left bottom)
					(hide yes)
				)
			)
			(property "Author" "Antmicro"
				(at 20.32 -25.4 0)
				(effects
					(font
						(size 1.27 1.27)
						(thickness 0.15)
					)
					(justify left bottom)
					(hide yes)
				)
			)
			(property "Val" "10u"
				(at 20.32 -7.62 0)
				(effects
					(font
						(size 1.27 1.27)
						(thickness 0.15)
					)
					(justify left bottom)
				)
			)
			(property "Voltage" ""
				(at 20.32 -27.94 0)
				(effects
					(font
						(size 1.27 1.27)
					)
					(justify left bottom)
					(hide yes)
				)
			)
			(property "Dielectric" "template_dielectric"
				(at 20.32 -30.48 0)
				(effects
					(font
						(size 1.27 1.27)
					)
					(justify left bottom)
					(hide yes)
				)
			)
			(property "ki_keywords" "0603, SMT, CAPACITOR, PASSIVE, CERAMIC, MLCC"
				(at 0 0 0)
				(effects
					(font
						(size 1.27 1.27)
					)
					(hide yes)
				)
			)
			(symbol "C_10u_0603_3_0_1"
				(polyline
					(pts
						(xy 2.032 -1.524) (xy 2.032 1.524)
					)
					(stroke
						(width 0.3048)
						(type default)
					)
					(fill
						(type none)
					)
				)
				(polyline
					(pts
						(xy 3.048 -1.524) (xy 3.048 1.524)
					)
					(stroke
						(width 0.3302)
						(type default)
					)
					(fill
						(type none)
					)
				)
			)
			(symbol "C_10u_0603_3_1_1"
				(pin passive line
					(at 0 0 0)
					(length 2.032)
					(name "~"
						(effects
							(font
								(size 1.27 1.27)
							)
						)
					)
					(number "1"
						(effects
							(font
								(size 1.27 1.27)
							)
						)
					)
				)
				(pin passive line
					(at 5.08 0 180)
					(length 2.032)
					(name "~"
						(effects
							(font
								(size 1.27 1.27)
							)
						)
					)
					(number "2"
						(effects
							(font
								(size 1.27 1.27)
							)
						)
					)
				)
			)
		)
	(symbol "C_10u_0603_4"
			(pin_numbers hide)
			(pin_names hide)
			(exclude_from_sim no)
			(in_bom yes)
			(on_board yes)
			(property "Reference" "C"
				(at 20.32 -5.08 0)
				(effects
					(font
						(size 1.27 1.27)
						(thickness 0.15)
					)
					(justify left bottom)
				)
			)
			(property "Value" "C_10u_0603"
				(at 20.32 -10.16 0)
				(effects
					(font
						(size 1.27 1.27)
						(thickness 0.15)
					)
					(justify left bottom)
					(hide yes)
				)
			)
			(property "Footprint" "antmicro-footprints:C_0603_1608Metric"
				(at 20.32 -12.7 0)
				(effects
					(font
						(size 1.27 1.27)
						(thickness 0.15)
					)
					(justify left bottom)
					(hide yes)
				)
			)
			(property "Datasheet" "https://www.murata.com/products/productdetail?partno=GRM188R61A106KE69%23"
				(at 20.32 -15.24 0)
				(effects
					(font
						(size 1.27 1.27)
						(thickness 0.15)
					)
					(justify left bottom)
					(hide yes)
				)
			)
			(property "Description" "SMD Multilayer Ceramic Capacitor, 10 µF, 10 V, 0603 [1608 Metric], ± 10%, X5R, GRM Series"
				(at 0 0 0)
				(effects
					(font
						(size 1.27 1.27)
					)
					(hide yes)
				)
			)
			(property "MPN" "GRM188R61A106KE69D"
				(at 20.32 -17.78 0)
				(effects
					(font
						(size 1.27 1.27)
						(thickness 0.15)
					)
					(justify left bottom)
					(hide yes)
				)
			)
			(property "Manufacturer" "Murata"
				(at 20.32 -20.32 0)
				(effects
					(font
						(size 1.27 1.27)
						(thickness 0.15)
					)
					(justify left bottom)
					(hide yes)
				)
			)
			(property "License" "Apache-2.0"
				(at 20.32 -22.86 0)
				(effects
					(font
						(size 1.27 1.27)
						(thickness 0.15)
					)
					(justify left bottom)
					(hide yes)
				)
			)
			(property "Author" "Antmicro"
				(at 20.32 -25.4 0)
				(effects
					(font
						(size 1.27 1.27)
						(thickness 0.15)
					)
					(justify left bottom)
					(hide yes)
				)
			)
			(property "Val" "10u"
				(at 20.32 -7.62 0)
				(effects
					(font
						(size 1.27 1.27)
						(thickness 0.15)
					)
					(justify left bottom)
				)
			)
			(property "Voltage" ""
				(at 20.32 -27.94 0)
				(effects
					(font
						(size 1.27 1.27)
					)
					(justify left bottom)
					(hide yes)
				)
			)
			(property "Dielectric" "template_dielectric"
				(at 20.32 -30.48 0)
				(effects
					(font
						(size 1.27 1.27)
					)
					(justify left bottom)
					(hide yes)
				)
			)
			(property "ki_keywords" "0603, SMT, CAPACITOR, PASSIVE, CERAMIC, MLCC"
				(at 0 0 0)
				(effects
					(font
						(size 1.27 1.27)
					)
					(hide yes)
				)
			)
			(symbol "C_10u_0603_4_0_1"
				(polyline
					(pts
						(xy 2.032 -1.524) (xy 2.032 1.524)
					)
					(stroke
						(width 0.3048)
						(type default)
					)
					(fill
						(type none)
					)
				)
				(polyline
					(pts
						(xy 3.048 -1.524) (xy 3.048 1.524)
					)
					(stroke
						(width 0.3302)
						(type default)
					)
					(fill
						(type none)
					)
				)
			)
			(symbol "C_10u_0603_4_1_1"
				(pin passive line
					(at 0 0 0)
					(length 2.032)
					(name "~"
						(effects
							(font
								(size 1.27 1.27)
							)
						)
					)
					(number "1"
						(effects
							(font
								(size 1.27 1.27)
							)
						)
					)
				)
				(pin passive line
					(at 5.08 0 180)
					(length 2.032)
					(name "~"
						(effects
							(font
								(size 1.27 1.27)
							)
						)
					)
					(number "2"
						(effects
							(font
								(size 1.27 1.27)
							)
						)
					)
				)
			)
		)
	(symbol "C_220n_0402_1"
			(pin_numbers hide)
			(pin_names hide)
			(exclude_from_sim no)
			(in_bom yes)
			(on_board yes)
			(property "Reference" "C"
				(at 20.32 -5.08 0)
				(effects
					(font
						(size 1.27 1.27)
						(thickness 0.15)
					)
					(justify left bottom)
				)
			)
			(property "Value" "C_220n_0402"
				(at 20.32 -10.16 0)
				(effects
					(font
						(size 1.27 1.27)
						(thickness 0.15)
					)
					(justify left bottom)
					(hide yes)
				)
			)
			(property "Footprint" "antmicro-footprints:C_0402_1005Metric"
				(at 20.32 -12.7 0)
				(effects
					(font
						(size 1.27 1.27)
						(thickness 0.15)
					)
					(justify left bottom)
					(hide yes)
				)
			)
			(property "Datasheet" "https://www.yageo.com/en/Chart/Download/pdf/CC0402KRX5R6BB224"
				(at 20.32 -15.24 0)
				(effects
					(font
						(size 1.27 1.27)
						(thickness 0.15)
					)
					(justify left bottom)
					(hide yes)
				)
			)
			(property "Description" "SMD Multilayer Ceramic Capacitor, 0.22 µF, 10 V, 0402 [1005 Metric], ± 10%, X5R, CC Series"
				(at 0 0 0)
				(effects
					(font
						(size 1.27 1.27)
					)
					(hide yes)
				)
			)
			(property "MPN" "CC0402KRX5R6BB224"
				(at 20.32 -17.78 0)
				(effects
					(font
						(size 1.27 1.27)
						(thickness 0.15)
					)
					(justify left bottom)
					(hide yes)
				)
			)
			(property "Manufacturer" "YAGEO"
				(at 20.32 -20.32 0)
				(effects
					(font
						(size 1.27 1.27)
						(thickness 0.15)
					)
					(justify left bottom)
					(hide yes)
				)
			)
			(property "License" "Apache-2.0"
				(at 20.32 -22.86 0)
				(effects
					(font
						(size 1.27 1.27)
						(thickness 0.15)
					)
					(justify left bottom)
					(hide yes)
				)
			)
			(property "Author" "Antmicro"
				(at 20.32 -25.4 0)
				(effects
					(font
						(size 1.27 1.27)
						(thickness 0.15)
					)
					(justify left bottom)
					(hide yes)
				)
			)
			(property "Val" "220n"
				(at 20.32 -7.62 0)
				(effects
					(font
						(size 1.27 1.27)
						(thickness 0.15)
					)
					(justify left bottom)
				)
			)
			(property "Voltage" ""
				(at 20.32 -27.94 0)
				(effects
					(font
						(size 1.27 1.27)
					)
					(justify left bottom)
					(hide yes)
				)
			)
			(property "Dielectric" ""
				(at 20.32 -30.48 0)
				(effects
					(font
						(size 1.27 1.27)
					)
					(justify left bottom)
					(hide yes)
				)
			)
			(property "ki_keywords" "0402, SMT, CAPACITOR, PASSIVE, MLCC, CERAMIC"
				(at 0 0 0)
				(effects
					(font
						(size 1.27 1.27)
					)
					(hide yes)
				)
			)
			(symbol "C_220n_0402_1_0_1"
				(polyline
					(pts
						(xy 2.032 -1.524) (xy 2.032 1.524)
					)
					(stroke
						(width 0.3048)
						(type default)
					)
					(fill
						(type none)
					)
				)
				(polyline
					(pts
						(xy 3.048 -1.524) (xy 3.048 1.524)
					)
					(stroke
						(width 0.3302)
						(type default)
					)
					(fill
						(type none)
					)
				)
			)
			(symbol "C_220n_0402_1_1_1"
				(pin passive line
					(at 0 0 0)
					(length 2.032)
					(name "~"
						(effects
							(font
								(size 1.27 1.27)
							)
						)
					)
					(number "1"
						(effects
							(font
								(size 1.27 1.27)
							)
						)
					)
				)
				(pin passive line
					(at 5.08 0 180)
					(length 2.032)
					(name "~"
						(effects
							(font
								(size 1.27 1.27)
							)
						)
					)
					(number "2"
						(effects
							(font
								(size 1.27 1.27)
							)
						)
					)
				)
			)
		)
	(symbol "C_220n_0402_2"
			(pin_numbers hide)
			(pin_names hide)
			(exclude_from_sim no)
			(in_bom yes)
			(on_board yes)
			(property "Reference" "C"
				(at 20.32 -5.08 0)
				(effects
					(font
						(size 1.27 1.27)
						(thickness 0.15)
					)
					(justify left bottom)
				)
			)
			(property "Value" "C_220n_0402"
				(at 20.32 -10.16 0)
				(effects
					(font
						(size 1.27 1.27)
						(thickness 0.15)
					)
					(justify left bottom)
					(hide yes)
				)
			)
			(property "Footprint" "antmicro-footprints:C_0402_1005Metric"
				(at 20.32 -12.7 0)
				(effects
					(font
						(size 1.27 1.27)
						(thickness 0.15)
					)
					(justify left bottom)
					(hide yes)
				)
			)
			(property "Datasheet" "https://www.yageo.com/en/Chart/Download/pdf/CC0402KRX5R6BB224"
				(at 20.32 -15.24 0)
				(effects
					(font
						(size 1.27 1.27)
						(thickness 0.15)
					)
					(justify left bottom)
					(hide yes)
				)
			)
			(property "Description" "SMD Multilayer Ceramic Capacitor, 0.22 µF, 10 V, 0402 [1005 Metric], ± 10%, X5R, CC Series"
				(at 0 0 0)
				(effects
					(font
						(size 1.27 1.27)
					)
					(hide yes)
				)
			)
			(property "MPN" "CC0402KRX5R6BB224"
				(at 20.32 -17.78 0)
				(effects
					(font
						(size 1.27 1.27)
						(thickness 0.15)
					)
					(justify left bottom)
					(hide yes)
				)
			)
			(property "Manufacturer" "YAGEO"
				(at 20.32 -20.32 0)
				(effects
					(font
						(size 1.27 1.27)
						(thickness 0.15)
					)
					(justify left bottom)
					(hide yes)
				)
			)
			(property "License" "Apache-2.0"
				(at 20.32 -22.86 0)
				(effects
					(font
						(size 1.27 1.27)
						(thickness 0.15)
					)
					(justify left bottom)
					(hide yes)
				)
			)
			(property "Author" "Antmicro"
				(at 20.32 -25.4 0)
				(effects
					(font
						(size 1.27 1.27)
						(thickness 0.15)
					)
					(justify left bottom)
					(hide yes)
				)
			)
			(property "Val" "220n"
				(at 20.32 -7.62 0)
				(effects
					(font
						(size 1.27 1.27)
						(thickness 0.15)
					)
					(justify left bottom)
				)
			)
			(property "Voltage" ""
				(at 20.32 -27.94 0)
				(effects
					(font
						(size 1.27 1.27)
					)
					(justify left bottom)
					(hide yes)
				)
			)
			(property "Dielectric" ""
				(at 20.32 -30.48 0)
				(effects
					(font
						(size 1.27 1.27)
					)
					(justify left bottom)
					(hide yes)
				)
			)
			(property "ki_keywords" "0402, SMT, CAPACITOR, PASSIVE, MLCC, CERAMIC"
				(at 0 0 0)
				(effects
					(font
						(size 1.27 1.27)
					)
					(hide yes)
				)
			)
			(symbol "C_220n_0402_2_0_1"
				(polyline
					(pts
						(xy 2.032 -1.524) (xy 2.032 1.524)
					)
					(stroke
						(width 0.3048)
						(type default)
					)
					(fill
						(type none)
					)
				)
				(polyline
					(pts
						(xy 3.048 -1.524) (xy 3.048 1.524)
					)
					(stroke
						(width 0.3302)
						(type default)
					)
					(fill
						(type none)
					)
				)
			)
			(symbol "C_220n_0402_2_1_1"
				(pin passive line
					(at 0 0 0)
					(length 2.032)
					(name "~"
						(effects
							(font
								(size 1.27 1.27)
							)
						)
					)
					(number "1"
						(effects
							(font
								(size 1.27 1.27)
							)
						)
					)
				)
				(pin passive line
					(at 5.08 0 180)
					(length 2.032)
					(name "~"
						(effects
							(font
								(size 1.27 1.27)
							)
						)
					)
					(number "2"
						(effects
							(font
								(size 1.27 1.27)
							)
						)
					)
				)
			)
		)
	(symbol "C_220n_0402_3"
			(pin_numbers hide)
			(pin_names hide)
			(exclude_from_sim no)
			(in_bom yes)
			(on_board yes)
			(property "Reference" "C"
				(at 20.32 -5.08 0)
				(effects
					(font
						(size 1.27 1.27)
						(thickness 0.15)
					)
					(justify left bottom)
				)
			)
			(property "Value" "C_220n_0402"
				(at 20.32 -10.16 0)
				(effects
					(font
						(size 1.27 1.27)
						(thickness 0.15)
					)
					(justify left bottom)
					(hide yes)
				)
			)
			(property "Footprint" "antmicro-footprints:C_0402_1005Metric"
				(at 20.32 -12.7 0)
				(effects
					(font
						(size 1.27 1.27)
						(thickness 0.15)
					)
					(justify left bottom)
					(hide yes)
				)
			)
			(property "Datasheet" "https://www.yageo.com/en/Chart/Download/pdf/CC0402KRX5R6BB224"
				(at 20.32 -15.24 0)
				(effects
					(font
						(size 1.27 1.27)
						(thickness 0.15)
					)
					(justify left bottom)
					(hide yes)
				)
			)
			(property "Description" "SMD Multilayer Ceramic Capacitor, 0.22 µF, 10 V, 0402 [1005 Metric], ± 10%, X5R, CC Series"
				(at 0 0 0)
				(effects
					(font
						(size 1.27 1.27)
					)
					(hide yes)
				)
			)
			(property "MPN" "CC0402KRX5R6BB224"
				(at 20.32 -17.78 0)
				(effects
					(font
						(size 1.27 1.27)
						(thickness 0.15)
					)
					(justify left bottom)
					(hide yes)
				)
			)
			(property "Manufacturer" "YAGEO"
				(at 20.32 -20.32 0)
				(effects
					(font
						(size 1.27 1.27)
						(thickness 0.15)
					)
					(justify left bottom)
					(hide yes)
				)
			)
			(property "License" "Apache-2.0"
				(at 20.32 -22.86 0)
				(effects
					(font
						(size 1.27 1.27)
						(thickness 0.15)
					)
					(justify left bottom)
					(hide yes)
				)
			)
			(property "Author" "Antmicro"
				(at 20.32 -25.4 0)
				(effects
					(font
						(size 1.27 1.27)
						(thickness 0.15)
					)
					(justify left bottom)
					(hide yes)
				)
			)
			(property "Val" "220n"
				(at 20.32 -7.62 0)
				(effects
					(font
						(size 1.27 1.27)
						(thickness 0.15)
					)
					(justify left bottom)
				)
			)
			(property "Voltage" ""
				(at 20.32 -27.94 0)
				(effects
					(font
						(size 1.27 1.27)
					)
					(justify left bottom)
					(hide yes)
				)
			)
			(property "Dielectric" ""
				(at 20.32 -30.48 0)
				(effects
					(font
						(size 1.27 1.27)
					)
					(justify left bottom)
					(hide yes)
				)
			)
			(property "ki_keywords" "0402, SMT, CAPACITOR, PASSIVE, MLCC, CERAMIC"
				(at 0 0 0)
				(effects
					(font
						(size 1.27 1.27)
					)
					(hide yes)
				)
			)
			(symbol "C_220n_0402_3_0_1"
				(polyline
					(pts
						(xy 2.032 -1.524) (xy 2.032 1.524)
					)
					(stroke
						(width 0.3048)
						(type default)
					)
					(fill
						(type none)
					)
				)
				(polyline
					(pts
						(xy 3.048 -1.524) (xy 3.048 1.524)
					)
					(stroke
						(width 0.3302)
						(type default)
					)
					(fill
						(type none)
					)
				)
			)
			(symbol "C_220n_0402_3_1_1"
				(pin passive line
					(at 0 0 0)
					(length 2.032)
					(name "~"
						(effects
							(font
								(size 1.27 1.27)
							)
						)
					)
					(number "1"
						(effects
							(font
								(size 1.27 1.27)
							)
						)
					)
				)
				(pin passive line
					(at 5.08 0 180)
					(length 2.032)
					(name "~"
						(effects
							(font
								(size 1.27 1.27)
							)
						)
					)
					(number "2"
						(effects
							(font
								(size 1.27 1.27)
							)
						)
					)
				)
			)
		)
	(symbol "C_220n_0402_4"
			(pin_numbers hide)
			(pin_names hide)
			(exclude_from_sim no)
			(in_bom yes)
			(on_board yes)
			(property "Reference" "C"
				(at 20.32 -5.08 0)
				(effects
					(font
						(size 1.27 1.27)
						(thickness 0.15)
					)
					(justify left bottom)
				)
			)
			(property "Value" "C_220n_0402"
				(at 20.32 -10.16 0)
				(effects
					(font
						(size 1.27 1.27)
						(thickness 0.15)
					)
					(justify left bottom)
					(hide yes)
				)
			)
			(property "Footprint" "antmicro-footprints:C_0402_1005Metric"
				(at 20.32 -12.7 0)
				(effects
					(font
						(size 1.27 1.27)
						(thickness 0.15)
					)
					(justify left bottom)
					(hide yes)
				)
			)
			(property "Datasheet" "https://www.yageo.com/en/Chart/Download/pdf/CC0402KRX5R6BB224"
				(at 20.32 -15.24 0)
				(effects
					(font
						(size 1.27 1.27)
						(thickness 0.15)
					)
					(justify left bottom)
					(hide yes)
				)
			)
			(property "Description" "SMD Multilayer Ceramic Capacitor, 0.22 µF, 10 V, 0402 [1005 Metric], ± 10%, X5R, CC Series"
				(at 0 0 0)
				(effects
					(font
						(size 1.27 1.27)
					)
					(hide yes)
				)
			)
			(property "MPN" "CC0402KRX5R6BB224"
				(at 20.32 -17.78 0)
				(effects
					(font
						(size 1.27 1.27)
						(thickness 0.15)
					)
					(justify left bottom)
					(hide yes)
				)
			)
			(property "Manufacturer" "YAGEO"
				(at 20.32 -20.32 0)
				(effects
					(font
						(size 1.27 1.27)
						(thickness 0.15)
					)
					(justify left bottom)
					(hide yes)
				)
			)
			(property "License" "Apache-2.0"
				(at 20.32 -22.86 0)
				(effects
					(font
						(size 1.27 1.27)
						(thickness 0.15)
					)
					(justify left bottom)
					(hide yes)
				)
			)
			(property "Author" "Antmicro"
				(at 20.32 -25.4 0)
				(effects
					(font
						(size 1.27 1.27)
						(thickness 0.15)
					)
					(justify left bottom)
					(hide yes)
				)
			)
			(property "Val" "220n"
				(at 20.32 -7.62 0)
				(effects
					(font
						(size 1.27 1.27)
						(thickness 0.15)
					)
					(justify left bottom)
				)
			)
			(property "Voltage" ""
				(at 20.32 -27.94 0)
				(effects
					(font
						(size 1.27 1.27)
					)
					(justify left bottom)
					(hide yes)
				)
			)
			(property "Dielectric" ""
				(at 20.32 -30.48 0)
				(effects
					(font
						(size 1.27 1.27)
					)
					(justify left bottom)
					(hide yes)
				)
			)
			(property "ki_keywords" "0402, SMT, CAPACITOR, PASSIVE, MLCC, CERAMIC"
				(at 0 0 0)
				(effects
					(font
						(size 1.27 1.27)
					)
					(hide yes)
				)
			)
			(symbol "C_220n_0402_4_0_1"
				(polyline
					(pts
						(xy 2.032 -1.524) (xy 2.032 1.524)
					)
					(stroke
						(width 0.3048)
						(type default)
					)
					(fill
						(type none)
					)
				)
				(polyline
					(pts
						(xy 3.048 -1.524) (xy 3.048 1.524)
					)
					(stroke
						(width 0.3302)
						(type default)
					)
					(fill
						(type none)
					)
				)
			)
			(symbol "C_220n_0402_4_1_1"
				(pin passive line
					(at 0 0 0)
					(length 2.032)
					(name "~"
						(effects
							(font
								(size 1.27 1.27)
							)
						)
					)
					(number "1"
						(effects
							(font
								(size 1.27 1.27)
							)
						)
					)
				)
				(pin passive line
					(at 5.08 0 180)
					(length 2.032)
					(name "~"
						(effects
							(font
								(size 1.27 1.27)
							)
						)
					)
					(number "2"
						(effects
							(font
								(size 1.27 1.27)
							)
						)
					)
				)
			)
		)
	(symbol "C_220n_0402_5"
			(pin_numbers hide)
			(pin_names hide)
			(exclude_from_sim no)
			(in_bom yes)
			(on_board yes)
			(property "Reference" "C"
				(at 20.32 -5.08 0)
				(effects
					(font
						(size 1.27 1.27)
						(thickness 0.15)
					)
					(justify left bottom)
				)
			)
			(property "Value" "C_220n_0402"
				(at 20.32 -10.16 0)
				(effects
					(font
						(size 1.27 1.27)
						(thickness 0.15)
					)
					(justify left bottom)
					(hide yes)
				)
			)
			(property "Footprint" "antmicro-footprints:C_0402_1005Metric"
				(at 20.32 -12.7 0)
				(effects
					(font
						(size 1.27 1.27)
						(thickness 0.15)
					)
					(justify left bottom)
					(hide yes)
				)
			)
			(property "Datasheet" "https://www.yageo.com/en/Chart/Download/pdf/CC0402KRX5R6BB224"
				(at 20.32 -15.24 0)
				(effects
					(font
						(size 1.27 1.27)
						(thickness 0.15)
					)
					(justify left bottom)
					(hide yes)
				)
			)
			(property "Description" "SMD Multilayer Ceramic Capacitor, 0.22 µF, 10 V, 0402 [1005 Metric], ± 10%, X5R, CC Series"
				(at 0 0 0)
				(effects
					(font
						(size 1.27 1.27)
					)
					(hide yes)
				)
			)
			(property "MPN" "CC0402KRX5R6BB224"
				(at 20.32 -17.78 0)
				(effects
					(font
						(size 1.27 1.27)
						(thickness 0.15)
					)
					(justify left bottom)
					(hide yes)
				)
			)
			(property "Manufacturer" "YAGEO"
				(at 20.32 -20.32 0)
				(effects
					(font
						(size 1.27 1.27)
						(thickness 0.15)
					)
					(justify left bottom)
					(hide yes)
				)
			)
			(property "License" "Apache-2.0"
				(at 20.32 -22.86 0)
				(effects
					(font
						(size 1.27 1.27)
						(thickness 0.15)
					)
					(justify left bottom)
					(hide yes)
				)
			)
			(property "Author" "Antmicro"
				(at 20.32 -25.4 0)
				(effects
					(font
						(size 1.27 1.27)
						(thickness 0.15)
					)
					(justify left bottom)
					(hide yes)
				)
			)
			(property "Val" "220n"
				(at 20.32 -7.62 0)
				(effects
					(font
						(size 1.27 1.27)
						(thickness 0.15)
					)
					(justify left bottom)
				)
			)
			(property "Voltage" ""
				(at 20.32 -27.94 0)
				(effects
					(font
						(size 1.27 1.27)
					)
					(justify left bottom)
					(hide yes)
				)
			)
			(property "Dielectric" ""
				(at 20.32 -30.48 0)
				(effects
					(font
						(size 1.27 1.27)
					)
					(justify left bottom)
					(hide yes)
				)
			)
			(property "ki_keywords" "0402, SMT, CAPACITOR, PASSIVE, MLCC, CERAMIC"
				(at 0 0 0)
				(effects
					(font
						(size 1.27 1.27)
					)
					(hide yes)
				)
			)
			(symbol "C_220n_0402_5_0_1"
				(polyline
					(pts
						(xy 2.032 -1.524) (xy 2.032 1.524)
					)
					(stroke
						(width 0.3048)
						(type default)
					)
					(fill
						(type none)
					)
				)
				(polyline
					(pts
						(xy 3.048 -1.524) (xy 3.048 1.524)
					)
					(stroke
						(width 0.3302)
						(type default)
					)
					(fill
						(type none)
					)
				)
			)
			(symbol "C_220n_0402_5_1_1"
				(pin passive line
					(at 0 0 0)
					(length 2.032)
					(name "~"
						(effects
							(font
								(size 1.27 1.27)
							)
						)
					)
					(number "1"
						(effects
							(font
								(size 1.27 1.27)
							)
						)
					)
				)
				(pin passive line
					(at 5.08 0 180)
					(length 2.032)
					(name "~"
						(effects
							(font
								(size 1.27 1.27)
							)
						)
					)
					(number "2"
						(effects
							(font
								(size 1.27 1.27)
							)
						)
					)
				)
			)
		)
	(symbol "C_220n_0402_7"
			(pin_numbers hide)
			(pin_names hide)
			(exclude_from_sim no)
			(in_bom yes)
			(on_board yes)
			(property "Reference" "C"
				(at 20.32 -5.08 0)
				(effects
					(font
						(size 1.27 1.27)
						(thickness 0.15)
					)
					(justify left bottom)
				)
			)
			(property "Value" "C_220n_0402"
				(at 20.32 -10.16 0)
				(effects
					(font
						(size 1.27 1.27)
						(thickness 0.15)
					)
					(justify left bottom)
					(hide yes)
				)
			)
			(property "Footprint" "antmicro-footprints:C_0402_1005Metric"
				(at 20.32 -12.7 0)
				(effects
					(font
						(size 1.27 1.27)
						(thickness 0.15)
					)
					(justify left bottom)
					(hide yes)
				)
			)
			(property "Datasheet" "https://www.yageo.com/en/Chart/Download/pdf/CC0402KRX5R6BB224"
				(at 20.32 -15.24 0)
				(effects
					(font
						(size 1.27 1.27)
						(thickness 0.15)
					)
					(justify left bottom)
					(hide yes)
				)
			)
			(property "Description" "SMD Multilayer Ceramic Capacitor, 0.22 µF, 10 V, 0402 [1005 Metric], ± 10%, X5R, CC Series"
				(at 0 0 0)
				(effects
					(font
						(size 1.27 1.27)
					)
					(hide yes)
				)
			)
			(property "MPN" "CC0402KRX5R6BB224"
				(at 20.32 -17.78 0)
				(effects
					(font
						(size 1.27 1.27)
						(thickness 0.15)
					)
					(justify left bottom)
					(hide yes)
				)
			)
			(property "Manufacturer" "YAGEO"
				(at 20.32 -20.32 0)
				(effects
					(font
						(size 1.27 1.27)
						(thickness 0.15)
					)
					(justify left bottom)
					(hide yes)
				)
			)
			(property "License" "Apache-2.0"
				(at 20.32 -22.86 0)
				(effects
					(font
						(size 1.27 1.27)
						(thickness 0.15)
					)
					(justify left bottom)
					(hide yes)
				)
			)
			(property "Author" "Antmicro"
				(at 20.32 -25.4 0)
				(effects
					(font
						(size 1.27 1.27)
						(thickness 0.15)
					)
					(justify left bottom)
					(hide yes)
				)
			)
			(property "Val" "220n"
				(at 20.32 -7.62 0)
				(effects
					(font
						(size 1.27 1.27)
						(thickness 0.15)
					)
					(justify left bottom)
				)
			)
			(property "Voltage" ""
				(at 20.32 -27.94 0)
				(effects
					(font
						(size 1.27 1.27)
					)
					(justify left bottom)
					(hide yes)
				)
			)
			(property "Dielectric" ""
				(at 20.32 -30.48 0)
				(effects
					(font
						(size 1.27 1.27)
					)
					(justify left bottom)
					(hide yes)
				)
			)
			(property "ki_keywords" "0402, SMT, CAPACITOR, PASSIVE, MLCC, CERAMIC"
				(at 0 0 0)
				(effects
					(font
						(size 1.27 1.27)
					)
					(hide yes)
				)
			)
			(symbol "C_220n_0402_7_0_1"
				(polyline
					(pts
						(xy 2.032 -1.524) (xy 2.032 1.524)
					)
					(stroke
						(width 0.3048)
						(type default)
					)
					(fill
						(type none)
					)
				)
				(polyline
					(pts
						(xy 3.048 -1.524) (xy 3.048 1.524)
					)
					(stroke
						(width 0.3302)
						(type default)
					)
					(fill
						(type none)
					)
				)
			)
			(symbol "C_220n_0402_7_1_1"
				(pin passive line
					(at 0 0 0)
					(length 2.032)
					(name "~"
						(effects
							(font
								(size 1.27 1.27)
							)
						)
					)
					(number "1"
						(effects
							(font
								(size 1.27 1.27)
							)
						)
					)
				)
				(pin passive line
					(at 5.08 0 180)
					(length 2.032)
					(name "~"
						(effects
							(font
								(size 1.27 1.27)
							)
						)
					)
					(number "2"
						(effects
							(font
								(size 1.27 1.27)
							)
						)
					)
				)
			)
		)
	(symbol "C_220n_0402_8"
			(pin_numbers hide)
			(pin_names hide)
			(exclude_from_sim no)
			(in_bom yes)
			(on_board yes)
			(property "Reference" "C"
				(at 20.32 -5.08 0)
				(effects
					(font
						(size 1.27 1.27)
						(thickness 0.15)
					)
					(justify left bottom)
				)
			)
			(property "Value" "C_220n_0402"
				(at 20.32 -10.16 0)
				(effects
					(font
						(size 1.27 1.27)
						(thickness 0.15)
					)
					(justify left bottom)
					(hide yes)
				)
			)
			(property "Footprint" "antmicro-footprints:C_0402_1005Metric"
				(at 20.32 -12.7 0)
				(effects
					(font
						(size 1.27 1.27)
						(thickness 0.15)
					)
					(justify left bottom)
					(hide yes)
				)
			)
			(property "Datasheet" "https://www.yageo.com/en/Chart/Download/pdf/CC0402KRX5R6BB224"
				(at 20.32 -15.24 0)
				(effects
					(font
						(size 1.27 1.27)
						(thickness 0.15)
					)
					(justify left bottom)
					(hide yes)
				)
			)
			(property "Description" "SMD Multilayer Ceramic Capacitor, 0.22 µF, 10 V, 0402 [1005 Metric], ± 10%, X5R, CC Series"
				(at 0 0 0)
				(effects
					(font
						(size 1.27 1.27)
					)
					(hide yes)
				)
			)
			(property "MPN" "CC0402KRX5R6BB224"
				(at 20.32 -17.78 0)
				(effects
					(font
						(size 1.27 1.27)
						(thickness 0.15)
					)
					(justify left bottom)
					(hide yes)
				)
			)
			(property "Manufacturer" "YAGEO"
				(at 20.32 -20.32 0)
				(effects
					(font
						(size 1.27 1.27)
						(thickness 0.15)
					)
					(justify left bottom)
					(hide yes)
				)
			)
			(property "License" "Apache-2.0"
				(at 20.32 -22.86 0)
				(effects
					(font
						(size 1.27 1.27)
						(thickness 0.15)
					)
					(justify left bottom)
					(hide yes)
				)
			)
			(property "Author" "Antmicro"
				(at 20.32 -25.4 0)
				(effects
					(font
						(size 1.27 1.27)
						(thickness 0.15)
					)
					(justify left bottom)
					(hide yes)
				)
			)
			(property "Val" "220n"
				(at 20.32 -7.62 0)
				(effects
					(font
						(size 1.27 1.27)
						(thickness 0.15)
					)
					(justify left bottom)
				)
			)
			(property "Voltage" ""
				(at 20.32 -27.94 0)
				(effects
					(font
						(size 1.27 1.27)
					)
					(justify left bottom)
					(hide yes)
				)
			)
			(property "Dielectric" ""
				(at 20.32 -30.48 0)
				(effects
					(font
						(size 1.27 1.27)
					)
					(justify left bottom)
					(hide yes)
				)
			)
			(property "ki_keywords" "0402, SMT, CAPACITOR, PASSIVE, MLCC, CERAMIC"
				(at 0 0 0)
				(effects
					(font
						(size 1.27 1.27)
					)
					(hide yes)
				)
			)
			(symbol "C_220n_0402_8_0_1"
				(polyline
					(pts
						(xy 2.032 -1.524) (xy 2.032 1.524)
					)
					(stroke
						(width 0.3048)
						(type default)
					)
					(fill
						(type none)
					)
				)
				(polyline
					(pts
						(xy 3.048 -1.524) (xy 3.048 1.524)
					)
					(stroke
						(width 0.3302)
						(type default)
					)
					(fill
						(type none)
					)
				)
			)
			(symbol "C_220n_0402_8_1_1"
				(pin passive line
					(at 0 0 0)
					(length 2.032)
					(name "~"
						(effects
							(font
								(size 1.27 1.27)
							)
						)
					)
					(number "1"
						(effects
							(font
								(size 1.27 1.27)
							)
						)
					)
				)
				(pin passive line
					(at 5.08 0 180)
					(length 2.032)
					(name "~"
						(effects
							(font
								(size 1.27 1.27)
							)
						)
					)
					(number "2"
						(effects
							(font
								(size 1.27 1.27)
							)
						)
					)
				)
			)
		)
	(symbol "C_4u7_25V_0402_1"
			(pin_numbers hide)
			(pin_names hide)
			(exclude_from_sim no)
			(in_bom yes)
			(on_board yes)
			(property "Reference" "C"
				(at 20.32 -5.08 0)
				(effects
					(font
						(size 1.27 1.27)
						(thickness 0.15)
					)
					(justify left bottom)
				)
			)
			(property "Value" "C_4u7_25V_0402"
				(at 20.32 -10.16 0)
				(effects
					(font
						(size 1.27 1.27)
						(thickness 0.15)
					)
					(justify left bottom)
					(hide yes)
				)
			)
			(property "Footprint" "antmicro-footprints:C_0402_1005Metric"
				(at 20.32 -12.7 0)
				(effects
					(font
						(size 1.27 1.27)
						(thickness 0.15)
					)
					(justify left bottom)
					(hide yes)
				)
			)
			(property "Datasheet" "https://www.murata.com/products/productdetail?partno=GRM155C61E475ME15%23"
				(at 20.32 -15.24 0)
				(effects
					(font
						(size 1.27 1.27)
						(thickness 0.15)
					)
					(justify left bottom)
					(hide yes)
				)
			)
			(property "Description" "SMD Multilayer Ceramic Capacitor"
				(at 0 0 0)
				(effects
					(font
						(size 1.27 1.27)
					)
					(hide yes)
				)
			)
			(property "MPN" "GRM155C61E475ME15J"
				(at 20.32 -17.78 0)
				(effects
					(font
						(size 1.27 1.27)
						(thickness 0.15)
					)
					(justify left bottom)
					(hide yes)
				)
			)
			(property "Manufacturer" "Murata"
				(at 20.32 -20.32 0)
				(effects
					(font
						(size 1.27 1.27)
						(thickness 0.15)
					)
					(justify left bottom)
					(hide yes)
				)
			)
			(property "License" "Apache-2.0"
				(at 20.32 -22.86 0)
				(effects
					(font
						(size 1.27 1.27)
						(thickness 0.15)
					)
					(justify left bottom)
					(hide yes)
				)
			)
			(property "Author" "Antmicro"
				(at 20.32 -25.4 0)
				(effects
					(font
						(size 1.27 1.27)
						(thickness 0.15)
					)
					(justify left bottom)
					(hide yes)
				)
			)
			(property "Val" "4u7"
				(at 20.32 -7.62 0)
				(effects
					(font
						(size 1.27 1.27)
						(thickness 0.15)
					)
					(justify left bottom)
				)
			)
			(property "Voltage" "25V"
				(at 20.32 -27.94 0)
				(effects
					(font
						(size 1.27 1.27)
					)
					(justify left bottom)
					(hide yes)
				)
			)
			(property "Dielectric" "X5S"
				(at 20.32 -30.48 0)
				(effects
					(font
						(size 1.27 1.27)
					)
					(justify left bottom)
					(hide yes)
				)
			)
			(property "ki_keywords" "0402, SMT, CAPACITOR, PASSIVE, CERAMIC"
				(at 0 0 0)
				(effects
					(font
						(size 1.27 1.27)
					)
					(hide yes)
				)
			)
			(symbol "C_4u7_25V_0402_1_0_1"
				(polyline
					(pts
						(xy 2.032 -1.524) (xy 2.032 1.524)
					)
					(stroke
						(width 0.3048)
						(type default)
					)
					(fill
						(type none)
					)
				)
				(polyline
					(pts
						(xy 3.048 -1.524) (xy 3.048 1.524)
					)
					(stroke
						(width 0.3302)
						(type default)
					)
					(fill
						(type none)
					)
				)
			)
			(symbol "C_4u7_25V_0402_1_1_1"
				(pin passive line
					(at 0 0 0)
					(length 2.032)
					(name "~"
						(effects
							(font
								(size 1.27 1.27)
							)
						)
					)
					(number "1"
						(effects
							(font
								(size 1.27 1.27)
							)
						)
					)
				)
				(pin passive line
					(at 5.08 0 180)
					(length 2.032)
					(name "~"
						(effects
							(font
								(size 1.27 1.27)
							)
						)
					)
					(number "2"
						(effects
							(font
								(size 1.27 1.27)
							)
						)
					)
				)
			)
		)
	(symbol "DF2S30FS_SOD_1"
			(pin_numbers hide)
			(pin_names hide)
			(exclude_from_sim no)
			(in_bom yes)
			(on_board yes)
			(property "Reference" "D"
				(at 21.59 -2.54 0)
				(effects
					(font
						(size 1.27 1.27)
						(thickness 0.15)
					)
					(justify left bottom)
				)
			)
			(property "Value" "DF2S30FS_SOD"
				(at 21.59 -15.24 0)
				(effects
					(font
						(size 1.27 1.27)
						(thickness 0.15)
					)
					(justify left bottom)
					(hide yes)
				)
			)
			(property "Footprint" "antmicro-footprints:SOD-923"
				(at 21.59 -7.62 0)
				(effects
					(font
						(size 1.27 1.27)
						(thickness 0.15)
					)
					(justify left bottom)
					(hide yes)
				)
			)
			(property "Datasheet" "https://toshiba.semicon-storage.com/info/DF2S30FS_datasheet_en_20211216.pdf?did=11156&prodName=DF2S30FS"
				(at 21.59 -10.16 0)
				(effects
					(font
						(size 1.27 1.27)
						(thickness 0.15)
					)
					(justify left bottom)
					(hide yes)
				)
			)
			(property "Description" "Unidirectional TVS, 8 kV,  SOD-923, 23 V, 7 pF"
				(at 0 0 0)
				(effects
					(font
						(size 1.27 1.27)
					)
					(hide yes)
				)
			)
			(property "Manufacturer" "Toshiba"
				(at 21.59 -12.7 0)
				(effects
					(font
						(size 1.27 1.27)
						(thickness 0.15)
					)
					(justify left bottom)
					(hide yes)
				)
			)
			(property "MPN" "DF2S30FS"
				(at 21.59 -5.08 0)
				(effects
					(font
						(size 1.27 1.27)
						(thickness 0.15)
					)
					(justify left bottom)
				)
			)
			(property "Author" "Antmicro"
				(at 21.59 -17.78 0)
				(effects
					(font
						(size 1.27 1.27)
						(thickness 0.15)
					)
					(justify left bottom)
					(hide yes)
				)
			)
			(property "License" "Apache-2.0"
				(at 21.59 -20.32 0)
				(effects
					(font
						(size 1.27 1.27)
						(thickness 0.15)
					)
					(justify left bottom)
					(hide yes)
				)
			)
			(property "ki_keywords" "DIODE, SEMICONDUCTOR, TVS, ESD"
				(at 0 0 0)
				(effects
					(font
						(size 1.27 1.27)
					)
					(hide yes)
				)
			)
			(symbol "DF2S30FS_SOD_1_0_1"
				(polyline
					(pts
						(xy 1.905 0) (xy 0.635 0)
					)
					(stroke
						(width 0)
						(type default)
					)
					(fill
						(type none)
					)
				)
				(polyline
					(pts
						(xy 4.445 0) (xy 3.175 0)
					)
					(stroke
						(width 0)
						(type default)
					)
					(fill
						(type none)
					)
				)
			)
			(symbol "DF2S30FS_SOD_1_1_1"
				(polyline
					(pts
						(xy 1.778 1.016) (xy 1.397 1.016)
					)
					(stroke
						(width 0.254)
						(type default)
					)
					(fill
						(type none)
					)
				)
				(polyline
					(pts
						(xy 1.778 1.016) (xy 1.778 -1.016)
					)
					(stroke
						(width 0.254)
						(type default)
					)
					(fill
						(type none)
					)
				)
				(polyline
					(pts
						(xy 2.159 -1.016) (xy 1.778 -1.016)
					)
					(stroke
						(width 0.254)
						(type default)
					)
					(fill
						(type none)
					)
				)
				(polyline
					(pts
						(xy 3.302 1.016) (xy 3.302 -1.016) (xy 1.778 0) (xy 3.302 1.016)
					)
					(stroke
						(width 0.254)
						(type default)
					)
					(fill
						(type outline)
					)
				)
				(pin passive line
					(at 0 0 0)
					(length 0.635)
					(name "C"
						(effects
							(font
								(size 1.27 1.27)
							)
						)
					)
					(number "1"
						(effects
							(font
								(size 1.27 1.27)
							)
						)
					)
				)
				(pin passive line
					(at 5.08 0 180)
					(length 0.635)
					(name "A"
						(effects
							(font
								(size 1.27 1.27)
							)
						)
					)
					(number "2"
						(effects
							(font
								(size 1.27 1.27)
							)
						)
					)
				)
			)
		)
	(symbol "GND_1"
			(power)
			(pin_numbers hide)
			(pin_names hide)
			(exclude_from_sim no)
			(in_bom yes)
			(on_board yes)
			(property "Reference" "#PWR"
				(at 8.89 -2.54 0)
				(effects
					(font
						(size 1.27 1.27)
						(thickness 0.15)
					)
					(justify left bottom)
					(hide yes)
				)
			)
			(property "Value" "GND_1"
				(at 8.89 -5.08 0)
				(effects
					(font
						(size 1.27 1.27)
						(thickness 0.15)
					)
					(justify left bottom)
				)
			)
			(property "Footprint" ""
				(at 8.89 -7.62 0)
				(effects
					(font
						(size 1.27 1.27)
						(thickness 0.15)
					)
					(justify left bottom)
					(hide yes)
				)
			)
			(property "Datasheet" ""
				(at 8.89 -12.7 0)
				(effects
					(font
						(size 1.27 1.27)
						(thickness 0.15)
					)
					(justify left bottom)
					(hide yes)
				)
			)
			(property "Description" ""
				(at 0 0 0)
				(effects
					(font
						(size 1.27 1.27)
					)
					(hide yes)
				)
			)
			(property "Author" "Antmicro"
				(at 8.89 -7.62 0)
				(effects
					(font
						(size 1.27 1.27)
						(thickness 0.15)
					)
					(justify left bottom)
					(hide yes)
				)
			)
			(property "License" "Apache-2.0"
				(at 8.89 -10.16 0)
				(effects
					(font
						(size 1.27 1.27)
						(thickness 0.15)
					)
					(justify left bottom)
					(hide yes)
				)
			)
			(symbol "GND_1_1_1"
				(polyline
					(pts
						(xy 0 0) (xy 0 -1.27) (xy 1.27 -1.27) (xy 0 -2.54) (xy -1.27 -1.27) (xy 0 -1.27)
					)
					(stroke
						(width 0)
						(type default)
					)
					(fill
						(type none)
					)
				)
				(pin power_in line
					(at 0 0 270)
					(length 0)
					(name "GND"
						(effects
							(font
								(size 1.27 1.27)
							)
						)
					)
					(number "1"
						(effects
							(font
								(size 1.27 1.27)
							)
						)
					)
				)
			)
		)
	(symbol "GND_2"
			(power)
			(pin_numbers hide)
			(pin_names hide)
			(exclude_from_sim no)
			(in_bom yes)
			(on_board yes)
			(property "Reference" "#PWR"
				(at 8.89 -2.54 0)
				(effects
					(font
						(size 1.27 1.27)
						(thickness 0.15)
					)
					(justify left bottom)
					(hide yes)
				)
			)
			(property "Value" "GND_2"
				(at 8.89 -5.08 0)
				(effects
					(font
						(size 1.27 1.27)
						(thickness 0.15)
					)
					(justify left bottom)
				)
			)
			(property "Footprint" ""
				(at 8.89 -7.62 0)
				(effects
					(font
						(size 1.27 1.27)
						(thickness 0.15)
					)
					(justify left bottom)
					(hide yes)
				)
			)
			(property "Datasheet" ""
				(at 8.89 -12.7 0)
				(effects
					(font
						(size 1.27 1.27)
						(thickness 0.15)
					)
					(justify left bottom)
					(hide yes)
				)
			)
			(property "Description" ""
				(at 0 0 0)
				(effects
					(font
						(size 1.27 1.27)
					)
					(hide yes)
				)
			)
			(property "Author" "Antmicro"
				(at 8.89 -7.62 0)
				(effects
					(font
						(size 1.27 1.27)
						(thickness 0.15)
					)
					(justify left bottom)
					(hide yes)
				)
			)
			(property "License" "Apache-2.0"
				(at 8.89 -10.16 0)
				(effects
					(font
						(size 1.27 1.27)
						(thickness 0.15)
					)
					(justify left bottom)
					(hide yes)
				)
			)
			(symbol "GND_2_1_1"
				(polyline
					(pts
						(xy 0 0) (xy 0 -1.27) (xy 1.27 -1.27) (xy 0 -2.54) (xy -1.27 -1.27) (xy 0 -1.27)
					)
					(stroke
						(width 0)
						(type default)
					)
					(fill
						(type none)
					)
				)
				(pin power_in line
					(at 0 0 270)
					(length 0)
					(name "GND"
						(effects
							(font
								(size 1.27 1.27)
							)
						)
					)
					(number "1"
						(effects
							(font
								(size 1.27 1.27)
							)
						)
					)
				)
			)
		)
	(symbol "GND_3"
			(power)
			(pin_numbers hide)
			(pin_names hide)
			(exclude_from_sim no)
			(in_bom yes)
			(on_board yes)
			(property "Reference" "#PWR"
				(at 8.89 -2.54 0)
				(effects
					(font
						(size 1.27 1.27)
						(thickness 0.15)
					)
					(justify left bottom)
					(hide yes)
				)
			)
			(property "Value" "GND_3"
				(at 8.89 -5.08 0)
				(effects
					(font
						(size 1.27 1.27)
						(thickness 0.15)
					)
					(justify left bottom)
				)
			)
			(property "Footprint" ""
				(at 8.89 -7.62 0)
				(effects
					(font
						(size 1.27 1.27)
						(thickness 0.15)
					)
					(justify left bottom)
					(hide yes)
				)
			)
			(property "Datasheet" ""
				(at 8.89 -12.7 0)
				(effects
					(font
						(size 1.27 1.27)
						(thickness 0.15)
					)
					(justify left bottom)
					(hide yes)
				)
			)
			(property "Description" ""
				(at 0 0 0)
				(effects
					(font
						(size 1.27 1.27)
					)
					(hide yes)
				)
			)
			(property "Author" "Antmicro"
				(at 8.89 -7.62 0)
				(effects
					(font
						(size 1.27 1.27)
						(thickness 0.15)
					)
					(justify left bottom)
					(hide yes)
				)
			)
			(property "License" "Apache-2.0"
				(at 8.89 -10.16 0)
				(effects
					(font
						(size 1.27 1.27)
						(thickness 0.15)
					)
					(justify left bottom)
					(hide yes)
				)
			)
			(symbol "GND_3_1_1"
				(polyline
					(pts
						(xy 0 0) (xy 0 -1.27) (xy 1.27 -1.27) (xy 0 -2.54) (xy -1.27 -1.27) (xy 0 -1.27)
					)
					(stroke
						(width 0)
						(type default)
					)
					(fill
						(type none)
					)
				)
				(pin power_in line
					(at 0 0 270)
					(length 0)
					(name "GND"
						(effects
							(font
								(size 1.27 1.27)
							)
						)
					)
					(number "1"
						(effects
							(font
								(size 1.27 1.27)
							)
						)
					)
				)
			)
		)
	(symbol "GND_4"
			(power)
			(pin_numbers hide)
			(pin_names hide)
			(exclude_from_sim no)
			(in_bom yes)
			(on_board yes)
			(property "Reference" "#PWR"
				(at 8.89 -2.54 0)
				(effects
					(font
						(size 1.27 1.27)
						(thickness 0.15)
					)
					(justify left bottom)
					(hide yes)
				)
			)
			(property "Value" "GND_4"
				(at 8.89 -5.08 0)
				(effects
					(font
						(size 1.27 1.27)
						(thickness 0.15)
					)
					(justify left bottom)
				)
			)
			(property "Footprint" ""
				(at 8.89 -7.62 0)
				(effects
					(font
						(size 1.27 1.27)
						(thickness 0.15)
					)
					(justify left bottom)
					(hide yes)
				)
			)
			(property "Datasheet" ""
				(at 8.89 -12.7 0)
				(effects
					(font
						(size 1.27 1.27)
						(thickness 0.15)
					)
					(justify left bottom)
					(hide yes)
				)
			)
			(property "Description" ""
				(at 0 0 0)
				(effects
					(font
						(size 1.27 1.27)
					)
					(hide yes)
				)
			)
			(property "Author" "Antmicro"
				(at 8.89 -7.62 0)
				(effects
					(font
						(size 1.27 1.27)
						(thickness 0.15)
					)
					(justify left bottom)
					(hide yes)
				)
			)
			(property "License" "Apache-2.0"
				(at 8.89 -10.16 0)
				(effects
					(font
						(size 1.27 1.27)
						(thickness 0.15)
					)
					(justify left bottom)
					(hide yes)
				)
			)
			(symbol "GND_4_1_1"
				(polyline
					(pts
						(xy 0 0) (xy 0 -1.27) (xy 1.27 -1.27) (xy 0 -2.54) (xy -1.27 -1.27) (xy 0 -1.27)
					)
					(stroke
						(width 0)
						(type default)
					)
					(fill
						(type none)
					)
				)
				(pin power_in line
					(at 0 0 270)
					(length 0)
					(name "GND"
						(effects
							(font
								(size 1.27 1.27)
							)
						)
					)
					(number "1"
						(effects
							(font
								(size 1.27 1.27)
							)
						)
					)
				)
			)
		)
	(symbol "GND_5"
			(power)
			(pin_numbers hide)
			(pin_names hide)
			(exclude_from_sim no)
			(in_bom yes)
			(on_board yes)
			(property "Reference" "#PWR"
				(at 8.89 -2.54 0)
				(effects
					(font
						(size 1.27 1.27)
						(thickness 0.15)
					)
					(justify left bottom)
					(hide yes)
				)
			)
			(property "Value" "GND_5"
				(at 8.89 -5.08 0)
				(effects
					(font
						(size 1.27 1.27)
						(thickness 0.15)
					)
					(justify left bottom)
				)
			)
			(property "Footprint" ""
				(at 8.89 -7.62 0)
				(effects
					(font
						(size 1.27 1.27)
						(thickness 0.15)
					)
					(justify left bottom)
					(hide yes)
				)
			)
			(property "Datasheet" ""
				(at 8.89 -12.7 0)
				(effects
					(font
						(size 1.27 1.27)
						(thickness 0.15)
					)
					(justify left bottom)
					(hide yes)
				)
			)
			(property "Description" ""
				(at 0 0 0)
				(effects
					(font
						(size 1.27 1.27)
					)
					(hide yes)
				)
			)
			(property "Author" "Antmicro"
				(at 8.89 -7.62 0)
				(effects
					(font
						(size 1.27 1.27)
						(thickness 0.15)
					)
					(justify left bottom)
					(hide yes)
				)
			)
			(property "License" "Apache-2.0"
				(at 8.89 -10.16 0)
				(effects
					(font
						(size 1.27 1.27)
						(thickness 0.15)
					)
					(justify left bottom)
					(hide yes)
				)
			)
			(symbol "GND_5_1_1"
				(polyline
					(pts
						(xy 0 0) (xy 0 -1.27) (xy 1.27 -1.27) (xy 0 -2.54) (xy -1.27 -1.27) (xy 0 -1.27)
					)
					(stroke
						(width 0)
						(type default)
					)
					(fill
						(type none)
					)
				)
				(pin power_in line
					(at 0 0 270)
					(length 0)
					(name "GND"
						(effects
							(font
								(size 1.27 1.27)
							)
						)
					)
					(number "1"
						(effects
							(font
								(size 1.27 1.27)
							)
						)
					)
				)
			)
		)
	(symbol "GND_6"
			(power)
			(pin_numbers hide)
			(pin_names hide)
			(exclude_from_sim no)
			(in_bom yes)
			(on_board yes)
			(property "Reference" "#PWR"
				(at 8.89 -2.54 0)
				(effects
					(font
						(size 1.27 1.27)
						(thickness 0.15)
					)
					(justify left bottom)
					(hide yes)
				)
			)
			(property "Value" "GND_6"
				(at 8.89 -5.08 0)
				(effects
					(font
						(size 1.27 1.27)
						(thickness 0.15)
					)
					(justify left bottom)
				)
			)
			(property "Footprint" ""
				(at 8.89 -7.62 0)
				(effects
					(font
						(size 1.27 1.27)
						(thickness 0.15)
					)
					(justify left bottom)
					(hide yes)
				)
			)
			(property "Datasheet" ""
				(at 8.89 -12.7 0)
				(effects
					(font
						(size 1.27 1.27)
						(thickness 0.15)
					)
					(justify left bottom)
					(hide yes)
				)
			)
			(property "Description" ""
				(at 0 0 0)
				(effects
					(font
						(size 1.27 1.27)
					)
					(hide yes)
				)
			)
			(property "Author" "Antmicro"
				(at 8.89 -7.62 0)
				(effects
					(font
						(size 1.27 1.27)
						(thickness 0.15)
					)
					(justify left bottom)
					(hide yes)
				)
			)
			(property "License" "Apache-2.0"
				(at 8.89 -10.16 0)
				(effects
					(font
						(size 1.27 1.27)
						(thickness 0.15)
					)
					(justify left bottom)
					(hide yes)
				)
			)
			(symbol "GND_6_1_1"
				(polyline
					(pts
						(xy 0 0) (xy 0 -1.27) (xy 1.27 -1.27) (xy 0 -2.54) (xy -1.27 -1.27) (xy 0 -1.27)
					)
					(stroke
						(width 0)
						(type default)
					)
					(fill
						(type none)
					)
				)
				(pin power_in line
					(at 0 0 270)
					(length 0)
					(name "GND"
						(effects
							(font
								(size 1.27 1.27)
							)
						)
					)
					(number "1"
						(effects
							(font
								(size 1.27 1.27)
							)
						)
					)
				)
			)
		)
	(symbol "GND_7"
			(power)
			(pin_numbers hide)
			(pin_names hide)
			(exclude_from_sim no)
			(in_bom yes)
			(on_board yes)
			(property "Reference" "#PWR"
				(at 8.89 -2.54 0)
				(effects
					(font
						(size 1.27 1.27)
						(thickness 0.15)
					)
					(justify left bottom)
					(hide yes)
				)
			)
			(property "Value" "GND_7"
				(at 8.89 -5.08 0)
				(effects
					(font
						(size 1.27 1.27)
						(thickness 0.15)
					)
					(justify left bottom)
				)
			)
			(property "Footprint" ""
				(at 8.89 -7.62 0)
				(effects
					(font
						(size 1.27 1.27)
						(thickness 0.15)
					)
					(justify left bottom)
					(hide yes)
				)
			)
			(property "Datasheet" ""
				(at 8.89 -12.7 0)
				(effects
					(font
						(size 1.27 1.27)
						(thickness 0.15)
					)
					(justify left bottom)
					(hide yes)
				)
			)
			(property "Description" ""
				(at 0 0 0)
				(effects
					(font
						(size 1.27 1.27)
					)
					(hide yes)
				)
			)
			(property "Author" "Antmicro"
				(at 8.89 -7.62 0)
				(effects
					(font
						(size 1.27 1.27)
						(thickness 0.15)
					)
					(justify left bottom)
					(hide yes)
				)
			)
			(property "License" "Apache-2.0"
				(at 8.89 -10.16 0)
				(effects
					(font
						(size 1.27 1.27)
						(thickness 0.15)
					)
					(justify left bottom)
					(hide yes)
				)
			)
			(symbol "GND_7_1_1"
				(polyline
					(pts
						(xy 0 0) (xy 0 -1.27) (xy 1.27 -1.27) (xy 0 -2.54) (xy -1.27 -1.27) (xy 0 -1.27)
					)
					(stroke
						(width 0)
						(type default)
					)
					(fill
						(type none)
					)
				)
				(pin power_in line
					(at 0 0 270)
					(length 0)
					(name "GND"
						(effects
							(font
								(size 1.27 1.27)
							)
						)
					)
					(number "1"
						(effects
							(font
								(size 1.27 1.27)
							)
						)
					)
				)
			)
		)
	(symbol "GND_8"
			(power)
			(pin_numbers hide)
			(pin_names hide)
			(exclude_from_sim no)
			(in_bom yes)
			(on_board yes)
			(property "Reference" "#PWR"
				(at 8.89 -2.54 0)
				(effects
					(font
						(size 1.27 1.27)
						(thickness 0.15)
					)
					(justify left bottom)
					(hide yes)
				)
			)
			(property "Value" "GND_8"
				(at 8.89 -5.08 0)
				(effects
					(font
						(size 1.27 1.27)
						(thickness 0.15)
					)
					(justify left bottom)
				)
			)
			(property "Footprint" ""
				(at 8.89 -7.62 0)
				(effects
					(font
						(size 1.27 1.27)
						(thickness 0.15)
					)
					(justify left bottom)
					(hide yes)
				)
			)
			(property "Datasheet" ""
				(at 8.89 -12.7 0)
				(effects
					(font
						(size 1.27 1.27)
						(thickness 0.15)
					)
					(justify left bottom)
					(hide yes)
				)
			)
			(property "Description" ""
				(at 0 0 0)
				(effects
					(font
						(size 1.27 1.27)
					)
					(hide yes)
				)
			)
			(property "Author" "Antmicro"
				(at 8.89 -7.62 0)
				(effects
					(font
						(size 1.27 1.27)
						(thickness 0.15)
					)
					(justify left bottom)
					(hide yes)
				)
			)
			(property "License" "Apache-2.0"
				(at 8.89 -10.16 0)
				(effects
					(font
						(size 1.27 1.27)
						(thickness 0.15)
					)
					(justify left bottom)
					(hide yes)
				)
			)
			(symbol "GND_8_1_1"
				(polyline
					(pts
						(xy 0 0) (xy 0 -1.27) (xy 1.27 -1.27) (xy 0 -2.54) (xy -1.27 -1.27) (xy 0 -1.27)
					)
					(stroke
						(width 0)
						(type default)
					)
					(fill
						(type none)
					)
				)
				(pin power_in line
					(at 0 0 270)
					(length 0)
					(name "GND"
						(effects
							(font
								(size 1.27 1.27)
							)
						)
					)
					(number "1"
						(effects
							(font
								(size 1.27 1.27)
							)
						)
					)
				)
			)
		)
	(symbol "LED_G_0603_LTST-C190GKT_1"
			(pin_numbers hide)
			(pin_names hide)
			(exclude_from_sim no)
			(in_bom yes)
			(on_board yes)
			(property "Reference" "D"
				(at 22.86 -2.54 0)
				(effects
					(font
						(size 1.27 1.27)
						(thickness 0.15)
					)
					(justify left bottom)
				)
			)
			(property "Value" "LED_G_0603_LTST-C190GKT"
				(at 22.86 -7.62 0)
				(effects
					(font
						(size 1.27 1.27)
						(thickness 0.15)
					)
					(justify left bottom)
					(hide yes)
				)
			)
			(property "Footprint" "antmicro-footprints:LED_0603_1608Metric_G"
				(at 22.86 -10.16 0)
				(effects
					(font
						(size 1.27 1.27)
						(thickness 0.15)
					)
					(justify left bottom)
					(hide yes)
				)
			)
			(property "Datasheet" "https://media.digikey.com/pdf/Data%20Sheets/Lite-On%20PDFs/LTST-C190GKT.pdf"
				(at 22.86 -12.7 0)
				(effects
					(font
						(size 1.27 1.27)
						(thickness 0.15)
					)
					(justify left bottom)
					(hide yes)
				)
			)
			(property "Description" "LED, Green, SMD, 0603, 20 mA, 2.1 V, 569 nm"
				(at 0 0 0)
				(effects
					(font
						(size 1.27 1.27)
					)
					(hide yes)
				)
			)
			(property "MPN" "LTST-C190GKT"
				(at 22.86 -15.24 0)
				(effects
					(font
						(size 1.27 1.27)
						(thickness 0.15)
					)
					(justify left bottom)
					(hide yes)
				)
			)
			(property "Manufacturer" "Lite-On"
				(at 22.86 -17.78 0)
				(effects
					(font
						(size 1.27 1.27)
						(thickness 0.15)
					)
					(justify left bottom)
					(hide yes)
				)
			)
			(property "Color" "Green"
				(at 22.86 -5.08 0)
				(effects
					(font
						(size 1.27 1.27)
					)
					(justify left bottom)
				)
			)
			(property "Author" "Antmicro"
				(at 22.86 -20.32 0)
				(effects
					(font
						(size 1.27 1.27)
						(thickness 0.15)
					)
					(justify left bottom)
					(hide yes)
				)
			)
			(property "License" "Apache-2.0"
				(at 22.86 -22.86 0)
				(effects
					(font
						(size 1.27 1.27)
						(thickness 0.15)
					)
					(justify left bottom)
					(hide yes)
				)
			)
			(property "ki_keywords" "SMT, DIODE, SEMICONDUCTOR, LED"
				(at 0 0 0)
				(effects
					(font
						(size 1.27 1.27)
					)
					(hide yes)
				)
			)
			(symbol "LED_G_0603_LTST-C190GKT_1_0_1"
				(polyline
					(pts
						(xy 1.905 0) (xy 0.635 0)
					)
					(stroke
						(width 0)
						(type default)
					)
					(fill
						(type none)
					)
				)
				(polyline
					(pts
						(xy 4.445 0) (xy 3.175 0)
					)
					(stroke
						(width 0)
						(type default)
					)
					(fill
						(type none)
					)
				)
			)
			(symbol "LED_G_0603_LTST-C190GKT_1_1_1"
				(polyline
					(pts
						(xy 1.778 1.016) (xy 1.778 -1.016)
					)
					(stroke
						(width 0.254)
						(type default)
					)
					(fill
						(type none)
					)
				)
				(polyline
					(pts
						(xy 3.302 1.016) (xy 3.302 -1.016) (xy 1.778 0) (xy 3.302 1.016)
					)
					(stroke
						(width 0.254)
						(type default)
					)
					(fill
						(type outline)
					)
				)
				(polyline
					(pts
						(xy 1.143 2.286) (xy 1.143 1.778) (xy 1.143 2.286) (xy 1.651 2.286) (xy 1.143 2.286) (xy 2.159 1.27)
					)
					(stroke
						(width 0.254)
						(type default)
					)
					(fill
						(type none)
					)
				)
				(polyline
					(pts
						(xy 2.159 2.54) (xy 2.159 2.032) (xy 2.159 2.54) (xy 2.667 2.54) (xy 2.159 2.54) (xy 3.048 1.651)
					)
					(stroke
						(width 0.254)
						(type default)
					)
					(fill
						(type none)
					)
				)
				(pin passive line
					(at 0 0 0)
					(length 0.635)
					(name "C"
						(effects
							(font
								(size 1.27 1.27)
							)
						)
					)
					(number "1"
						(effects
							(font
								(size 1.27 1.27)
							)
						)
					)
				)
				(pin passive line
					(at 5.08 0 180)
					(length 0.635)
					(name "A"
						(effects
							(font
								(size 1.27 1.27)
							)
						)
					)
					(number "2"
						(effects
							(font
								(size 1.27 1.27)
							)
						)
					)
				)
			)
		)
	(symbol "LED_G_0603_LTST-C190GKT_2"
			(pin_numbers hide)
			(pin_names hide)
			(exclude_from_sim no)
			(in_bom yes)
			(on_board yes)
			(property "Reference" "D"
				(at 22.86 -2.54 0)
				(effects
					(font
						(size 1.27 1.27)
						(thickness 0.15)
					)
					(justify left bottom)
				)
			)
			(property "Value" "LED_G_0603_LTST-C190GKT"
				(at 22.86 -7.62 0)
				(effects
					(font
						(size 1.27 1.27)
						(thickness 0.15)
					)
					(justify left bottom)
					(hide yes)
				)
			)
			(property "Footprint" "antmicro-footprints:LED_0603_1608Metric_G"
				(at 22.86 -10.16 0)
				(effects
					(font
						(size 1.27 1.27)
						(thickness 0.15)
					)
					(justify left bottom)
					(hide yes)
				)
			)
			(property "Datasheet" "https://media.digikey.com/pdf/Data%20Sheets/Lite-On%20PDFs/LTST-C190GKT.pdf"
				(at 22.86 -12.7 0)
				(effects
					(font
						(size 1.27 1.27)
						(thickness 0.15)
					)
					(justify left bottom)
					(hide yes)
				)
			)
			(property "Description" "LED, Green, SMD, 0603, 20 mA, 2.1 V, 569 nm"
				(at 0 0 0)
				(effects
					(font
						(size 1.27 1.27)
					)
					(hide yes)
				)
			)
			(property "MPN" "LTST-C190GKT"
				(at 22.86 -15.24 0)
				(effects
					(font
						(size 1.27 1.27)
						(thickness 0.15)
					)
					(justify left bottom)
					(hide yes)
				)
			)
			(property "Manufacturer" "Lite-On"
				(at 22.86 -17.78 0)
				(effects
					(font
						(size 1.27 1.27)
						(thickness 0.15)
					)
					(justify left bottom)
					(hide yes)
				)
			)
			(property "Color" "Green"
				(at 22.86 -5.08 0)
				(effects
					(font
						(size 1.27 1.27)
					)
					(justify left bottom)
				)
			)
			(property "Author" "Antmicro"
				(at 22.86 -20.32 0)
				(effects
					(font
						(size 1.27 1.27)
						(thickness 0.15)
					)
					(justify left bottom)
					(hide yes)
				)
			)
			(property "License" "Apache-2.0"
				(at 22.86 -22.86 0)
				(effects
					(font
						(size 1.27 1.27)
						(thickness 0.15)
					)
					(justify left bottom)
					(hide yes)
				)
			)
			(property "ki_keywords" "SMT, DIODE, SEMICONDUCTOR, LED"
				(at 0 0 0)
				(effects
					(font
						(size 1.27 1.27)
					)
					(hide yes)
				)
			)
			(symbol "LED_G_0603_LTST-C190GKT_2_0_1"
				(polyline
					(pts
						(xy 1.905 0) (xy 0.635 0)
					)
					(stroke
						(width 0)
						(type default)
					)
					(fill
						(type none)
					)
				)
				(polyline
					(pts
						(xy 4.445 0) (xy 3.175 0)
					)
					(stroke
						(width 0)
						(type default)
					)
					(fill
						(type none)
					)
				)
			)
			(symbol "LED_G_0603_LTST-C190GKT_2_1_1"
				(polyline
					(pts
						(xy 1.778 1.016) (xy 1.778 -1.016)
					)
					(stroke
						(width 0.254)
						(type default)
					)
					(fill
						(type none)
					)
				)
				(polyline
					(pts
						(xy 3.302 1.016) (xy 3.302 -1.016) (xy 1.778 0) (xy 3.302 1.016)
					)
					(stroke
						(width 0.254)
						(type default)
					)
					(fill
						(type outline)
					)
				)
				(polyline
					(pts
						(xy 1.143 2.286) (xy 1.143 1.778) (xy 1.143 2.286) (xy 1.651 2.286) (xy 1.143 2.286) (xy 2.159 1.27)
					)
					(stroke
						(width 0.254)
						(type default)
					)
					(fill
						(type none)
					)
				)
				(polyline
					(pts
						(xy 2.159 2.54) (xy 2.159 2.032) (xy 2.159 2.54) (xy 2.667 2.54) (xy 2.159 2.54) (xy 3.048 1.651)
					)
					(stroke
						(width 0.254)
						(type default)
					)
					(fill
						(type none)
					)
				)
				(pin passive line
					(at 0 0 0)
					(length 0.635)
					(name "C"
						(effects
							(font
								(size 1.27 1.27)
							)
						)
					)
					(number "1"
						(effects
							(font
								(size 1.27 1.27)
							)
						)
					)
				)
				(pin passive line
					(at 5.08 0 180)
					(length 0.635)
					(name "A"
						(effects
							(font
								(size 1.27 1.27)
							)
						)
					)
					(number "2"
						(effects
							(font
								(size 1.27 1.27)
							)
						)
					)
				)
			)
		)
	(symbol "LED_G_0603_LTST-C190GKT_3"
			(pin_numbers hide)
			(pin_names hide)
			(exclude_from_sim no)
			(in_bom yes)
			(on_board yes)
			(property "Reference" "D"
				(at 22.86 -2.54 0)
				(effects
					(font
						(size 1.27 1.27)
						(thickness 0.15)
					)
					(justify left bottom)
				)
			)
			(property "Value" "LED_G_0603_LTST-C190GKT"
				(at 22.86 -7.62 0)
				(effects
					(font
						(size 1.27 1.27)
						(thickness 0.15)
					)
					(justify left bottom)
					(hide yes)
				)
			)
			(property "Footprint" "antmicro-footprints:LED_0603_1608Metric_G"
				(at 22.86 -10.16 0)
				(effects
					(font
						(size 1.27 1.27)
						(thickness 0.15)
					)
					(justify left bottom)
					(hide yes)
				)
			)
			(property "Datasheet" "https://media.digikey.com/pdf/Data%20Sheets/Lite-On%20PDFs/LTST-C190GKT.pdf"
				(at 22.86 -12.7 0)
				(effects
					(font
						(size 1.27 1.27)
						(thickness 0.15)
					)
					(justify left bottom)
					(hide yes)
				)
			)
			(property "Description" "LED, Green, SMD, 0603, 20 mA, 2.1 V, 569 nm"
				(at 0 0 0)
				(effects
					(font
						(size 1.27 1.27)
					)
					(hide yes)
				)
			)
			(property "MPN" "LTST-C190GKT"
				(at 22.86 -15.24 0)
				(effects
					(font
						(size 1.27 1.27)
						(thickness 0.15)
					)
					(justify left bottom)
					(hide yes)
				)
			)
			(property "Manufacturer" "Lite-On"
				(at 22.86 -17.78 0)
				(effects
					(font
						(size 1.27 1.27)
						(thickness 0.15)
					)
					(justify left bottom)
					(hide yes)
				)
			)
			(property "Color" "Green"
				(at 22.86 -5.08 0)
				(effects
					(font
						(size 1.27 1.27)
					)
					(justify left bottom)
				)
			)
			(property "Author" "Antmicro"
				(at 22.86 -20.32 0)
				(effects
					(font
						(size 1.27 1.27)
						(thickness 0.15)
					)
					(justify left bottom)
					(hide yes)
				)
			)
			(property "License" "Apache-2.0"
				(at 22.86 -22.86 0)
				(effects
					(font
						(size 1.27 1.27)
						(thickness 0.15)
					)
					(justify left bottom)
					(hide yes)
				)
			)
			(property "ki_keywords" "SMT, DIODE, SEMICONDUCTOR, LED"
				(at 0 0 0)
				(effects
					(font
						(size 1.27 1.27)
					)
					(hide yes)
				)
			)
			(symbol "LED_G_0603_LTST-C190GKT_3_0_1"
				(polyline
					(pts
						(xy 1.905 0) (xy 0.635 0)
					)
					(stroke
						(width 0)
						(type default)
					)
					(fill
						(type none)
					)
				)
				(polyline
					(pts
						(xy 4.445 0) (xy 3.175 0)
					)
					(stroke
						(width 0)
						(type default)
					)
					(fill
						(type none)
					)
				)
			)
			(symbol "LED_G_0603_LTST-C190GKT_3_1_1"
				(polyline
					(pts
						(xy 1.778 1.016) (xy 1.778 -1.016)
					)
					(stroke
						(width 0.254)
						(type default)
					)
					(fill
						(type none)
					)
				)
				(polyline
					(pts
						(xy 3.302 1.016) (xy 3.302 -1.016) (xy 1.778 0) (xy 3.302 1.016)
					)
					(stroke
						(width 0.254)
						(type default)
					)
					(fill
						(type outline)
					)
				)
				(polyline
					(pts
						(xy 1.143 2.286) (xy 1.143 1.778) (xy 1.143 2.286) (xy 1.651 2.286) (xy 1.143 2.286) (xy 2.159 1.27)
					)
					(stroke
						(width 0.254)
						(type default)
					)
					(fill
						(type none)
					)
				)
				(polyline
					(pts
						(xy 2.159 2.54) (xy 2.159 2.032) (xy 2.159 2.54) (xy 2.667 2.54) (xy 2.159 2.54) (xy 3.048 1.651)
					)
					(stroke
						(width 0.254)
						(type default)
					)
					(fill
						(type none)
					)
				)
				(pin passive line
					(at 0 0 0)
					(length 0.635)
					(name "C"
						(effects
							(font
								(size 1.27 1.27)
							)
						)
					)
					(number "1"
						(effects
							(font
								(size 1.27 1.27)
							)
						)
					)
				)
				(pin passive line
					(at 5.08 0 180)
					(length 0.635)
					(name "A"
						(effects
							(font
								(size 1.27 1.27)
							)
						)
					)
					(number "2"
						(effects
							(font
								(size 1.27 1.27)
							)
						)
					)
				)
			)
		)
	(symbol "LED_G_0603_LTST-C190GKT_4"
			(pin_numbers hide)
			(pin_names hide)
			(exclude_from_sim no)
			(in_bom yes)
			(on_board yes)
			(property "Reference" "D"
				(at 22.86 -2.54 0)
				(effects
					(font
						(size 1.27 1.27)
						(thickness 0.15)
					)
					(justify left bottom)
				)
			)
			(property "Value" "LED_G_0603_LTST-C190GKT"
				(at 22.86 -7.62 0)
				(effects
					(font
						(size 1.27 1.27)
						(thickness 0.15)
					)
					(justify left bottom)
					(hide yes)
				)
			)
			(property "Footprint" "antmicro-footprints:LED_0603_1608Metric_G"
				(at 22.86 -10.16 0)
				(effects
					(font
						(size 1.27 1.27)
						(thickness 0.15)
					)
					(justify left bottom)
					(hide yes)
				)
			)
			(property "Datasheet" "https://media.digikey.com/pdf/Data%20Sheets/Lite-On%20PDFs/LTST-C190GKT.pdf"
				(at 22.86 -12.7 0)
				(effects
					(font
						(size 1.27 1.27)
						(thickness 0.15)
					)
					(justify left bottom)
					(hide yes)
				)
			)
			(property "Description" "LED, Green, SMD, 0603, 20 mA, 2.1 V, 569 nm"
				(at 0 0 0)
				(effects
					(font
						(size 1.27 1.27)
					)
					(hide yes)
				)
			)
			(property "MPN" "LTST-C190GKT"
				(at 22.86 -15.24 0)
				(effects
					(font
						(size 1.27 1.27)
						(thickness 0.15)
					)
					(justify left bottom)
					(hide yes)
				)
			)
			(property "Manufacturer" "Lite-On"
				(at 22.86 -17.78 0)
				(effects
					(font
						(size 1.27 1.27)
						(thickness 0.15)
					)
					(justify left bottom)
					(hide yes)
				)
			)
			(property "Color" "Green"
				(at 22.86 -5.08 0)
				(effects
					(font
						(size 1.27 1.27)
					)
					(justify left bottom)
				)
			)
			(property "Author" "Antmicro"
				(at 22.86 -20.32 0)
				(effects
					(font
						(size 1.27 1.27)
						(thickness 0.15)
					)
					(justify left bottom)
					(hide yes)
				)
			)
			(property "License" "Apache-2.0"
				(at 22.86 -22.86 0)
				(effects
					(font
						(size 1.27 1.27)
						(thickness 0.15)
					)
					(justify left bottom)
					(hide yes)
				)
			)
			(property "ki_keywords" "SMT, DIODE, SEMICONDUCTOR, LED"
				(at 0 0 0)
				(effects
					(font
						(size 1.27 1.27)
					)
					(hide yes)
				)
			)
			(symbol "LED_G_0603_LTST-C190GKT_4_0_1"
				(polyline
					(pts
						(xy 1.905 0) (xy 0.635 0)
					)
					(stroke
						(width 0)
						(type default)
					)
					(fill
						(type none)
					)
				)
				(polyline
					(pts
						(xy 4.445 0) (xy 3.175 0)
					)
					(stroke
						(width 0)
						(type default)
					)
					(fill
						(type none)
					)
				)
			)
			(symbol "LED_G_0603_LTST-C190GKT_4_1_1"
				(polyline
					(pts
						(xy 1.778 1.016) (xy 1.778 -1.016)
					)
					(stroke
						(width 0.254)
						(type default)
					)
					(fill
						(type none)
					)
				)
				(polyline
					(pts
						(xy 3.302 1.016) (xy 3.302 -1.016) (xy 1.778 0) (xy 3.302 1.016)
					)
					(stroke
						(width 0.254)
						(type default)
					)
					(fill
						(type outline)
					)
				)
				(polyline
					(pts
						(xy 1.143 2.286) (xy 1.143 1.778) (xy 1.143 2.286) (xy 1.651 2.286) (xy 1.143 2.286) (xy 2.159 1.27)
					)
					(stroke
						(width 0.254)
						(type default)
					)
					(fill
						(type none)
					)
				)
				(polyline
					(pts
						(xy 2.159 2.54) (xy 2.159 2.032) (xy 2.159 2.54) (xy 2.667 2.54) (xy 2.159 2.54) (xy 3.048 1.651)
					)
					(stroke
						(width 0.254)
						(type default)
					)
					(fill
						(type none)
					)
				)
				(pin passive line
					(at 0 0 0)
					(length 0.635)
					(name "C"
						(effects
							(font
								(size 1.27 1.27)
							)
						)
					)
					(number "1"
						(effects
							(font
								(size 1.27 1.27)
							)
						)
					)
				)
				(pin passive line
					(at 5.08 0 180)
					(length 0.635)
					(name "A"
						(effects
							(font
								(size 1.27 1.27)
							)
						)
					)
					(number "2"
						(effects
							(font
								(size 1.27 1.27)
							)
						)
					)
				)
			)
		)
	(symbol "LED_G_0603_LTST-C190GKT_5"
			(pin_numbers hide)
			(pin_names hide)
			(exclude_from_sim no)
			(in_bom yes)
			(on_board yes)
			(property "Reference" "D"
				(at 22.86 -2.54 0)
				(effects
					(font
						(size 1.27 1.27)
						(thickness 0.15)
					)
					(justify left bottom)
				)
			)
			(property "Value" "LED_G_0603_LTST-C190GKT"
				(at 22.86 -7.62 0)
				(effects
					(font
						(size 1.27 1.27)
						(thickness 0.15)
					)
					(justify left bottom)
					(hide yes)
				)
			)
			(property "Footprint" "antmicro-footprints:LED_0603_1608Metric_G"
				(at 22.86 -10.16 0)
				(effects
					(font
						(size 1.27 1.27)
						(thickness 0.15)
					)
					(justify left bottom)
					(hide yes)
				)
			)
			(property "Datasheet" "https://media.digikey.com/pdf/Data%20Sheets/Lite-On%20PDFs/LTST-C190GKT.pdf"
				(at 22.86 -12.7 0)
				(effects
					(font
						(size 1.27 1.27)
						(thickness 0.15)
					)
					(justify left bottom)
					(hide yes)
				)
			)
			(property "Description" "LED, Green, SMD, 0603, 20 mA, 2.1 V, 569 nm"
				(at 0 0 0)
				(effects
					(font
						(size 1.27 1.27)
					)
					(hide yes)
				)
			)
			(property "MPN" "LTST-C190GKT"
				(at 22.86 -15.24 0)
				(effects
					(font
						(size 1.27 1.27)
						(thickness 0.15)
					)
					(justify left bottom)
					(hide yes)
				)
			)
			(property "Manufacturer" "Lite-On"
				(at 22.86 -17.78 0)
				(effects
					(font
						(size 1.27 1.27)
						(thickness 0.15)
					)
					(justify left bottom)
					(hide yes)
				)
			)
			(property "Color" "Green"
				(at 22.86 -5.08 0)
				(effects
					(font
						(size 1.27 1.27)
					)
					(justify left bottom)
				)
			)
			(property "Author" "Antmicro"
				(at 22.86 -20.32 0)
				(effects
					(font
						(size 1.27 1.27)
						(thickness 0.15)
					)
					(justify left bottom)
					(hide yes)
				)
			)
			(property "License" "Apache-2.0"
				(at 22.86 -22.86 0)
				(effects
					(font
						(size 1.27 1.27)
						(thickness 0.15)
					)
					(justify left bottom)
					(hide yes)
				)
			)
			(property "ki_keywords" "SMT, DIODE, SEMICONDUCTOR, LED"
				(at 0 0 0)
				(effects
					(font
						(size 1.27 1.27)
					)
					(hide yes)
				)
			)
			(symbol "LED_G_0603_LTST-C190GKT_5_0_1"
				(polyline
					(pts
						(xy 1.905 0) (xy 0.635 0)
					)
					(stroke
						(width 0)
						(type default)
					)
					(fill
						(type none)
					)
				)
				(polyline
					(pts
						(xy 4.445 0) (xy 3.175 0)
					)
					(stroke
						(width 0)
						(type default)
					)
					(fill
						(type none)
					)
				)
			)
			(symbol "LED_G_0603_LTST-C190GKT_5_1_1"
				(polyline
					(pts
						(xy 1.778 1.016) (xy 1.778 -1.016)
					)
					(stroke
						(width 0.254)
						(type default)
					)
					(fill
						(type none)
					)
				)
				(polyline
					(pts
						(xy 3.302 1.016) (xy 3.302 -1.016) (xy 1.778 0) (xy 3.302 1.016)
					)
					(stroke
						(width 0.254)
						(type default)
					)
					(fill
						(type outline)
					)
				)
				(polyline
					(pts
						(xy 1.143 2.286) (xy 1.143 1.778) (xy 1.143 2.286) (xy 1.651 2.286) (xy 1.143 2.286) (xy 2.159 1.27)
					)
					(stroke
						(width 0.254)
						(type default)
					)
					(fill
						(type none)
					)
				)
				(polyline
					(pts
						(xy 2.159 2.54) (xy 2.159 2.032) (xy 2.159 2.54) (xy 2.667 2.54) (xy 2.159 2.54) (xy 3.048 1.651)
					)
					(stroke
						(width 0.254)
						(type default)
					)
					(fill
						(type none)
					)
				)
				(pin passive line
					(at 0 0 0)
					(length 0.635)
					(name "C"
						(effects
							(font
								(size 1.27 1.27)
							)
						)
					)
					(number "1"
						(effects
							(font
								(size 1.27 1.27)
							)
						)
					)
				)
				(pin passive line
					(at 5.08 0 180)
					(length 0.635)
					(name "A"
						(effects
							(font
								(size 1.27 1.27)
							)
						)
					)
					(number "2"
						(effects
							(font
								(size 1.27 1.27)
							)
						)
					)
				)
			)
		)
	(symbol "R_0R_0402_1"
			(pin_numbers hide)
			(pin_names hide)
			(exclude_from_sim no)
			(in_bom yes)
			(on_board yes)
			(property "Reference" "R"
				(at 20.32 -5.08 0)
				(effects
					(font
						(size 1.27 1.27)
						(thickness 0.15)
					)
					(justify left bottom)
				)
			)
			(property "Value" "R_0R_0402"
				(at 20.32 -12.7 0)
				(effects
					(font
						(size 1.27 1.27)
						(thickness 0.15)
					)
					(justify left bottom)
					(hide yes)
				)
			)
			(property "Footprint" "antmicro-footprints:R_0402_1005Metric"
				(at 20.32 -15.24 0)
				(effects
					(font
						(size 1.27 1.27)
						(thickness 0.15)
					)
					(justify left bottom)
					(hide yes)
				)
			)
			(property "Datasheet" "https://industrial.panasonic.com/cdbs/www-data/pdf/RDA0000/AOA0000C301.pdf"
				(at 20.32 -17.78 0)
				(effects
					(font
						(size 1.27 1.27)
						(thickness 0.15)
					)
					(justify left bottom)
					(hide yes)
				)
			)
			(property "Description" "SMD Chip Resistor, Jumper, 0 ohm, 100 mW, 0402 [1005 Metric], Thick Film, General Purpose"
				(at 0 0 0)
				(effects
					(font
						(size 1.27 1.27)
					)
					(hide yes)
				)
			)
			(property "MPN" "ERJ2GE0R00X"
				(at 20.32 -20.32 0)
				(effects
					(font
						(size 1.27 1.27)
						(thickness 0.15)
					)
					(justify left bottom)
					(hide yes)
				)
			)
			(property "Manufacturer" "Panasonic"
				(at 20.32 -22.86 0)
				(effects
					(font
						(size 1.27 1.27)
						(thickness 0.15)
					)
					(justify left bottom)
					(hide yes)
				)
			)
			(property "License" "Apache-2.0"
				(at 20.32 -25.4 0)
				(effects
					(font
						(size 1.27 1.27)
						(thickness 0.15)
					)
					(justify left bottom)
					(hide yes)
				)
			)
			(property "Author" "Antmicro"
				(at 20.32 -27.94 0)
				(effects
					(font
						(size 1.27 1.27)
						(thickness 0.15)
					)
					(justify left bottom)
					(hide yes)
				)
			)
			(property "Val" "0R"
				(at 20.32 -7.62 0)
				(effects
					(font
						(size 1.27 1.27)
						(thickness 0.15)
					)
					(justify left bottom)
				)
			)
			(property "Tolerance" "~"
				(at 20.32 -10.16 0)
				(effects
					(font
						(size 1.27 1.27)
					)
					(justify left bottom)
					(hide yes)
				)
			)
			(property "Current" "1A"
				(at 20.32 -30.48 0)
				(effects
					(font
						(size 1.27 1.27)
						(thickness 0.15)
					)
					(justify left bottom)
					(hide yes)
				)
			)
			(property "ki_keywords" "0402, SMT, RESISTOR, PASSIVE"
				(at 0 0 0)
				(effects
					(font
						(size 1.27 1.27)
					)
					(hide yes)
				)
			)
			(symbol "R_0R_0402_1_0_1"
				(rectangle
					(start 0.635 0.889)
					(end 4.445 -0.889)
					(stroke
						(width 0.254)
						(type default)
					)
					(fill
						(type none)
					)
				)
			)
			(symbol "R_0R_0402_1_1_1"
				(pin passive line
					(at 0 0 0)
					(length 0.635)
					(name "~"
						(effects
							(font
								(size 1.27 1.27)
							)
						)
					)
					(number "1"
						(effects
							(font
								(size 1.27 1.27)
							)
						)
					)
				)
				(pin passive line
					(at 5.08 0 180)
					(length 0.635)
					(name "~"
						(effects
							(font
								(size 1.27 1.27)
							)
						)
					)
					(number "2"
						(effects
							(font
								(size 1.27 1.27)
							)
						)
					)
				)
			)
		)
	(symbol "R_0R_0402_10"
			(pin_numbers hide)
			(pin_names hide)
			(exclude_from_sim no)
			(in_bom yes)
			(on_board yes)
			(property "Reference" "R"
				(at 20.32 -5.08 0)
				(effects
					(font
						(size 1.27 1.27)
						(thickness 0.15)
					)
					(justify left bottom)
				)
			)
			(property "Value" "R_0R_0402"
				(at 20.32 -12.7 0)
				(effects
					(font
						(size 1.27 1.27)
						(thickness 0.15)
					)
					(justify left bottom)
					(hide yes)
				)
			)
			(property "Footprint" "antmicro-footprints:R_0402_1005Metric"
				(at 20.32 -15.24 0)
				(effects
					(font
						(size 1.27 1.27)
						(thickness 0.15)
					)
					(justify left bottom)
					(hide yes)
				)
			)
			(property "Datasheet" "https://industrial.panasonic.com/cdbs/www-data/pdf/RDA0000/AOA0000C301.pdf"
				(at 20.32 -17.78 0)
				(effects
					(font
						(size 1.27 1.27)
						(thickness 0.15)
					)
					(justify left bottom)
					(hide yes)
				)
			)
			(property "Description" "SMD Chip Resistor, Jumper, 0 ohm, 100 mW, 0402 [1005 Metric], Thick Film, General Purpose"
				(at 0 0 0)
				(effects
					(font
						(size 1.27 1.27)
					)
					(hide yes)
				)
			)
			(property "MPN" "ERJ2GE0R00X"
				(at 20.32 -20.32 0)
				(effects
					(font
						(size 1.27 1.27)
						(thickness 0.15)
					)
					(justify left bottom)
					(hide yes)
				)
			)
			(property "Manufacturer" "Panasonic"
				(at 20.32 -22.86 0)
				(effects
					(font
						(size 1.27 1.27)
						(thickness 0.15)
					)
					(justify left bottom)
					(hide yes)
				)
			)
			(property "License" "Apache-2.0"
				(at 20.32 -25.4 0)
				(effects
					(font
						(size 1.27 1.27)
						(thickness 0.15)
					)
					(justify left bottom)
					(hide yes)
				)
			)
			(property "Author" "Antmicro"
				(at 20.32 -27.94 0)
				(effects
					(font
						(size 1.27 1.27)
						(thickness 0.15)
					)
					(justify left bottom)
					(hide yes)
				)
			)
			(property "Val" "0R"
				(at 20.32 -7.62 0)
				(effects
					(font
						(size 1.27 1.27)
						(thickness 0.15)
					)
					(justify left bottom)
				)
			)
			(property "Tolerance" "~"
				(at 20.32 -10.16 0)
				(effects
					(font
						(size 1.27 1.27)
					)
					(justify left bottom)
					(hide yes)
				)
			)
			(property "Current" "1A"
				(at 20.32 -30.48 0)
				(effects
					(font
						(size 1.27 1.27)
						(thickness 0.15)
					)
					(justify left bottom)
					(hide yes)
				)
			)
			(property "ki_keywords" "0402, SMT, RESISTOR, PASSIVE"
				(at 0 0 0)
				(effects
					(font
						(size 1.27 1.27)
					)
					(hide yes)
				)
			)
			(symbol "R_0R_0402_10_0_1"
				(rectangle
					(start 0.635 0.889)
					(end 4.445 -0.889)
					(stroke
						(width 0.254)
						(type default)
					)
					(fill
						(type none)
					)
				)
			)
			(symbol "R_0R_0402_10_1_1"
				(pin passive line
					(at 0 0 0)
					(length 0.635)
					(name "~"
						(effects
							(font
								(size 1.27 1.27)
							)
						)
					)
					(number "1"
						(effects
							(font
								(size 1.27 1.27)
							)
						)
					)
				)
				(pin passive line
					(at 5.08 0 180)
					(length 0.635)
					(name "~"
						(effects
							(font
								(size 1.27 1.27)
							)
						)
					)
					(number "2"
						(effects
							(font
								(size 1.27 1.27)
							)
						)
					)
				)
			)
		)
	(symbol "R_0R_0402_11"
			(pin_numbers hide)
			(pin_names hide)
			(exclude_from_sim no)
			(in_bom yes)
			(on_board yes)
			(property "Reference" "R"
				(at 20.32 -5.08 0)
				(effects
					(font
						(size 1.27 1.27)
						(thickness 0.15)
					)
					(justify left bottom)
				)
			)
			(property "Value" "R_0R_0402"
				(at 20.32 -12.7 0)
				(effects
					(font
						(size 1.27 1.27)
						(thickness 0.15)
					)
					(justify left bottom)
					(hide yes)
				)
			)
			(property "Footprint" "antmicro-footprints:R_0402_1005Metric"
				(at 20.32 -15.24 0)
				(effects
					(font
						(size 1.27 1.27)
						(thickness 0.15)
					)
					(justify left bottom)
					(hide yes)
				)
			)
			(property "Datasheet" "https://industrial.panasonic.com/cdbs/www-data/pdf/RDA0000/AOA0000C301.pdf"
				(at 20.32 -17.78 0)
				(effects
					(font
						(size 1.27 1.27)
						(thickness 0.15)
					)
					(justify left bottom)
					(hide yes)
				)
			)
			(property "Description" "SMD Chip Resistor, Jumper, 0 ohm, 100 mW, 0402 [1005 Metric], Thick Film, General Purpose"
				(at 0 0 0)
				(effects
					(font
						(size 1.27 1.27)
					)
					(hide yes)
				)
			)
			(property "MPN" "ERJ2GE0R00X"
				(at 20.32 -20.32 0)
				(effects
					(font
						(size 1.27 1.27)
						(thickness 0.15)
					)
					(justify left bottom)
					(hide yes)
				)
			)
			(property "Manufacturer" "Panasonic"
				(at 20.32 -22.86 0)
				(effects
					(font
						(size 1.27 1.27)
						(thickness 0.15)
					)
					(justify left bottom)
					(hide yes)
				)
			)
			(property "License" "Apache-2.0"
				(at 20.32 -25.4 0)
				(effects
					(font
						(size 1.27 1.27)
						(thickness 0.15)
					)
					(justify left bottom)
					(hide yes)
				)
			)
			(property "Author" "Antmicro"
				(at 20.32 -27.94 0)
				(effects
					(font
						(size 1.27 1.27)
						(thickness 0.15)
					)
					(justify left bottom)
					(hide yes)
				)
			)
			(property "Val" "0R"
				(at 20.32 -7.62 0)
				(effects
					(font
						(size 1.27 1.27)
						(thickness 0.15)
					)
					(justify left bottom)
				)
			)
			(property "Tolerance" "~"
				(at 20.32 -10.16 0)
				(effects
					(font
						(size 1.27 1.27)
					)
					(justify left bottom)
					(hide yes)
				)
			)
			(property "Current" "1A"
				(at 20.32 -30.48 0)
				(effects
					(font
						(size 1.27 1.27)
						(thickness 0.15)
					)
					(justify left bottom)
					(hide yes)
				)
			)
			(property "ki_keywords" "0402, SMT, RESISTOR, PASSIVE"
				(at 0 0 0)
				(effects
					(font
						(size 1.27 1.27)
					)
					(hide yes)
				)
			)
			(symbol "R_0R_0402_11_0_1"
				(rectangle
					(start 0.635 0.889)
					(end 4.445 -0.889)
					(stroke
						(width 0.254)
						(type default)
					)
					(fill
						(type none)
					)
				)
			)
			(symbol "R_0R_0402_11_1_1"
				(pin passive line
					(at 0 0 0)
					(length 0.635)
					(name "~"
						(effects
							(font
								(size 1.27 1.27)
							)
						)
					)
					(number "1"
						(effects
							(font
								(size 1.27 1.27)
							)
						)
					)
				)
				(pin passive line
					(at 5.08 0 180)
					(length 0.635)
					(name "~"
						(effects
							(font
								(size 1.27 1.27)
							)
						)
					)
					(number "2"
						(effects
							(font
								(size 1.27 1.27)
							)
						)
					)
				)
			)
		)
	(symbol "R_0R_0402_2"
			(pin_numbers hide)
			(pin_names hide)
			(exclude_from_sim no)
			(in_bom yes)
			(on_board yes)
			(property "Reference" "R"
				(at 20.32 -5.08 0)
				(effects
					(font
						(size 1.27 1.27)
						(thickness 0.15)
					)
					(justify left bottom)
				)
			)
			(property "Value" "R_0R_0402"
				(at 20.32 -12.7 0)
				(effects
					(font
						(size 1.27 1.27)
						(thickness 0.15)
					)
					(justify left bottom)
					(hide yes)
				)
			)
			(property "Footprint" "antmicro-footprints:R_0402_1005Metric"
				(at 20.32 -15.24 0)
				(effects
					(font
						(size 1.27 1.27)
						(thickness 0.15)
					)
					(justify left bottom)
					(hide yes)
				)
			)
			(property "Datasheet" "https://industrial.panasonic.com/cdbs/www-data/pdf/RDA0000/AOA0000C301.pdf"
				(at 20.32 -17.78 0)
				(effects
					(font
						(size 1.27 1.27)
						(thickness 0.15)
					)
					(justify left bottom)
					(hide yes)
				)
			)
			(property "Description" "SMD Chip Resistor, Jumper, 0 ohm, 100 mW, 0402 [1005 Metric], Thick Film, General Purpose"
				(at 0 0 0)
				(effects
					(font
						(size 1.27 1.27)
					)
					(hide yes)
				)
			)
			(property "MPN" "ERJ2GE0R00X"
				(at 20.32 -20.32 0)
				(effects
					(font
						(size 1.27 1.27)
						(thickness 0.15)
					)
					(justify left bottom)
					(hide yes)
				)
			)
			(property "Manufacturer" "Panasonic"
				(at 20.32 -22.86 0)
				(effects
					(font
						(size 1.27 1.27)
						(thickness 0.15)
					)
					(justify left bottom)
					(hide yes)
				)
			)
			(property "License" "Apache-2.0"
				(at 20.32 -25.4 0)
				(effects
					(font
						(size 1.27 1.27)
						(thickness 0.15)
					)
					(justify left bottom)
					(hide yes)
				)
			)
			(property "Author" "Antmicro"
				(at 20.32 -27.94 0)
				(effects
					(font
						(size 1.27 1.27)
						(thickness 0.15)
					)
					(justify left bottom)
					(hide yes)
				)
			)
			(property "Val" "0R"
				(at 20.32 -7.62 0)
				(effects
					(font
						(size 1.27 1.27)
						(thickness 0.15)
					)
					(justify left bottom)
				)
			)
			(property "Tolerance" "~"
				(at 20.32 -10.16 0)
				(effects
					(font
						(size 1.27 1.27)
					)
					(justify left bottom)
					(hide yes)
				)
			)
			(property "Current" "1A"
				(at 20.32 -30.48 0)
				(effects
					(font
						(size 1.27 1.27)
						(thickness 0.15)
					)
					(justify left bottom)
					(hide yes)
				)
			)
			(property "ki_keywords" "0402, SMT, RESISTOR, PASSIVE"
				(at 0 0 0)
				(effects
					(font
						(size 1.27 1.27)
					)
					(hide yes)
				)
			)
			(symbol "R_0R_0402_2_0_1"
				(rectangle
					(start 0.635 0.889)
					(end 4.445 -0.889)
					(stroke
						(width 0.254)
						(type default)
					)
					(fill
						(type none)
					)
				)
			)
			(symbol "R_0R_0402_2_1_1"
				(pin passive line
					(at 0 0 0)
					(length 0.635)
					(name "~"
						(effects
							(font
								(size 1.27 1.27)
							)
						)
					)
					(number "1"
						(effects
							(font
								(size 1.27 1.27)
							)
						)
					)
				)
				(pin passive line
					(at 5.08 0 180)
					(length 0.635)
					(name "~"
						(effects
							(font
								(size 1.27 1.27)
							)
						)
					)
					(number "2"
						(effects
							(font
								(size 1.27 1.27)
							)
						)
					)
				)
			)
		)
	(symbol "R_0R_0402_3"
			(pin_numbers hide)
			(pin_names hide)
			(exclude_from_sim no)
			(in_bom yes)
			(on_board yes)
			(property "Reference" "R"
				(at 20.32 -5.08 0)
				(effects
					(font
						(size 1.27 1.27)
						(thickness 0.15)
					)
					(justify left bottom)
				)
			)
			(property "Value" "R_0R_0402"
				(at 20.32 -12.7 0)
				(effects
					(font
						(size 1.27 1.27)
						(thickness 0.15)
					)
					(justify left bottom)
					(hide yes)
				)
			)
			(property "Footprint" "antmicro-footprints:R_0402_1005Metric"
				(at 20.32 -15.24 0)
				(effects
					(font
						(size 1.27 1.27)
						(thickness 0.15)
					)
					(justify left bottom)
					(hide yes)
				)
			)
			(property "Datasheet" "https://industrial.panasonic.com/cdbs/www-data/pdf/RDA0000/AOA0000C301.pdf"
				(at 20.32 -17.78 0)
				(effects
					(font
						(size 1.27 1.27)
						(thickness 0.15)
					)
					(justify left bottom)
					(hide yes)
				)
			)
			(property "Description" "SMD Chip Resistor, Jumper, 0 ohm, 100 mW, 0402 [1005 Metric], Thick Film, General Purpose"
				(at 0 0 0)
				(effects
					(font
						(size 1.27 1.27)
					)
					(hide yes)
				)
			)
			(property "MPN" "ERJ2GE0R00X"
				(at 20.32 -20.32 0)
				(effects
					(font
						(size 1.27 1.27)
						(thickness 0.15)
					)
					(justify left bottom)
					(hide yes)
				)
			)
			(property "Manufacturer" "Panasonic"
				(at 20.32 -22.86 0)
				(effects
					(font
						(size 1.27 1.27)
						(thickness 0.15)
					)
					(justify left bottom)
					(hide yes)
				)
			)
			(property "License" "Apache-2.0"
				(at 20.32 -25.4 0)
				(effects
					(font
						(size 1.27 1.27)
						(thickness 0.15)
					)
					(justify left bottom)
					(hide yes)
				)
			)
			(property "Author" "Antmicro"
				(at 20.32 -27.94 0)
				(effects
					(font
						(size 1.27 1.27)
						(thickness 0.15)
					)
					(justify left bottom)
					(hide yes)
				)
			)
			(property "Val" "0R"
				(at 20.32 -7.62 0)
				(effects
					(font
						(size 1.27 1.27)
						(thickness 0.15)
					)
					(justify left bottom)
				)
			)
			(property "Tolerance" "~"
				(at 20.32 -10.16 0)
				(effects
					(font
						(size 1.27 1.27)
					)
					(justify left bottom)
					(hide yes)
				)
			)
			(property "Current" "1A"
				(at 20.32 -30.48 0)
				(effects
					(font
						(size 1.27 1.27)
						(thickness 0.15)
					)
					(justify left bottom)
					(hide yes)
				)
			)
			(property "ki_keywords" "0402, SMT, RESISTOR, PASSIVE"
				(at 0 0 0)
				(effects
					(font
						(size 1.27 1.27)
					)
					(hide yes)
				)
			)
			(symbol "R_0R_0402_3_0_1"
				(rectangle
					(start 0.635 0.889)
					(end 4.445 -0.889)
					(stroke
						(width 0.254)
						(type default)
					)
					(fill
						(type none)
					)
				)
			)
			(symbol "R_0R_0402_3_1_1"
				(pin passive line
					(at 0 0 0)
					(length 0.635)
					(name "~"
						(effects
							(font
								(size 1.27 1.27)
							)
						)
					)
					(number "1"
						(effects
							(font
								(size 1.27 1.27)
							)
						)
					)
				)
				(pin passive line
					(at 5.08 0 180)
					(length 0.635)
					(name "~"
						(effects
							(font
								(size 1.27 1.27)
							)
						)
					)
					(number "2"
						(effects
							(font
								(size 1.27 1.27)
							)
						)
					)
				)
			)
		)
	(symbol "R_0R_0402_4"
			(pin_numbers hide)
			(pin_names hide)
			(exclude_from_sim no)
			(in_bom yes)
			(on_board yes)
			(property "Reference" "R"
				(at 20.32 -5.08 0)
				(effects
					(font
						(size 1.27 1.27)
						(thickness 0.15)
					)
					(justify left bottom)
				)
			)
			(property "Value" "R_0R_0402"
				(at 20.32 -12.7 0)
				(effects
					(font
						(size 1.27 1.27)
						(thickness 0.15)
					)
					(justify left bottom)
					(hide yes)
				)
			)
			(property "Footprint" "antmicro-footprints:R_0402_1005Metric"
				(at 20.32 -15.24 0)
				(effects
					(font
						(size 1.27 1.27)
						(thickness 0.15)
					)
					(justify left bottom)
					(hide yes)
				)
			)
			(property "Datasheet" "https://industrial.panasonic.com/cdbs/www-data/pdf/RDA0000/AOA0000C301.pdf"
				(at 20.32 -17.78 0)
				(effects
					(font
						(size 1.27 1.27)
						(thickness 0.15)
					)
					(justify left bottom)
					(hide yes)
				)
			)
			(property "Description" "SMD Chip Resistor, Jumper, 0 ohm, 100 mW, 0402 [1005 Metric], Thick Film, General Purpose"
				(at 0 0 0)
				(effects
					(font
						(size 1.27 1.27)
					)
					(hide yes)
				)
			)
			(property "MPN" "ERJ2GE0R00X"
				(at 20.32 -20.32 0)
				(effects
					(font
						(size 1.27 1.27)
						(thickness 0.15)
					)
					(justify left bottom)
					(hide yes)
				)
			)
			(property "Manufacturer" "Panasonic"
				(at 20.32 -22.86 0)
				(effects
					(font
						(size 1.27 1.27)
						(thickness 0.15)
					)
					(justify left bottom)
					(hide yes)
				)
			)
			(property "License" "Apache-2.0"
				(at 20.32 -25.4 0)
				(effects
					(font
						(size 1.27 1.27)
						(thickness 0.15)
					)
					(justify left bottom)
					(hide yes)
				)
			)
			(property "Author" "Antmicro"
				(at 20.32 -27.94 0)
				(effects
					(font
						(size 1.27 1.27)
						(thickness 0.15)
					)
					(justify left bottom)
					(hide yes)
				)
			)
			(property "Val" "0R"
				(at 20.32 -7.62 0)
				(effects
					(font
						(size 1.27 1.27)
						(thickness 0.15)
					)
					(justify left bottom)
				)
			)
			(property "Tolerance" "~"
				(at 20.32 -10.16 0)
				(effects
					(font
						(size 1.27 1.27)
					)
					(justify left bottom)
					(hide yes)
				)
			)
			(property "Current" "1A"
				(at 20.32 -30.48 0)
				(effects
					(font
						(size 1.27 1.27)
						(thickness 0.15)
					)
					(justify left bottom)
					(hide yes)
				)
			)
			(property "ki_keywords" "0402, SMT, RESISTOR, PASSIVE"
				(at 0 0 0)
				(effects
					(font
						(size 1.27 1.27)
					)
					(hide yes)
				)
			)
			(symbol "R_0R_0402_4_0_1"
				(rectangle
					(start 0.635 0.889)
					(end 4.445 -0.889)
					(stroke
						(width 0.254)
						(type default)
					)
					(fill
						(type none)
					)
				)
			)
			(symbol "R_0R_0402_4_1_1"
				(pin passive line
					(at 0 0 0)
					(length 0.635)
					(name "~"
						(effects
							(font
								(size 1.27 1.27)
							)
						)
					)
					(number "1"
						(effects
							(font
								(size 1.27 1.27)
							)
						)
					)
				)
				(pin passive line
					(at 5.08 0 180)
					(length 0.635)
					(name "~"
						(effects
							(font
								(size 1.27 1.27)
							)
						)
					)
					(number "2"
						(effects
							(font
								(size 1.27 1.27)
							)
						)
					)
				)
			)
		)
	(symbol "R_0R_0402_5"
			(pin_numbers hide)
			(pin_names hide)
			(exclude_from_sim no)
			(in_bom yes)
			(on_board yes)
			(property "Reference" "R"
				(at 20.32 -5.08 0)
				(effects
					(font
						(size 1.27 1.27)
						(thickness 0.15)
					)
					(justify left bottom)
				)
			)
			(property "Value" "R_0R_0402"
				(at 20.32 -12.7 0)
				(effects
					(font
						(size 1.27 1.27)
						(thickness 0.15)
					)
					(justify left bottom)
					(hide yes)
				)
			)
			(property "Footprint" "antmicro-footprints:R_0402_1005Metric"
				(at 20.32 -15.24 0)
				(effects
					(font
						(size 1.27 1.27)
						(thickness 0.15)
					)
					(justify left bottom)
					(hide yes)
				)
			)
			(property "Datasheet" "https://industrial.panasonic.com/cdbs/www-data/pdf/RDA0000/AOA0000C301.pdf"
				(at 20.32 -17.78 0)
				(effects
					(font
						(size 1.27 1.27)
						(thickness 0.15)
					)
					(justify left bottom)
					(hide yes)
				)
			)
			(property "Description" "SMD Chip Resistor, Jumper, 0 ohm, 100 mW, 0402 [1005 Metric], Thick Film, General Purpose"
				(at 0 0 0)
				(effects
					(font
						(size 1.27 1.27)
					)
					(hide yes)
				)
			)
			(property "MPN" "ERJ2GE0R00X"
				(at 20.32 -20.32 0)
				(effects
					(font
						(size 1.27 1.27)
						(thickness 0.15)
					)
					(justify left bottom)
					(hide yes)
				)
			)
			(property "Manufacturer" "Panasonic"
				(at 20.32 -22.86 0)
				(effects
					(font
						(size 1.27 1.27)
						(thickness 0.15)
					)
					(justify left bottom)
					(hide yes)
				)
			)
			(property "License" "Apache-2.0"
				(at 20.32 -25.4 0)
				(effects
					(font
						(size 1.27 1.27)
						(thickness 0.15)
					)
					(justify left bottom)
					(hide yes)
				)
			)
			(property "Author" "Antmicro"
				(at 20.32 -27.94 0)
				(effects
					(font
						(size 1.27 1.27)
						(thickness 0.15)
					)
					(justify left bottom)
					(hide yes)
				)
			)
			(property "Val" "0R"
				(at 20.32 -7.62 0)
				(effects
					(font
						(size 1.27 1.27)
						(thickness 0.15)
					)
					(justify left bottom)
				)
			)
			(property "Tolerance" "~"
				(at 20.32 -10.16 0)
				(effects
					(font
						(size 1.27 1.27)
					)
					(justify left bottom)
					(hide yes)
				)
			)
			(property "Current" "1A"
				(at 20.32 -30.48 0)
				(effects
					(font
						(size 1.27 1.27)
						(thickness 0.15)
					)
					(justify left bottom)
					(hide yes)
				)
			)
			(property "ki_keywords" "0402, SMT, RESISTOR, PASSIVE"
				(at 0 0 0)
				(effects
					(font
						(size 1.27 1.27)
					)
					(hide yes)
				)
			)
			(symbol "R_0R_0402_5_0_1"
				(rectangle
					(start 0.635 0.889)
					(end 4.445 -0.889)
					(stroke
						(width 0.254)
						(type default)
					)
					(fill
						(type none)
					)
				)
			)
			(symbol "R_0R_0402_5_1_1"
				(pin passive line
					(at 0 0 0)
					(length 0.635)
					(name "~"
						(effects
							(font
								(size 1.27 1.27)
							)
						)
					)
					(number "1"
						(effects
							(font
								(size 1.27 1.27)
							)
						)
					)
				)
				(pin passive line
					(at 5.08 0 180)
					(length 0.635)
					(name "~"
						(effects
							(font
								(size 1.27 1.27)
							)
						)
					)
					(number "2"
						(effects
							(font
								(size 1.27 1.27)
							)
						)
					)
				)
			)
		)
	(symbol "R_0R_0402_6"
			(pin_numbers hide)
			(pin_names hide)
			(exclude_from_sim no)
			(in_bom yes)
			(on_board yes)
			(property "Reference" "R"
				(at 20.32 -5.08 0)
				(effects
					(font
						(size 1.27 1.27)
						(thickness 0.15)
					)
					(justify left bottom)
				)
			)
			(property "Value" "R_0R_0402"
				(at 20.32 -12.7 0)
				(effects
					(font
						(size 1.27 1.27)
						(thickness 0.15)
					)
					(justify left bottom)
					(hide yes)
				)
			)
			(property "Footprint" "antmicro-footprints:R_0402_1005Metric"
				(at 20.32 -15.24 0)
				(effects
					(font
						(size 1.27 1.27)
						(thickness 0.15)
					)
					(justify left bottom)
					(hide yes)
				)
			)
			(property "Datasheet" "https://industrial.panasonic.com/cdbs/www-data/pdf/RDA0000/AOA0000C301.pdf"
				(at 20.32 -17.78 0)
				(effects
					(font
						(size 1.27 1.27)
						(thickness 0.15)
					)
					(justify left bottom)
					(hide yes)
				)
			)
			(property "Description" "SMD Chip Resistor, Jumper, 0 ohm, 100 mW, 0402 [1005 Metric], Thick Film, General Purpose"
				(at 0 0 0)
				(effects
					(font
						(size 1.27 1.27)
					)
					(hide yes)
				)
			)
			(property "MPN" "ERJ2GE0R00X"
				(at 20.32 -20.32 0)
				(effects
					(font
						(size 1.27 1.27)
						(thickness 0.15)
					)
					(justify left bottom)
					(hide yes)
				)
			)
			(property "Manufacturer" "Panasonic"
				(at 20.32 -22.86 0)
				(effects
					(font
						(size 1.27 1.27)
						(thickness 0.15)
					)
					(justify left bottom)
					(hide yes)
				)
			)
			(property "License" "Apache-2.0"
				(at 20.32 -25.4 0)
				(effects
					(font
						(size 1.27 1.27)
						(thickness 0.15)
					)
					(justify left bottom)
					(hide yes)
				)
			)
			(property "Author" "Antmicro"
				(at 20.32 -27.94 0)
				(effects
					(font
						(size 1.27 1.27)
						(thickness 0.15)
					)
					(justify left bottom)
					(hide yes)
				)
			)
			(property "Val" "0R"
				(at 20.32 -7.62 0)
				(effects
					(font
						(size 1.27 1.27)
						(thickness 0.15)
					)
					(justify left bottom)
				)
			)
			(property "Tolerance" "~"
				(at 20.32 -10.16 0)
				(effects
					(font
						(size 1.27 1.27)
					)
					(justify left bottom)
					(hide yes)
				)
			)
			(property "Current" "1A"
				(at 20.32 -30.48 0)
				(effects
					(font
						(size 1.27 1.27)
						(thickness 0.15)
					)
					(justify left bottom)
					(hide yes)
				)
			)
			(property "ki_keywords" "0402, SMT, RESISTOR, PASSIVE"
				(at 0 0 0)
				(effects
					(font
						(size 1.27 1.27)
					)
					(hide yes)
				)
			)
			(symbol "R_0R_0402_6_0_1"
				(rectangle
					(start 0.635 0.889)
					(end 4.445 -0.889)
					(stroke
						(width 0.254)
						(type default)
					)
					(fill
						(type none)
					)
				)
			)
			(symbol "R_0R_0402_6_1_1"
				(pin passive line
					(at 0 0 0)
					(length 0.635)
					(name "~"
						(effects
							(font
								(size 1.27 1.27)
							)
						)
					)
					(number "1"
						(effects
							(font
								(size 1.27 1.27)
							)
						)
					)
				)
				(pin passive line
					(at 5.08 0 180)
					(length 0.635)
					(name "~"
						(effects
							(font
								(size 1.27 1.27)
							)
						)
					)
					(number "2"
						(effects
							(font
								(size 1.27 1.27)
							)
						)
					)
				)
			)
		)
	(symbol "R_0R_0402_7"
			(pin_numbers hide)
			(pin_names hide)
			(exclude_from_sim no)
			(in_bom yes)
			(on_board yes)
			(property "Reference" "R"
				(at 20.32 -5.08 0)
				(effects
					(font
						(size 1.27 1.27)
						(thickness 0.15)
					)
					(justify left bottom)
				)
			)
			(property "Value" "R_0R_0402"
				(at 20.32 -12.7 0)
				(effects
					(font
						(size 1.27 1.27)
						(thickness 0.15)
					)
					(justify left bottom)
					(hide yes)
				)
			)
			(property "Footprint" "antmicro-footprints:R_0402_1005Metric"
				(at 20.32 -15.24 0)
				(effects
					(font
						(size 1.27 1.27)
						(thickness 0.15)
					)
					(justify left bottom)
					(hide yes)
				)
			)
			(property "Datasheet" "https://industrial.panasonic.com/cdbs/www-data/pdf/RDA0000/AOA0000C301.pdf"
				(at 20.32 -17.78 0)
				(effects
					(font
						(size 1.27 1.27)
						(thickness 0.15)
					)
					(justify left bottom)
					(hide yes)
				)
			)
			(property "Description" "SMD Chip Resistor, Jumper, 0 ohm, 100 mW, 0402 [1005 Metric], Thick Film, General Purpose"
				(at 0 0 0)
				(effects
					(font
						(size 1.27 1.27)
					)
					(hide yes)
				)
			)
			(property "MPN" "ERJ2GE0R00X"
				(at 20.32 -20.32 0)
				(effects
					(font
						(size 1.27 1.27)
						(thickness 0.15)
					)
					(justify left bottom)
					(hide yes)
				)
			)
			(property "Manufacturer" "Panasonic"
				(at 20.32 -22.86 0)
				(effects
					(font
						(size 1.27 1.27)
						(thickness 0.15)
					)
					(justify left bottom)
					(hide yes)
				)
			)
			(property "License" "Apache-2.0"
				(at 20.32 -25.4 0)
				(effects
					(font
						(size 1.27 1.27)
						(thickness 0.15)
					)
					(justify left bottom)
					(hide yes)
				)
			)
			(property "Author" "Antmicro"
				(at 20.32 -27.94 0)
				(effects
					(font
						(size 1.27 1.27)
						(thickness 0.15)
					)
					(justify left bottom)
					(hide yes)
				)
			)
			(property "Val" "0R"
				(at 20.32 -7.62 0)
				(effects
					(font
						(size 1.27 1.27)
						(thickness 0.15)
					)
					(justify left bottom)
				)
			)
			(property "Tolerance" "~"
				(at 20.32 -10.16 0)
				(effects
					(font
						(size 1.27 1.27)
					)
					(justify left bottom)
					(hide yes)
				)
			)
			(property "Current" "1A"
				(at 20.32 -30.48 0)
				(effects
					(font
						(size 1.27 1.27)
						(thickness 0.15)
					)
					(justify left bottom)
					(hide yes)
				)
			)
			(property "ki_keywords" "0402, SMT, RESISTOR, PASSIVE"
				(at 0 0 0)
				(effects
					(font
						(size 1.27 1.27)
					)
					(hide yes)
				)
			)
			(symbol "R_0R_0402_7_0_1"
				(rectangle
					(start 0.635 0.889)
					(end 4.445 -0.889)
					(stroke
						(width 0.254)
						(type default)
					)
					(fill
						(type none)
					)
				)
			)
			(symbol "R_0R_0402_7_1_1"
				(pin passive line
					(at 0 0 0)
					(length 0.635)
					(name "~"
						(effects
							(font
								(size 1.27 1.27)
							)
						)
					)
					(number "1"
						(effects
							(font
								(size 1.27 1.27)
							)
						)
					)
				)
				(pin passive line
					(at 5.08 0 180)
					(length 0.635)
					(name "~"
						(effects
							(font
								(size 1.27 1.27)
							)
						)
					)
					(number "2"
						(effects
							(font
								(size 1.27 1.27)
							)
						)
					)
				)
			)
		)
	(symbol "R_0R_0402_8"
			(pin_numbers hide)
			(pin_names hide)
			(exclude_from_sim no)
			(in_bom yes)
			(on_board yes)
			(property "Reference" "R"
				(at 20.32 -5.08 0)
				(effects
					(font
						(size 1.27 1.27)
						(thickness 0.15)
					)
					(justify left bottom)
				)
			)
			(property "Value" "R_0R_0402"
				(at 20.32 -12.7 0)
				(effects
					(font
						(size 1.27 1.27)
						(thickness 0.15)
					)
					(justify left bottom)
					(hide yes)
				)
			)
			(property "Footprint" "antmicro-footprints:R_0402_1005Metric"
				(at 20.32 -15.24 0)
				(effects
					(font
						(size 1.27 1.27)
						(thickness 0.15)
					)
					(justify left bottom)
					(hide yes)
				)
			)
			(property "Datasheet" "https://industrial.panasonic.com/cdbs/www-data/pdf/RDA0000/AOA0000C301.pdf"
				(at 20.32 -17.78 0)
				(effects
					(font
						(size 1.27 1.27)
						(thickness 0.15)
					)
					(justify left bottom)
					(hide yes)
				)
			)
			(property "Description" "SMD Chip Resistor, Jumper, 0 ohm, 100 mW, 0402 [1005 Metric], Thick Film, General Purpose"
				(at 0 0 0)
				(effects
					(font
						(size 1.27 1.27)
					)
					(hide yes)
				)
			)
			(property "MPN" "ERJ2GE0R00X"
				(at 20.32 -20.32 0)
				(effects
					(font
						(size 1.27 1.27)
						(thickness 0.15)
					)
					(justify left bottom)
					(hide yes)
				)
			)
			(property "Manufacturer" "Panasonic"
				(at 20.32 -22.86 0)
				(effects
					(font
						(size 1.27 1.27)
						(thickness 0.15)
					)
					(justify left bottom)
					(hide yes)
				)
			)
			(property "License" "Apache-2.0"
				(at 20.32 -25.4 0)
				(effects
					(font
						(size 1.27 1.27)
						(thickness 0.15)
					)
					(justify left bottom)
					(hide yes)
				)
			)
			(property "Author" "Antmicro"
				(at 20.32 -27.94 0)
				(effects
					(font
						(size 1.27 1.27)
						(thickness 0.15)
					)
					(justify left bottom)
					(hide yes)
				)
			)
			(property "Val" "0R"
				(at 20.32 -7.62 0)
				(effects
					(font
						(size 1.27 1.27)
						(thickness 0.15)
					)
					(justify left bottom)
				)
			)
			(property "Tolerance" "~"
				(at 20.32 -10.16 0)
				(effects
					(font
						(size 1.27 1.27)
					)
					(justify left bottom)
					(hide yes)
				)
			)
			(property "Current" "1A"
				(at 20.32 -30.48 0)
				(effects
					(font
						(size 1.27 1.27)
						(thickness 0.15)
					)
					(justify left bottom)
					(hide yes)
				)
			)
			(property "ki_keywords" "0402, SMT, RESISTOR, PASSIVE"
				(at 0 0 0)
				(effects
					(font
						(size 1.27 1.27)
					)
					(hide yes)
				)
			)
			(symbol "R_0R_0402_8_0_1"
				(rectangle
					(start 0.635 0.889)
					(end 4.445 -0.889)
					(stroke
						(width 0.254)
						(type default)
					)
					(fill
						(type none)
					)
				)
			)
			(symbol "R_0R_0402_8_1_1"
				(pin passive line
					(at 0 0 0)
					(length 0.635)
					(name "~"
						(effects
							(font
								(size 1.27 1.27)
							)
						)
					)
					(number "1"
						(effects
							(font
								(size 1.27 1.27)
							)
						)
					)
				)
				(pin passive line
					(at 5.08 0 180)
					(length 0.635)
					(name "~"
						(effects
							(font
								(size 1.27 1.27)
							)
						)
					)
					(number "2"
						(effects
							(font
								(size 1.27 1.27)
							)
						)
					)
				)
			)
		)
	(symbol "R_0R_0402_9"
			(pin_numbers hide)
			(pin_names hide)
			(exclude_from_sim no)
			(in_bom yes)
			(on_board yes)
			(property "Reference" "R"
				(at 20.32 -5.08 0)
				(effects
					(font
						(size 1.27 1.27)
						(thickness 0.15)
					)
					(justify left bottom)
				)
			)
			(property "Value" "R_0R_0402"
				(at 20.32 -12.7 0)
				(effects
					(font
						(size 1.27 1.27)
						(thickness 0.15)
					)
					(justify left bottom)
					(hide yes)
				)
			)
			(property "Footprint" "antmicro-footprints:R_0402_1005Metric"
				(at 20.32 -15.24 0)
				(effects
					(font
						(size 1.27 1.27)
						(thickness 0.15)
					)
					(justify left bottom)
					(hide yes)
				)
			)
			(property "Datasheet" "https://industrial.panasonic.com/cdbs/www-data/pdf/RDA0000/AOA0000C301.pdf"
				(at 20.32 -17.78 0)
				(effects
					(font
						(size 1.27 1.27)
						(thickness 0.15)
					)
					(justify left bottom)
					(hide yes)
				)
			)
			(property "Description" "SMD Chip Resistor, Jumper, 0 ohm, 100 mW, 0402 [1005 Metric], Thick Film, General Purpose"
				(at 0 0 0)
				(effects
					(font
						(size 1.27 1.27)
					)
					(hide yes)
				)
			)
			(property "MPN" "ERJ2GE0R00X"
				(at 20.32 -20.32 0)
				(effects
					(font
						(size 1.27 1.27)
						(thickness 0.15)
					)
					(justify left bottom)
					(hide yes)
				)
			)
			(property "Manufacturer" "Panasonic"
				(at 20.32 -22.86 0)
				(effects
					(font
						(size 1.27 1.27)
						(thickness 0.15)
					)
					(justify left bottom)
					(hide yes)
				)
			)
			(property "License" "Apache-2.0"
				(at 20.32 -25.4 0)
				(effects
					(font
						(size 1.27 1.27)
						(thickness 0.15)
					)
					(justify left bottom)
					(hide yes)
				)
			)
			(property "Author" "Antmicro"
				(at 20.32 -27.94 0)
				(effects
					(font
						(size 1.27 1.27)
						(thickness 0.15)
					)
					(justify left bottom)
					(hide yes)
				)
			)
			(property "Val" "0R"
				(at 20.32 -7.62 0)
				(effects
					(font
						(size 1.27 1.27)
						(thickness 0.15)
					)
					(justify left bottom)
				)
			)
			(property "Tolerance" "~"
				(at 20.32 -10.16 0)
				(effects
					(font
						(size 1.27 1.27)
					)
					(justify left bottom)
					(hide yes)
				)
			)
			(property "Current" "1A"
				(at 20.32 -30.48 0)
				(effects
					(font
						(size 1.27 1.27)
						(thickness 0.15)
					)
					(justify left bottom)
					(hide yes)
				)
			)
			(property "ki_keywords" "0402, SMT, RESISTOR, PASSIVE"
				(at 0 0 0)
				(effects
					(font
						(size 1.27 1.27)
					)
					(hide yes)
				)
			)
			(symbol "R_0R_0402_9_0_1"
				(rectangle
					(start 0.635 0.889)
					(end 4.445 -0.889)
					(stroke
						(width 0.254)
						(type default)
					)
					(fill
						(type none)
					)
				)
			)
			(symbol "R_0R_0402_9_1_1"
				(pin passive line
					(at 0 0 0)
					(length 0.635)
					(name "~"
						(effects
							(font
								(size 1.27 1.27)
							)
						)
					)
					(number "1"
						(effects
							(font
								(size 1.27 1.27)
							)
						)
					)
				)
				(pin passive line
					(at 5.08 0 180)
					(length 0.635)
					(name "~"
						(effects
							(font
								(size 1.27 1.27)
							)
						)
					)
					(number "2"
						(effects
							(font
								(size 1.27 1.27)
							)
						)
					)
				)
			)
		)
	(symbol "R_100k_0402_1"
			(pin_numbers hide)
			(pin_names hide)
			(exclude_from_sim no)
			(in_bom yes)
			(on_board yes)
			(property "Reference" "R"
				(at 20.32 -5.08 0)
				(effects
					(font
						(size 1.27 1.27)
						(thickness 0.15)
					)
					(justify left bottom)
				)
			)
			(property "Value" "R_100k_0402"
				(at 20.32 -12.7 0)
				(effects
					(font
						(size 1.27 1.27)
						(thickness 0.15)
					)
					(justify left bottom)
					(hide yes)
				)
			)
			(property "Footprint" "antmicro-footprints:R_0402_1005Metric"
				(at 20.32 -15.24 0)
				(effects
					(font
						(size 1.27 1.27)
						(thickness 0.15)
					)
					(justify left bottom)
					(hide yes)
				)
			)
			(property "Datasheet" "https://www.bourns.com/docs/product-datasheets/cr.pdf"
				(at 20.32 -17.78 0)
				(effects
					(font
						(size 1.27 1.27)
						(thickness 0.15)
					)
					(justify left bottom)
					(hide yes)
				)
			)
			(property "Description" "SMD Chip Resistor, 100 kohm, ± 1%, 62.5 mW, 0402 [1005 Metric], Thick Film, General Purpose"
				(at 0 0 0)
				(effects
					(font
						(size 1.27 1.27)
					)
					(hide yes)
				)
			)
			(property "MPN" "CR0402-FX-1003GLF"
				(at 20.32 -20.32 0)
				(effects
					(font
						(size 1.27 1.27)
						(thickness 0.15)
					)
					(justify left bottom)
					(hide yes)
				)
			)
			(property "Manufacturer" "Bourns"
				(at 20.32 -22.86 0)
				(effects
					(font
						(size 1.27 1.27)
						(thickness 0.15)
					)
					(justify left bottom)
					(hide yes)
				)
			)
			(property "License" "Apache-2.0"
				(at 20.32 -25.4 0)
				(effects
					(font
						(size 1.27 1.27)
						(thickness 0.15)
					)
					(justify left bottom)
					(hide yes)
				)
			)
			(property "Author" "Antmicro"
				(at 20.32 -27.94 0)
				(effects
					(font
						(size 1.27 1.27)
						(thickness 0.15)
					)
					(justify left bottom)
					(hide yes)
				)
			)
			(property "Val" "100k"
				(at 20.32 -7.62 0)
				(effects
					(font
						(size 1.27 1.27)
						(thickness 0.15)
					)
					(justify left bottom)
				)
			)
			(property "Tolerance" "1%"
				(at 20.32 -10.16 0)
				(effects
					(font
						(size 1.27 1.27)
					)
					(justify left bottom)
					(hide yes)
				)
			)
			(property "ki_keywords" "0402, SMT, RESISTOR, PASSIVE"
				(at 0 0 0)
				(effects
					(font
						(size 1.27 1.27)
					)
					(hide yes)
				)
			)
			(symbol "R_100k_0402_1_0_1"
				(rectangle
					(start 0.635 0.889)
					(end 4.445 -0.889)
					(stroke
						(width 0.254)
						(type default)
					)
					(fill
						(type none)
					)
				)
			)
			(symbol "R_100k_0402_1_1_1"
				(pin passive line
					(at 0 0 0)
					(length 0.635)
					(name "~"
						(effects
							(font
								(size 1.27 1.27)
							)
						)
					)
					(number "1"
						(effects
							(font
								(size 1.27 1.27)
							)
						)
					)
				)
				(pin passive line
					(at 5.08 0 180)
					(length 0.635)
					(name "~"
						(effects
							(font
								(size 1.27 1.27)
							)
						)
					)
					(number "2"
						(effects
							(font
								(size 1.27 1.27)
							)
						)
					)
				)
			)
		)
	(symbol "R_10k_0402_1"
			(pin_numbers hide)
			(pin_names hide)
			(exclude_from_sim no)
			(in_bom yes)
			(on_board yes)
			(property "Reference" "R"
				(at 20.32 -5.08 0)
				(effects
					(font
						(size 1.27 1.27)
						(thickness 0.15)
					)
					(justify left bottom)
				)
			)
			(property "Value" "R_10k_0402"
				(at 20.32 -12.7 0)
				(effects
					(font
						(size 1.27 1.27)
						(thickness 0.15)
					)
					(justify left bottom)
					(hide yes)
				)
			)
			(property "Footprint" "antmicro-footprints:R_0402_1005Metric"
				(at 20.32 -15.24 0)
				(effects
					(font
						(size 1.27 1.27)
						(thickness 0.15)
					)
					(justify left bottom)
					(hide yes)
				)
			)
			(property "Datasheet" "https://www.bourns.com/docs/product-datasheets/cr.pdf"
				(at 20.32 -17.78 0)
				(effects
					(font
						(size 1.27 1.27)
						(thickness 0.15)
					)
					(justify left bottom)
					(hide yes)
				)
			)
			(property "Description" "SMD Chip Resistor, 10 kohm, ± 1%, 62.5 mW, 0402 [1005 Metric], Thick Film, General Purpose"
				(at 0 0 0)
				(effects
					(font
						(size 1.27 1.27)
					)
					(hide yes)
				)
			)
			(property "MPN" "CR0402-FX-1002GLF"
				(at 20.32 -20.32 0)
				(effects
					(font
						(size 1.27 1.27)
						(thickness 0.15)
					)
					(justify left bottom)
					(hide yes)
				)
			)
			(property "Manufacturer" "Bourns"
				(at 20.32 -22.86 0)
				(effects
					(font
						(size 1.27 1.27)
						(thickness 0.15)
					)
					(justify left bottom)
					(hide yes)
				)
			)
			(property "License" "Apache-2.0"
				(at 20.32 -25.4 0)
				(effects
					(font
						(size 1.27 1.27)
						(thickness 0.15)
					)
					(justify left bottom)
					(hide yes)
				)
			)
			(property "Author" "Antmicro"
				(at 20.32 -27.94 0)
				(effects
					(font
						(size 1.27 1.27)
						(thickness 0.15)
					)
					(justify left bottom)
					(hide yes)
				)
			)
			(property "Val" "10k"
				(at 20.32 -7.62 0)
				(effects
					(font
						(size 1.27 1.27)
						(thickness 0.15)
					)
					(justify left bottom)
				)
			)
			(property "Tolerance" "1%"
				(at 20.32 -10.16 0)
				(effects
					(font
						(size 1.27 1.27)
					)
					(justify left bottom)
					(hide yes)
				)
			)
			(property "ki_keywords" "0402, SMT, RESISTOR, PASSIVE"
				(at 0 0 0)
				(effects
					(font
						(size 1.27 1.27)
					)
					(hide yes)
				)
			)
			(symbol "R_10k_0402_1_0_1"
				(rectangle
					(start 0.635 0.889)
					(end 4.445 -0.889)
					(stroke
						(width 0.254)
						(type default)
					)
					(fill
						(type none)
					)
				)
			)
			(symbol "R_10k_0402_1_1_1"
				(pin passive line
					(at 0 0 0)
					(length 0.635)
					(name "~"
						(effects
							(font
								(size 1.27 1.27)
							)
						)
					)
					(number "1"
						(effects
							(font
								(size 1.27 1.27)
							)
						)
					)
				)
				(pin passive line
					(at 5.08 0 180)
					(length 0.635)
					(name "~"
						(effects
							(font
								(size 1.27 1.27)
							)
						)
					)
					(number "2"
						(effects
							(font
								(size 1.27 1.27)
							)
						)
					)
				)
			)
		)
	(symbol "R_10k_0402_2"
			(pin_numbers hide)
			(pin_names hide)
			(exclude_from_sim no)
			(in_bom yes)
			(on_board yes)
			(property "Reference" "R"
				(at 20.32 -5.08 0)
				(effects
					(font
						(size 1.27 1.27)
						(thickness 0.15)
					)
					(justify left bottom)
				)
			)
			(property "Value" "R_10k_0402"
				(at 20.32 -12.7 0)
				(effects
					(font
						(size 1.27 1.27)
						(thickness 0.15)
					)
					(justify left bottom)
					(hide yes)
				)
			)
			(property "Footprint" "antmicro-footprints:R_0402_1005Metric"
				(at 20.32 -15.24 0)
				(effects
					(font
						(size 1.27 1.27)
						(thickness 0.15)
					)
					(justify left bottom)
					(hide yes)
				)
			)
			(property "Datasheet" "https://www.bourns.com/docs/product-datasheets/cr.pdf"
				(at 20.32 -17.78 0)
				(effects
					(font
						(size 1.27 1.27)
						(thickness 0.15)
					)
					(justify left bottom)
					(hide yes)
				)
			)
			(property "Description" "SMD Chip Resistor, 10 kohm, ± 1%, 62.5 mW, 0402 [1005 Metric], Thick Film, General Purpose"
				(at 0 0 0)
				(effects
					(font
						(size 1.27 1.27)
					)
					(hide yes)
				)
			)
			(property "MPN" "CR0402-FX-1002GLF"
				(at 20.32 -20.32 0)
				(effects
					(font
						(size 1.27 1.27)
						(thickness 0.15)
					)
					(justify left bottom)
					(hide yes)
				)
			)
			(property "Manufacturer" "Bourns"
				(at 20.32 -22.86 0)
				(effects
					(font
						(size 1.27 1.27)
						(thickness 0.15)
					)
					(justify left bottom)
					(hide yes)
				)
			)
			(property "License" "Apache-2.0"
				(at 20.32 -25.4 0)
				(effects
					(font
						(size 1.27 1.27)
						(thickness 0.15)
					)
					(justify left bottom)
					(hide yes)
				)
			)
			(property "Author" "Antmicro"
				(at 20.32 -27.94 0)
				(effects
					(font
						(size 1.27 1.27)
						(thickness 0.15)
					)
					(justify left bottom)
					(hide yes)
				)
			)
			(property "Val" "10k"
				(at 20.32 -7.62 0)
				(effects
					(font
						(size 1.27 1.27)
						(thickness 0.15)
					)
					(justify left bottom)
				)
			)
			(property "Tolerance" "1%"
				(at 20.32 -10.16 0)
				(effects
					(font
						(size 1.27 1.27)
					)
					(justify left bottom)
					(hide yes)
				)
			)
			(property "ki_keywords" "0402, SMT, RESISTOR, PASSIVE"
				(at 0 0 0)
				(effects
					(font
						(size 1.27 1.27)
					)
					(hide yes)
				)
			)
			(symbol "R_10k_0402_2_0_1"
				(rectangle
					(start 0.635 0.889)
					(end 4.445 -0.889)
					(stroke
						(width 0.254)
						(type default)
					)
					(fill
						(type none)
					)
				)
			)
			(symbol "R_10k_0402_2_1_1"
				(pin passive line
					(at 0 0 0)
					(length 0.635)
					(name "~"
						(effects
							(font
								(size 1.27 1.27)
							)
						)
					)
					(number "1"
						(effects
							(font
								(size 1.27 1.27)
							)
						)
					)
				)
				(pin passive line
					(at 5.08 0 180)
					(length 0.635)
					(name "~"
						(effects
							(font
								(size 1.27 1.27)
							)
						)
					)
					(number "2"
						(effects
							(font
								(size 1.27 1.27)
							)
						)
					)
				)
			)
		)
	(symbol "R_10k_0402_3"
			(pin_numbers hide)
			(pin_names hide)
			(exclude_from_sim no)
			(in_bom yes)
			(on_board yes)
			(property "Reference" "R"
				(at 20.32 -5.08 0)
				(effects
					(font
						(size 1.27 1.27)
						(thickness 0.15)
					)
					(justify left bottom)
				)
			)
			(property "Value" "R_10k_0402"
				(at 20.32 -12.7 0)
				(effects
					(font
						(size 1.27 1.27)
						(thickness 0.15)
					)
					(justify left bottom)
					(hide yes)
				)
			)
			(property "Footprint" "antmicro-footprints:R_0402_1005Metric"
				(at 20.32 -15.24 0)
				(effects
					(font
						(size 1.27 1.27)
						(thickness 0.15)
					)
					(justify left bottom)
					(hide yes)
				)
			)
			(property "Datasheet" "https://www.bourns.com/docs/product-datasheets/cr.pdf"
				(at 20.32 -17.78 0)
				(effects
					(font
						(size 1.27 1.27)
						(thickness 0.15)
					)
					(justify left bottom)
					(hide yes)
				)
			)
			(property "Description" "SMD Chip Resistor, 10 kohm, ± 1%, 62.5 mW, 0402 [1005 Metric], Thick Film, General Purpose"
				(at 0 0 0)
				(effects
					(font
						(size 1.27 1.27)
					)
					(hide yes)
				)
			)
			(property "MPN" "CR0402-FX-1002GLF"
				(at 20.32 -20.32 0)
				(effects
					(font
						(size 1.27 1.27)
						(thickness 0.15)
					)
					(justify left bottom)
					(hide yes)
				)
			)
			(property "Manufacturer" "Bourns"
				(at 20.32 -22.86 0)
				(effects
					(font
						(size 1.27 1.27)
						(thickness 0.15)
					)
					(justify left bottom)
					(hide yes)
				)
			)
			(property "License" "Apache-2.0"
				(at 20.32 -25.4 0)
				(effects
					(font
						(size 1.27 1.27)
						(thickness 0.15)
					)
					(justify left bottom)
					(hide yes)
				)
			)
			(property "Author" "Antmicro"
				(at 20.32 -27.94 0)
				(effects
					(font
						(size 1.27 1.27)
						(thickness 0.15)
					)
					(justify left bottom)
					(hide yes)
				)
			)
			(property "Val" "10k"
				(at 20.32 -7.62 0)
				(effects
					(font
						(size 1.27 1.27)
						(thickness 0.15)
					)
					(justify left bottom)
				)
			)
			(property "Tolerance" "1%"
				(at 20.32 -10.16 0)
				(effects
					(font
						(size 1.27 1.27)
					)
					(justify left bottom)
					(hide yes)
				)
			)
			(property "ki_keywords" "0402, SMT, RESISTOR, PASSIVE"
				(at 0 0 0)
				(effects
					(font
						(size 1.27 1.27)
					)
					(hide yes)
				)
			)
			(symbol "R_10k_0402_3_0_1"
				(rectangle
					(start 0.635 0.889)
					(end 4.445 -0.889)
					(stroke
						(width 0.254)
						(type default)
					)
					(fill
						(type none)
					)
				)
			)
			(symbol "R_10k_0402_3_1_1"
				(pin passive line
					(at 0 0 0)
					(length 0.635)
					(name "~"
						(effects
							(font
								(size 1.27 1.27)
							)
						)
					)
					(number "1"
						(effects
							(font
								(size 1.27 1.27)
							)
						)
					)
				)
				(pin passive line
					(at 5.08 0 180)
					(length 0.635)
					(name "~"
						(effects
							(font
								(size 1.27 1.27)
							)
						)
					)
					(number "2"
						(effects
							(font
								(size 1.27 1.27)
							)
						)
					)
				)
			)
		)
	(symbol "R_10k_0402_4"
			(pin_numbers hide)
			(pin_names hide)
			(exclude_from_sim no)
			(in_bom yes)
			(on_board yes)
			(property "Reference" "R"
				(at 20.32 -5.08 0)
				(effects
					(font
						(size 1.27 1.27)
						(thickness 0.15)
					)
					(justify left bottom)
				)
			)
			(property "Value" "R_10k_0402"
				(at 20.32 -12.7 0)
				(effects
					(font
						(size 1.27 1.27)
						(thickness 0.15)
					)
					(justify left bottom)
					(hide yes)
				)
			)
			(property "Footprint" "antmicro-footprints:R_0402_1005Metric"
				(at 20.32 -15.24 0)
				(effects
					(font
						(size 1.27 1.27)
						(thickness 0.15)
					)
					(justify left bottom)
					(hide yes)
				)
			)
			(property "Datasheet" "https://www.bourns.com/docs/product-datasheets/cr.pdf"
				(at 20.32 -17.78 0)
				(effects
					(font
						(size 1.27 1.27)
						(thickness 0.15)
					)
					(justify left bottom)
					(hide yes)
				)
			)
			(property "Description" "SMD Chip Resistor, 10 kohm, ± 1%, 62.5 mW, 0402 [1005 Metric], Thick Film, General Purpose"
				(at 0 0 0)
				(effects
					(font
						(size 1.27 1.27)
					)
					(hide yes)
				)
			)
			(property "MPN" "CR0402-FX-1002GLF"
				(at 20.32 -20.32 0)
				(effects
					(font
						(size 1.27 1.27)
						(thickness 0.15)
					)
					(justify left bottom)
					(hide yes)
				)
			)
			(property "Manufacturer" "Bourns"
				(at 20.32 -22.86 0)
				(effects
					(font
						(size 1.27 1.27)
						(thickness 0.15)
					)
					(justify left bottom)
					(hide yes)
				)
			)
			(property "License" "Apache-2.0"
				(at 20.32 -25.4 0)
				(effects
					(font
						(size 1.27 1.27)
						(thickness 0.15)
					)
					(justify left bottom)
					(hide yes)
				)
			)
			(property "Author" "Antmicro"
				(at 20.32 -27.94 0)
				(effects
					(font
						(size 1.27 1.27)
						(thickness 0.15)
					)
					(justify left bottom)
					(hide yes)
				)
			)
			(property "Val" "10k"
				(at 20.32 -7.62 0)
				(effects
					(font
						(size 1.27 1.27)
						(thickness 0.15)
					)
					(justify left bottom)
				)
			)
			(property "Tolerance" "1%"
				(at 20.32 -10.16 0)
				(effects
					(font
						(size 1.27 1.27)
					)
					(justify left bottom)
					(hide yes)
				)
			)
			(property "ki_keywords" "0402, SMT, RESISTOR, PASSIVE"
				(at 0 0 0)
				(effects
					(font
						(size 1.27 1.27)
					)
					(hide yes)
				)
			)
			(symbol "R_10k_0402_4_0_1"
				(rectangle
					(start 0.635 0.889)
					(end 4.445 -0.889)
					(stroke
						(width 0.254)
						(type default)
					)
					(fill
						(type none)
					)
				)
			)
			(symbol "R_10k_0402_4_1_1"
				(pin passive line
					(at 0 0 0)
					(length 0.635)
					(name "~"
						(effects
							(font
								(size 1.27 1.27)
							)
						)
					)
					(number "1"
						(effects
							(font
								(size 1.27 1.27)
							)
						)
					)
				)
				(pin passive line
					(at 5.08 0 180)
					(length 0.635)
					(name "~"
						(effects
							(font
								(size 1.27 1.27)
							)
						)
					)
					(number "2"
						(effects
							(font
								(size 1.27 1.27)
							)
						)
					)
				)
			)
		)
	(symbol "R_200R_0402_1"
			(pin_numbers hide)
			(pin_names hide)
			(exclude_from_sim no)
			(in_bom yes)
			(on_board yes)
			(property "Reference" "R"
				(at 20.32 -5.08 0)
				(effects
					(font
						(size 1.27 1.27)
						(thickness 0.15)
					)
					(justify left bottom)
				)
			)
			(property "Value" "R_200R_0402"
				(at 20.32 -12.7 0)
				(effects
					(font
						(size 1.27 1.27)
						(thickness 0.15)
					)
					(justify left bottom)
					(hide yes)
				)
			)
			(property "Footprint" "antmicro-footprints:R_0402_1005Metric"
				(at 20.32 -15.24 0)
				(effects
					(font
						(size 1.27 1.27)
						(thickness 0.15)
					)
					(justify left bottom)
					(hide yes)
				)
			)
			(property "Datasheet" "https://www.bourns.com/docs/product-datasheets/cr.pdf"
				(at 20.32 -17.78 0)
				(effects
					(font
						(size 1.27 1.27)
						(thickness 0.15)
					)
					(justify left bottom)
					(hide yes)
				)
			)
			(property "Description" "SMD Chip Resistor, 200 ohm, ± 1%, 62.5 mW, 0402 [1005 Metric], Thick Film, General Purpose"
				(at 0 0 0)
				(effects
					(font
						(size 1.27 1.27)
					)
					(hide yes)
				)
			)
			(property "MPN" "CR0402-FX-2000GLF"
				(at 20.32 -20.32 0)
				(effects
					(font
						(size 1.27 1.27)
						(thickness 0.15)
					)
					(justify left bottom)
					(hide yes)
				)
			)
			(property "Manufacturer" "Bourns"
				(at 20.32 -22.86 0)
				(effects
					(font
						(size 1.27 1.27)
						(thickness 0.15)
					)
					(justify left bottom)
					(hide yes)
				)
			)
			(property "License" "Apache-2.0"
				(at 20.32 -25.4 0)
				(effects
					(font
						(size 1.27 1.27)
						(thickness 0.15)
					)
					(justify left bottom)
					(hide yes)
				)
			)
			(property "Author" "Antmicro"
				(at 20.32 -27.94 0)
				(effects
					(font
						(size 1.27 1.27)
						(thickness 0.15)
					)
					(justify left bottom)
					(hide yes)
				)
			)
			(property "Val" "200R"
				(at 20.32 -7.62 0)
				(effects
					(font
						(size 1.27 1.27)
						(thickness 0.15)
					)
					(justify left bottom)
				)
			)
			(property "Tolerance" "1%"
				(at 20.32 -10.16 0)
				(effects
					(font
						(size 1.27 1.27)
					)
					(justify left bottom)
					(hide yes)
				)
			)
			(property "ki_keywords" "0402, SMT, RESISTOR, PASSIVE"
				(at 0 0 0)
				(effects
					(font
						(size 1.27 1.27)
					)
					(hide yes)
				)
			)
			(symbol "R_200R_0402_1_0_1"
				(rectangle
					(start 0.635 0.889)
					(end 4.445 -0.889)
					(stroke
						(width 0.254)
						(type default)
					)
					(fill
						(type none)
					)
				)
			)
			(symbol "R_200R_0402_1_1_1"
				(pin passive line
					(at 0 0 0)
					(length 0.635)
					(name "~"
						(effects
							(font
								(size 1.27 1.27)
							)
						)
					)
					(number "1"
						(effects
							(font
								(size 1.27 1.27)
							)
						)
					)
				)
				(pin passive line
					(at 5.08 0 180)
					(length 0.635)
					(name "~"
						(effects
							(font
								(size 1.27 1.27)
							)
						)
					)
					(number "2"
						(effects
							(font
								(size 1.27 1.27)
							)
						)
					)
				)
			)
		)
	(symbol "R_200R_0402_2"
			(pin_numbers hide)
			(pin_names hide)
			(exclude_from_sim no)
			(in_bom yes)
			(on_board yes)
			(property "Reference" "R"
				(at 20.32 -5.08 0)
				(effects
					(font
						(size 1.27 1.27)
						(thickness 0.15)
					)
					(justify left bottom)
				)
			)
			(property "Value" "R_200R_0402"
				(at 20.32 -12.7 0)
				(effects
					(font
						(size 1.27 1.27)
						(thickness 0.15)
					)
					(justify left bottom)
					(hide yes)
				)
			)
			(property "Footprint" "antmicro-footprints:R_0402_1005Metric"
				(at 20.32 -15.24 0)
				(effects
					(font
						(size 1.27 1.27)
						(thickness 0.15)
					)
					(justify left bottom)
					(hide yes)
				)
			)
			(property "Datasheet" "https://www.bourns.com/docs/product-datasheets/cr.pdf"
				(at 20.32 -17.78 0)
				(effects
					(font
						(size 1.27 1.27)
						(thickness 0.15)
					)
					(justify left bottom)
					(hide yes)
				)
			)
			(property "Description" "SMD Chip Resistor, 200 ohm, ± 1%, 62.5 mW, 0402 [1005 Metric], Thick Film, General Purpose"
				(at 0 0 0)
				(effects
					(font
						(size 1.27 1.27)
					)
					(hide yes)
				)
			)
			(property "MPN" "CR0402-FX-2000GLF"
				(at 20.32 -20.32 0)
				(effects
					(font
						(size 1.27 1.27)
						(thickness 0.15)
					)
					(justify left bottom)
					(hide yes)
				)
			)
			(property "Manufacturer" "Bourns"
				(at 20.32 -22.86 0)
				(effects
					(font
						(size 1.27 1.27)
						(thickness 0.15)
					)
					(justify left bottom)
					(hide yes)
				)
			)
			(property "License" "Apache-2.0"
				(at 20.32 -25.4 0)
				(effects
					(font
						(size 1.27 1.27)
						(thickness 0.15)
					)
					(justify left bottom)
					(hide yes)
				)
			)
			(property "Author" "Antmicro"
				(at 20.32 -27.94 0)
				(effects
					(font
						(size 1.27 1.27)
						(thickness 0.15)
					)
					(justify left bottom)
					(hide yes)
				)
			)
			(property "Val" "200R"
				(at 20.32 -7.62 0)
				(effects
					(font
						(size 1.27 1.27)
						(thickness 0.15)
					)
					(justify left bottom)
				)
			)
			(property "Tolerance" "1%"
				(at 20.32 -10.16 0)
				(effects
					(font
						(size 1.27 1.27)
					)
					(justify left bottom)
					(hide yes)
				)
			)
			(property "ki_keywords" "0402, SMT, RESISTOR, PASSIVE"
				(at 0 0 0)
				(effects
					(font
						(size 1.27 1.27)
					)
					(hide yes)
				)
			)
			(symbol "R_200R_0402_2_0_1"
				(rectangle
					(start 0.635 0.889)
					(end 4.445 -0.889)
					(stroke
						(width 0.254)
						(type default)
					)
					(fill
						(type none)
					)
				)
			)
			(symbol "R_200R_0402_2_1_1"
				(pin passive line
					(at 0 0 0)
					(length 0.635)
					(name "~"
						(effects
							(font
								(size 1.27 1.27)
							)
						)
					)
					(number "1"
						(effects
							(font
								(size 1.27 1.27)
							)
						)
					)
				)
				(pin passive line
					(at 5.08 0 180)
					(length 0.635)
					(name "~"
						(effects
							(font
								(size 1.27 1.27)
							)
						)
					)
					(number "2"
						(effects
							(font
								(size 1.27 1.27)
							)
						)
					)
				)
			)
		)
	(symbol "R_200k_0402_1"
			(pin_numbers hide)
			(pin_names hide)
			(exclude_from_sim no)
			(in_bom yes)
			(on_board yes)
			(property "Reference" "R"
				(at 20.32 -5.08 0)
				(effects
					(font
						(size 1.27 1.27)
						(thickness 0.15)
					)
					(justify left bottom)
				)
			)
			(property "Value" "R_200k_0402"
				(at 20.32 -12.7 0)
				(effects
					(font
						(size 1.27 1.27)
						(thickness 0.15)
					)
					(justify left bottom)
					(hide yes)
				)
			)
			(property "Footprint" "antmicro-footprints:R_0402_1005Metric"
				(at 20.32 -15.24 0)
				(effects
					(font
						(size 1.27 1.27)
						(thickness 0.15)
					)
					(justify left bottom)
					(hide yes)
				)
			)
			(property "Datasheet" "https://www.bourns.com/docs/product-datasheets/cr.pdf"
				(at 20.32 -17.78 0)
				(effects
					(font
						(size 1.27 1.27)
						(thickness 0.15)
					)
					(justify left bottom)
					(hide yes)
				)
			)
			(property "Description" "SMD Chip Resistor, 200 kohm, ± 1%, 62.5 mW, 0402 [1005 Metric], Thick Film, General Purpose"
				(at 0 0 0)
				(effects
					(font
						(size 1.27 1.27)
					)
					(hide yes)
				)
			)
			(property "MPN" "CR0402-FX-2003GLF"
				(at 20.32 -20.32 0)
				(effects
					(font
						(size 1.27 1.27)
						(thickness 0.15)
					)
					(justify left bottom)
					(hide yes)
				)
			)
			(property "Manufacturer" "Bourns"
				(at 20.32 -22.86 0)
				(effects
					(font
						(size 1.27 1.27)
						(thickness 0.15)
					)
					(justify left bottom)
					(hide yes)
				)
			)
			(property "License" "Apache-2.0"
				(at 20.32 -25.4 0)
				(effects
					(font
						(size 1.27 1.27)
						(thickness 0.15)
					)
					(justify left bottom)
					(hide yes)
				)
			)
			(property "Author" "Antmicro"
				(at 20.32 -27.94 0)
				(effects
					(font
						(size 1.27 1.27)
						(thickness 0.15)
					)
					(justify left bottom)
					(hide yes)
				)
			)
			(property "Val" "200k"
				(at 20.32 -7.62 0)
				(effects
					(font
						(size 1.27 1.27)
						(thickness 0.15)
					)
					(justify left bottom)
				)
			)
			(property "Tolerance" "1%"
				(at 20.32 -10.16 0)
				(effects
					(font
						(size 1.27 1.27)
					)
					(justify left bottom)
					(hide yes)
				)
			)
			(property "ki_keywords" "0402, SMT, RESISTOR, PASSIVE"
				(at 0 0 0)
				(effects
					(font
						(size 1.27 1.27)
					)
					(hide yes)
				)
			)
			(symbol "R_200k_0402_1_0_1"
				(rectangle
					(start 0.635 0.889)
					(end 4.445 -0.889)
					(stroke
						(width 0.254)
						(type default)
					)
					(fill
						(type none)
					)
				)
			)
			(symbol "R_200k_0402_1_1_1"
				(pin passive line
					(at 0 0 0)
					(length 0.635)
					(name "~"
						(effects
							(font
								(size 1.27 1.27)
							)
						)
					)
					(number "1"
						(effects
							(font
								(size 1.27 1.27)
							)
						)
					)
				)
				(pin passive line
					(at 5.08 0 180)
					(length 0.635)
					(name "~"
						(effects
							(font
								(size 1.27 1.27)
							)
						)
					)
					(number "2"
						(effects
							(font
								(size 1.27 1.27)
							)
						)
					)
				)
			)
		)
	(symbol "R_200k_0402_2"
			(pin_numbers hide)
			(pin_names hide)
			(exclude_from_sim no)
			(in_bom yes)
			(on_board yes)
			(property "Reference" "R"
				(at 20.32 -5.08 0)
				(effects
					(font
						(size 1.27 1.27)
						(thickness 0.15)
					)
					(justify left bottom)
				)
			)
			(property "Value" "R_200k_0402"
				(at 20.32 -12.7 0)
				(effects
					(font
						(size 1.27 1.27)
						(thickness 0.15)
					)
					(justify left bottom)
					(hide yes)
				)
			)
			(property "Footprint" "antmicro-footprints:R_0402_1005Metric"
				(at 20.32 -15.24 0)
				(effects
					(font
						(size 1.27 1.27)
						(thickness 0.15)
					)
					(justify left bottom)
					(hide yes)
				)
			)
			(property "Datasheet" "https://www.bourns.com/docs/product-datasheets/cr.pdf"
				(at 20.32 -17.78 0)
				(effects
					(font
						(size 1.27 1.27)
						(thickness 0.15)
					)
					(justify left bottom)
					(hide yes)
				)
			)
			(property "Description" "SMD Chip Resistor, 200 kohm, ± 1%, 62.5 mW, 0402 [1005 Metric], Thick Film, General Purpose"
				(at 0 0 0)
				(effects
					(font
						(size 1.27 1.27)
					)
					(hide yes)
				)
			)
			(property "MPN" "CR0402-FX-2003GLF"
				(at 20.32 -20.32 0)
				(effects
					(font
						(size 1.27 1.27)
						(thickness 0.15)
					)
					(justify left bottom)
					(hide yes)
				)
			)
			(property "Manufacturer" "Bourns"
				(at 20.32 -22.86 0)
				(effects
					(font
						(size 1.27 1.27)
						(thickness 0.15)
					)
					(justify left bottom)
					(hide yes)
				)
			)
			(property "License" "Apache-2.0"
				(at 20.32 -25.4 0)
				(effects
					(font
						(size 1.27 1.27)
						(thickness 0.15)
					)
					(justify left bottom)
					(hide yes)
				)
			)
			(property "Author" "Antmicro"
				(at 20.32 -27.94 0)
				(effects
					(font
						(size 1.27 1.27)
						(thickness 0.15)
					)
					(justify left bottom)
					(hide yes)
				)
			)
			(property "Val" "200k"
				(at 20.32 -7.62 0)
				(effects
					(font
						(size 1.27 1.27)
						(thickness 0.15)
					)
					(justify left bottom)
				)
			)
			(property "Tolerance" "1%"
				(at 20.32 -10.16 0)
				(effects
					(font
						(size 1.27 1.27)
					)
					(justify left bottom)
					(hide yes)
				)
			)
			(property "ki_keywords" "0402, SMT, RESISTOR, PASSIVE"
				(at 0 0 0)
				(effects
					(font
						(size 1.27 1.27)
					)
					(hide yes)
				)
			)
			(symbol "R_200k_0402_2_0_1"
				(rectangle
					(start 0.635 0.889)
					(end 4.445 -0.889)
					(stroke
						(width 0.254)
						(type default)
					)
					(fill
						(type none)
					)
				)
			)
			(symbol "R_200k_0402_2_1_1"
				(pin passive line
					(at 0 0 0)
					(length 0.635)
					(name "~"
						(effects
							(font
								(size 1.27 1.27)
							)
						)
					)
					(number "1"
						(effects
							(font
								(size 1.27 1.27)
							)
						)
					)
				)
				(pin passive line
					(at 5.08 0 180)
					(length 0.635)
					(name "~"
						(effects
							(font
								(size 1.27 1.27)
							)
						)
					)
					(number "2"
						(effects
							(font
								(size 1.27 1.27)
							)
						)
					)
				)
			)
		)
	(symbol "R_2k2_0402_1"
			(pin_numbers hide)
			(pin_names hide)
			(exclude_from_sim no)
			(in_bom yes)
			(on_board yes)
			(property "Reference" "R"
				(at 20.32 -5.08 0)
				(effects
					(font
						(size 1.27 1.27)
						(thickness 0.15)
					)
					(justify left bottom)
				)
			)
			(property "Value" "R_2k2_0402"
				(at 20.32 -12.7 0)
				(effects
					(font
						(size 1.27 1.27)
						(thickness 0.15)
					)
					(justify left bottom)
					(hide yes)
				)
			)
			(property "Footprint" "antmicro-footprints:R_0402_1005Metric"
				(at 20.32 -15.24 0)
				(effects
					(font
						(size 1.27 1.27)
						(thickness 0.15)
					)
					(justify left bottom)
					(hide yes)
				)
			)
			(property "Datasheet" "https://www.bourns.com/docs/product-datasheets/cr.pdf"
				(at 20.32 -17.78 0)
				(effects
					(font
						(size 1.27 1.27)
						(thickness 0.15)
					)
					(justify left bottom)
					(hide yes)
				)
			)
			(property "Description" "SMD Chip Resistor, 2.2 kohm, ± 1%, 62.5 mW, 0402 [1005 Metric], Thick Film, General Purpose"
				(at 0 0 0)
				(effects
					(font
						(size 1.27 1.27)
					)
					(hide yes)
				)
			)
			(property "MPN" "CR0402-FX-2201GLF"
				(at 20.32 -20.32 0)
				(effects
					(font
						(size 1.27 1.27)
						(thickness 0.15)
					)
					(justify left bottom)
					(hide yes)
				)
			)
			(property "Manufacturer" "Bourns"
				(at 20.32 -22.86 0)
				(effects
					(font
						(size 1.27 1.27)
						(thickness 0.15)
					)
					(justify left bottom)
					(hide yes)
				)
			)
			(property "License" "Apache-2.0"
				(at 20.32 -25.4 0)
				(effects
					(font
						(size 1.27 1.27)
						(thickness 0.15)
					)
					(justify left bottom)
					(hide yes)
				)
			)
			(property "Author" "Antmicro"
				(at 20.32 -27.94 0)
				(effects
					(font
						(size 1.27 1.27)
						(thickness 0.15)
					)
					(justify left bottom)
					(hide yes)
				)
			)
			(property "Val" "2k2"
				(at 20.32 -7.62 0)
				(effects
					(font
						(size 1.27 1.27)
						(thickness 0.15)
					)
					(justify left bottom)
				)
			)
			(property "Tolerance" "1%"
				(at 20.32 -10.16 0)
				(effects
					(font
						(size 1.27 1.27)
					)
					(justify left bottom)
					(hide yes)
				)
			)
			(property "ki_keywords" "0402, SMT, RESISTOR, PASSIVE"
				(at 0 0 0)
				(effects
					(font
						(size 1.27 1.27)
					)
					(hide yes)
				)
			)
			(symbol "R_2k2_0402_1_0_1"
				(rectangle
					(start 0.635 0.889)
					(end 4.445 -0.889)
					(stroke
						(width 0.254)
						(type default)
					)
					(fill
						(type none)
					)
				)
			)
			(symbol "R_2k2_0402_1_1_1"
				(pin passive line
					(at 0 0 0)
					(length 0.635)
					(name "~"
						(effects
							(font
								(size 1.27 1.27)
							)
						)
					)
					(number "1"
						(effects
							(font
								(size 1.27 1.27)
							)
						)
					)
				)
				(pin passive line
					(at 5.08 0 180)
					(length 0.635)
					(name "~"
						(effects
							(font
								(size 1.27 1.27)
							)
						)
					)
					(number "2"
						(effects
							(font
								(size 1.27 1.27)
							)
						)
					)
				)
			)
		)
	(symbol "R_47k_0402_1"
			(pin_numbers hide)
			(pin_names hide)
			(exclude_from_sim no)
			(in_bom yes)
			(on_board yes)
			(property "Reference" "R"
				(at 20.32 -5.08 0)
				(effects
					(font
						(size 1.27 1.27)
						(thickness 0.15)
					)
					(justify left bottom)
				)
			)
			(property "Value" "R_47k_0402"
				(at 20.32 -12.7 0)
				(effects
					(font
						(size 1.27 1.27)
						(thickness 0.15)
					)
					(justify left bottom)
					(hide yes)
				)
			)
			(property "Footprint" "antmicro-footprints:R_0402_1005Metric"
				(at 20.32 -15.24 0)
				(effects
					(font
						(size 1.27 1.27)
						(thickness 0.15)
					)
					(justify left bottom)
					(hide yes)
				)
			)
			(property "Datasheet" "https://www.bourns.com/docs/product-datasheets/cr.pdf"
				(at 20.32 -17.78 0)
				(effects
					(font
						(size 1.27 1.27)
						(thickness 0.15)
					)
					(justify left bottom)
					(hide yes)
				)
			)
			(property "Description" "SMD Chip Resistor, 47 kohm, ± 1%, 62.5 mW, 0402 [1005 Metric], Thick Film, General Purpose"
				(at 0 0 0)
				(effects
					(font
						(size 1.27 1.27)
					)
					(hide yes)
				)
			)
			(property "MPN" "CR0402-FX-4702GLF"
				(at 20.32 -20.32 0)
				(effects
					(font
						(size 1.27 1.27)
						(thickness 0.15)
					)
					(justify left bottom)
					(hide yes)
				)
			)
			(property "Manufacturer" "Bourns"
				(at 20.32 -22.86 0)
				(effects
					(font
						(size 1.27 1.27)
						(thickness 0.15)
					)
					(justify left bottom)
					(hide yes)
				)
			)
			(property "License" "Apache-2.0"
				(at 20.32 -25.4 0)
				(effects
					(font
						(size 1.27 1.27)
						(thickness 0.15)
					)
					(justify left bottom)
					(hide yes)
				)
			)
			(property "Author" "Antmicro"
				(at 20.32 -27.94 0)
				(effects
					(font
						(size 1.27 1.27)
						(thickness 0.15)
					)
					(justify left bottom)
					(hide yes)
				)
			)
			(property "Val" "47k"
				(at 20.32 -7.62 0)
				(effects
					(font
						(size 1.27 1.27)
						(thickness 0.15)
					)
					(justify left bottom)
				)
			)
			(property "Tolerance" "1%"
				(at 20.32 -10.16 0)
				(effects
					(font
						(size 1.27 1.27)
					)
					(justify left bottom)
					(hide yes)
				)
			)
			(property "ki_keywords" "0402, SMT, RESISTOR, PASSIVE"
				(at 0 0 0)
				(effects
					(font
						(size 1.27 1.27)
					)
					(hide yes)
				)
			)
			(symbol "R_47k_0402_1_0_1"
				(rectangle
					(start 0.635 0.889)
					(end 4.445 -0.889)
					(stroke
						(width 0.254)
						(type default)
					)
					(fill
						(type none)
					)
				)
			)
			(symbol "R_47k_0402_1_1_1"
				(pin passive line
					(at 0 0 0)
					(length 0.635)
					(name "~"
						(effects
							(font
								(size 1.27 1.27)
							)
						)
					)
					(number "1"
						(effects
							(font
								(size 1.27 1.27)
							)
						)
					)
				)
				(pin passive line
					(at 5.08 0 180)
					(length 0.635)
					(name "~"
						(effects
							(font
								(size 1.27 1.27)
							)
						)
					)
					(number "2"
						(effects
							(font
								(size 1.27 1.27)
							)
						)
					)
				)
			)
		)
	(symbol "R_47k_0402_2"
			(pin_numbers hide)
			(pin_names hide)
			(exclude_from_sim no)
			(in_bom yes)
			(on_board yes)
			(property "Reference" "R"
				(at 20.32 -5.08 0)
				(effects
					(font
						(size 1.27 1.27)
						(thickness 0.15)
					)
					(justify left bottom)
				)
			)
			(property "Value" "R_47k_0402"
				(at 20.32 -12.7 0)
				(effects
					(font
						(size 1.27 1.27)
						(thickness 0.15)
					)
					(justify left bottom)
					(hide yes)
				)
			)
			(property "Footprint" "antmicro-footprints:R_0402_1005Metric"
				(at 20.32 -15.24 0)
				(effects
					(font
						(size 1.27 1.27)
						(thickness 0.15)
					)
					(justify left bottom)
					(hide yes)
				)
			)
			(property "Datasheet" "https://www.bourns.com/docs/product-datasheets/cr.pdf"
				(at 20.32 -17.78 0)
				(effects
					(font
						(size 1.27 1.27)
						(thickness 0.15)
					)
					(justify left bottom)
					(hide yes)
				)
			)
			(property "Description" "SMD Chip Resistor, 47 kohm, ± 1%, 62.5 mW, 0402 [1005 Metric], Thick Film, General Purpose"
				(at 0 0 0)
				(effects
					(font
						(size 1.27 1.27)
					)
					(hide yes)
				)
			)
			(property "MPN" "CR0402-FX-4702GLF"
				(at 20.32 -20.32 0)
				(effects
					(font
						(size 1.27 1.27)
						(thickness 0.15)
					)
					(justify left bottom)
					(hide yes)
				)
			)
			(property "Manufacturer" "Bourns"
				(at 20.32 -22.86 0)
				(effects
					(font
						(size 1.27 1.27)
						(thickness 0.15)
					)
					(justify left bottom)
					(hide yes)
				)
			)
			(property "License" "Apache-2.0"
				(at 20.32 -25.4 0)
				(effects
					(font
						(size 1.27 1.27)
						(thickness 0.15)
					)
					(justify left bottom)
					(hide yes)
				)
			)
			(property "Author" "Antmicro"
				(at 20.32 -27.94 0)
				(effects
					(font
						(size 1.27 1.27)
						(thickness 0.15)
					)
					(justify left bottom)
					(hide yes)
				)
			)
			(property "Val" "47k"
				(at 20.32 -7.62 0)
				(effects
					(font
						(size 1.27 1.27)
						(thickness 0.15)
					)
					(justify left bottom)
				)
			)
			(property "Tolerance" "1%"
				(at 20.32 -10.16 0)
				(effects
					(font
						(size 1.27 1.27)
					)
					(justify left bottom)
					(hide yes)
				)
			)
			(property "ki_keywords" "0402, SMT, RESISTOR, PASSIVE"
				(at 0 0 0)
				(effects
					(font
						(size 1.27 1.27)
					)
					(hide yes)
				)
			)
			(symbol "R_47k_0402_2_0_1"
				(rectangle
					(start 0.635 0.889)
					(end 4.445 -0.889)
					(stroke
						(width 0.254)
						(type default)
					)
					(fill
						(type none)
					)
				)
			)
			(symbol "R_47k_0402_2_1_1"
				(pin passive line
					(at 0 0 0)
					(length 0.635)
					(name "~"
						(effects
							(font
								(size 1.27 1.27)
							)
						)
					)
					(number "1"
						(effects
							(font
								(size 1.27 1.27)
							)
						)
					)
				)
				(pin passive line
					(at 5.08 0 180)
					(length 0.635)
					(name "~"
						(effects
							(font
								(size 1.27 1.27)
							)
						)
					)
					(number "2"
						(effects
							(font
								(size 1.27 1.27)
							)
						)
					)
				)
			)
		)
	(symbol "R_4k7_0402_1"
			(pin_numbers hide)
			(pin_names hide)
			(exclude_from_sim no)
			(in_bom yes)
			(on_board yes)
			(property "Reference" "R"
				(at 20.32 -5.08 0)
				(effects
					(font
						(size 1.27 1.27)
						(thickness 0.15)
					)
					(justify left bottom)
				)
			)
			(property "Value" "R_4k7_0402"
				(at 20.32 -12.7 0)
				(effects
					(font
						(size 1.27 1.27)
						(thickness 0.15)
					)
					(justify left bottom)
					(hide yes)
				)
			)
			(property "Footprint" "antmicro-footprints:R_0402_1005Metric"
				(at 20.32 -15.24 0)
				(effects
					(font
						(size 1.27 1.27)
						(thickness 0.15)
					)
					(justify left bottom)
					(hide yes)
				)
			)
			(property "Datasheet" "https://www.bourns.com/docs/product-datasheets/cr.pdf"
				(at 20.32 -17.78 0)
				(effects
					(font
						(size 1.27 1.27)
						(thickness 0.15)
					)
					(justify left bottom)
					(hide yes)
				)
			)
			(property "Description" "SMD Chip Resistor, 4.7 kohm, ± 1%, 62.5 mW, 0402 [1005 Metric], Thick Film, General Purpose"
				(at 0 0 0)
				(effects
					(font
						(size 1.27 1.27)
					)
					(hide yes)
				)
			)
			(property "MPN" "CR0402-FX-4701GLF"
				(at 20.32 -20.32 0)
				(effects
					(font
						(size 1.27 1.27)
						(thickness 0.15)
					)
					(justify left bottom)
					(hide yes)
				)
			)
			(property "Manufacturer" "Bourns"
				(at 20.32 -22.86 0)
				(effects
					(font
						(size 1.27 1.27)
						(thickness 0.15)
					)
					(justify left bottom)
					(hide yes)
				)
			)
			(property "License" "Apache-2.0"
				(at 20.32 -25.4 0)
				(effects
					(font
						(size 1.27 1.27)
						(thickness 0.15)
					)
					(justify left bottom)
					(hide yes)
				)
			)
			(property "Author" "Antmicro"
				(at 20.32 -27.94 0)
				(effects
					(font
						(size 1.27 1.27)
						(thickness 0.15)
					)
					(justify left bottom)
					(hide yes)
				)
			)
			(property "Val" "4k7"
				(at 20.32 -7.62 0)
				(effects
					(font
						(size 1.27 1.27)
						(thickness 0.15)
					)
					(justify left bottom)
				)
			)
			(property "Tolerance" "1%"
				(at 20.32 -10.16 0)
				(effects
					(font
						(size 1.27 1.27)
					)
					(justify left bottom)
					(hide yes)
				)
			)
			(property "ki_keywords" "0402, SMT, RESISTOR, PASSIVE"
				(at 0 0 0)
				(effects
					(font
						(size 1.27 1.27)
					)
					(hide yes)
				)
			)
			(symbol "R_4k7_0402_1_0_1"
				(rectangle
					(start 0.635 0.889)
					(end 4.445 -0.889)
					(stroke
						(width 0.254)
						(type default)
					)
					(fill
						(type none)
					)
				)
			)
			(symbol "R_4k7_0402_1_1_1"
				(pin passive line
					(at 0 0 0)
					(length 0.635)
					(name "~"
						(effects
							(font
								(size 1.27 1.27)
							)
						)
					)
					(number "1"
						(effects
							(font
								(size 1.27 1.27)
							)
						)
					)
				)
				(pin passive line
					(at 5.08 0 180)
					(length 0.635)
					(name "~"
						(effects
							(font
								(size 1.27 1.27)
							)
						)
					)
					(number "2"
						(effects
							(font
								(size 1.27 1.27)
							)
						)
					)
				)
			)
		)
	(symbol "R_4k7_0402_2"
			(pin_numbers hide)
			(pin_names hide)
			(exclude_from_sim no)
			(in_bom yes)
			(on_board yes)
			(property "Reference" "R"
				(at 20.32 -5.08 0)
				(effects
					(font
						(size 1.27 1.27)
						(thickness 0.15)
					)
					(justify left bottom)
				)
			)
			(property "Value" "R_4k7_0402"
				(at 20.32 -12.7 0)
				(effects
					(font
						(size 1.27 1.27)
						(thickness 0.15)
					)
					(justify left bottom)
					(hide yes)
				)
			)
			(property "Footprint" "antmicro-footprints:R_0402_1005Metric"
				(at 20.32 -15.24 0)
				(effects
					(font
						(size 1.27 1.27)
						(thickness 0.15)
					)
					(justify left bottom)
					(hide yes)
				)
			)
			(property "Datasheet" "https://www.bourns.com/docs/product-datasheets/cr.pdf"
				(at 20.32 -17.78 0)
				(effects
					(font
						(size 1.27 1.27)
						(thickness 0.15)
					)
					(justify left bottom)
					(hide yes)
				)
			)
			(property "Description" "SMD Chip Resistor, 4.7 kohm, ± 1%, 62.5 mW, 0402 [1005 Metric], Thick Film, General Purpose"
				(at 0 0 0)
				(effects
					(font
						(size 1.27 1.27)
					)
					(hide yes)
				)
			)
			(property "MPN" "CR0402-FX-4701GLF"
				(at 20.32 -20.32 0)
				(effects
					(font
						(size 1.27 1.27)
						(thickness 0.15)
					)
					(justify left bottom)
					(hide yes)
				)
			)
			(property "Manufacturer" "Bourns"
				(at 20.32 -22.86 0)
				(effects
					(font
						(size 1.27 1.27)
						(thickness 0.15)
					)
					(justify left bottom)
					(hide yes)
				)
			)
			(property "License" "Apache-2.0"
				(at 20.32 -25.4 0)
				(effects
					(font
						(size 1.27 1.27)
						(thickness 0.15)
					)
					(justify left bottom)
					(hide yes)
				)
			)
			(property "Author" "Antmicro"
				(at 20.32 -27.94 0)
				(effects
					(font
						(size 1.27 1.27)
						(thickness 0.15)
					)
					(justify left bottom)
					(hide yes)
				)
			)
			(property "Val" "4k7"
				(at 20.32 -7.62 0)
				(effects
					(font
						(size 1.27 1.27)
						(thickness 0.15)
					)
					(justify left bottom)
				)
			)
			(property "Tolerance" "1%"
				(at 20.32 -10.16 0)
				(effects
					(font
						(size 1.27 1.27)
					)
					(justify left bottom)
					(hide yes)
				)
			)
			(property "ki_keywords" "0402, SMT, RESISTOR, PASSIVE"
				(at 0 0 0)
				(effects
					(font
						(size 1.27 1.27)
					)
					(hide yes)
				)
			)
			(symbol "R_4k7_0402_2_0_1"
				(rectangle
					(start 0.635 0.889)
					(end 4.445 -0.889)
					(stroke
						(width 0.254)
						(type default)
					)
					(fill
						(type none)
					)
				)
			)
			(symbol "R_4k7_0402_2_1_1"
				(pin passive line
					(at 0 0 0)
					(length 0.635)
					(name "~"
						(effects
							(font
								(size 1.27 1.27)
							)
						)
					)
					(number "1"
						(effects
							(font
								(size 1.27 1.27)
							)
						)
					)
				)
				(pin passive line
					(at 5.08 0 180)
					(length 0.635)
					(name "~"
						(effects
							(font
								(size 1.27 1.27)
							)
						)
					)
					(number "2"
						(effects
							(font
								(size 1.27 1.27)
							)
						)
					)
				)
			)
		)
	(symbol "R_4k7_0402_3"
			(pin_numbers hide)
			(pin_names hide)
			(exclude_from_sim no)
			(in_bom yes)
			(on_board yes)
			(property "Reference" "R"
				(at 20.32 -5.08 0)
				(effects
					(font
						(size 1.27 1.27)
						(thickness 0.15)
					)
					(justify left bottom)
				)
			)
			(property "Value" "R_4k7_0402"
				(at 20.32 -12.7 0)
				(effects
					(font
						(size 1.27 1.27)
						(thickness 0.15)
					)
					(justify left bottom)
					(hide yes)
				)
			)
			(property "Footprint" "antmicro-footprints:R_0402_1005Metric"
				(at 20.32 -15.24 0)
				(effects
					(font
						(size 1.27 1.27)
						(thickness 0.15)
					)
					(justify left bottom)
					(hide yes)
				)
			)
			(property "Datasheet" "https://www.bourns.com/docs/product-datasheets/cr.pdf"
				(at 20.32 -17.78 0)
				(effects
					(font
						(size 1.27 1.27)
						(thickness 0.15)
					)
					(justify left bottom)
					(hide yes)
				)
			)
			(property "Description" "SMD Chip Resistor, 4.7 kohm, ± 1%, 62.5 mW, 0402 [1005 Metric], Thick Film, General Purpose"
				(at 0 0 0)
				(effects
					(font
						(size 1.27 1.27)
					)
					(hide yes)
				)
			)
			(property "MPN" "CR0402-FX-4701GLF"
				(at 20.32 -20.32 0)
				(effects
					(font
						(size 1.27 1.27)
						(thickness 0.15)
					)
					(justify left bottom)
					(hide yes)
				)
			)
			(property "Manufacturer" "Bourns"
				(at 20.32 -22.86 0)
				(effects
					(font
						(size 1.27 1.27)
						(thickness 0.15)
					)
					(justify left bottom)
					(hide yes)
				)
			)
			(property "License" "Apache-2.0"
				(at 20.32 -25.4 0)
				(effects
					(font
						(size 1.27 1.27)
						(thickness 0.15)
					)
					(justify left bottom)
					(hide yes)
				)
			)
			(property "Author" "Antmicro"
				(at 20.32 -27.94 0)
				(effects
					(font
						(size 1.27 1.27)
						(thickness 0.15)
					)
					(justify left bottom)
					(hide yes)
				)
			)
			(property "Val" "4k7"
				(at 20.32 -7.62 0)
				(effects
					(font
						(size 1.27 1.27)
						(thickness 0.15)
					)
					(justify left bottom)
				)
			)
			(property "Tolerance" "1%"
				(at 20.32 -10.16 0)
				(effects
					(font
						(size 1.27 1.27)
					)
					(justify left bottom)
					(hide yes)
				)
			)
			(property "ki_keywords" "0402, SMT, RESISTOR, PASSIVE"
				(at 0 0 0)
				(effects
					(font
						(size 1.27 1.27)
					)
					(hide yes)
				)
			)
			(symbol "R_4k7_0402_3_0_1"
				(rectangle
					(start 0.635 0.889)
					(end 4.445 -0.889)
					(stroke
						(width 0.254)
						(type default)
					)
					(fill
						(type none)
					)
				)
			)
			(symbol "R_4k7_0402_3_1_1"
				(pin passive line
					(at 0 0 0)
					(length 0.635)
					(name "~"
						(effects
							(font
								(size 1.27 1.27)
							)
						)
					)
					(number "1"
						(effects
							(font
								(size 1.27 1.27)
							)
						)
					)
				)
				(pin passive line
					(at 5.08 0 180)
					(length 0.635)
					(name "~"
						(effects
							(font
								(size 1.27 1.27)
							)
						)
					)
					(number "2"
						(effects
							(font
								(size 1.27 1.27)
							)
						)
					)
				)
			)
		)
	(symbol "R_4k7_0402_4"
			(pin_numbers hide)
			(pin_names hide)
			(exclude_from_sim no)
			(in_bom yes)
			(on_board yes)
			(property "Reference" "R"
				(at 20.32 -5.08 0)
				(effects
					(font
						(size 1.27 1.27)
						(thickness 0.15)
					)
					(justify left bottom)
				)
			)
			(property "Value" "R_4k7_0402"
				(at 20.32 -12.7 0)
				(effects
					(font
						(size 1.27 1.27)
						(thickness 0.15)
					)
					(justify left bottom)
					(hide yes)
				)
			)
			(property "Footprint" "antmicro-footprints:R_0402_1005Metric"
				(at 20.32 -15.24 0)
				(effects
					(font
						(size 1.27 1.27)
						(thickness 0.15)
					)
					(justify left bottom)
					(hide yes)
				)
			)
			(property "Datasheet" "https://www.bourns.com/docs/product-datasheets/cr.pdf"
				(at 20.32 -17.78 0)
				(effects
					(font
						(size 1.27 1.27)
						(thickness 0.15)
					)
					(justify left bottom)
					(hide yes)
				)
			)
			(property "Description" "SMD Chip Resistor, 4.7 kohm, ± 1%, 62.5 mW, 0402 [1005 Metric], Thick Film, General Purpose"
				(at 0 0 0)
				(effects
					(font
						(size 1.27 1.27)
					)
					(hide yes)
				)
			)
			(property "MPN" "CR0402-FX-4701GLF"
				(at 20.32 -20.32 0)
				(effects
					(font
						(size 1.27 1.27)
						(thickness 0.15)
					)
					(justify left bottom)
					(hide yes)
				)
			)
			(property "Manufacturer" "Bourns"
				(at 20.32 -22.86 0)
				(effects
					(font
						(size 1.27 1.27)
						(thickness 0.15)
					)
					(justify left bottom)
					(hide yes)
				)
			)
			(property "License" "Apache-2.0"
				(at 20.32 -25.4 0)
				(effects
					(font
						(size 1.27 1.27)
						(thickness 0.15)
					)
					(justify left bottom)
					(hide yes)
				)
			)
			(property "Author" "Antmicro"
				(at 20.32 -27.94 0)
				(effects
					(font
						(size 1.27 1.27)
						(thickness 0.15)
					)
					(justify left bottom)
					(hide yes)
				)
			)
			(property "Val" "4k7"
				(at 20.32 -7.62 0)
				(effects
					(font
						(size 1.27 1.27)
						(thickness 0.15)
					)
					(justify left bottom)
				)
			)
			(property "Tolerance" "1%"
				(at 20.32 -10.16 0)
				(effects
					(font
						(size 1.27 1.27)
					)
					(justify left bottom)
					(hide yes)
				)
			)
			(property "ki_keywords" "0402, SMT, RESISTOR, PASSIVE"
				(at 0 0 0)
				(effects
					(font
						(size 1.27 1.27)
					)
					(hide yes)
				)
			)
			(symbol "R_4k7_0402_4_0_1"
				(rectangle
					(start 0.635 0.889)
					(end 4.445 -0.889)
					(stroke
						(width 0.254)
						(type default)
					)
					(fill
						(type none)
					)
				)
			)
			(symbol "R_4k7_0402_4_1_1"
				(pin passive line
					(at 0 0 0)
					(length 0.635)
					(name "~"
						(effects
							(font
								(size 1.27 1.27)
							)
						)
					)
					(number "1"
						(effects
							(font
								(size 1.27 1.27)
							)
						)
					)
				)
				(pin passive line
					(at 5.08 0 180)
					(length 0.635)
					(name "~"
						(effects
							(font
								(size 1.27 1.27)
							)
						)
					)
					(number "2"
						(effects
							(font
								(size 1.27 1.27)
							)
						)
					)
				)
			)
		)
	(symbol "R_4k7_0402_5"
			(pin_numbers hide)
			(pin_names hide)
			(exclude_from_sim no)
			(in_bom yes)
			(on_board yes)
			(property "Reference" "R"
				(at 20.32 -5.08 0)
				(effects
					(font
						(size 1.27 1.27)
						(thickness 0.15)
					)
					(justify left bottom)
				)
			)
			(property "Value" "R_4k7_0402"
				(at 20.32 -12.7 0)
				(effects
					(font
						(size 1.27 1.27)
						(thickness 0.15)
					)
					(justify left bottom)
					(hide yes)
				)
			)
			(property "Footprint" "antmicro-footprints:R_0402_1005Metric"
				(at 20.32 -15.24 0)
				(effects
					(font
						(size 1.27 1.27)
						(thickness 0.15)
					)
					(justify left bottom)
					(hide yes)
				)
			)
			(property "Datasheet" "https://www.bourns.com/docs/product-datasheets/cr.pdf"
				(at 20.32 -17.78 0)
				(effects
					(font
						(size 1.27 1.27)
						(thickness 0.15)
					)
					(justify left bottom)
					(hide yes)
				)
			)
			(property "Description" "SMD Chip Resistor, 4.7 kohm, ± 1%, 62.5 mW, 0402 [1005 Metric], Thick Film, General Purpose"
				(at 0 0 0)
				(effects
					(font
						(size 1.27 1.27)
					)
					(hide yes)
				)
			)
			(property "MPN" "CR0402-FX-4701GLF"
				(at 20.32 -20.32 0)
				(effects
					(font
						(size 1.27 1.27)
						(thickness 0.15)
					)
					(justify left bottom)
					(hide yes)
				)
			)
			(property "Manufacturer" "Bourns"
				(at 20.32 -22.86 0)
				(effects
					(font
						(size 1.27 1.27)
						(thickness 0.15)
					)
					(justify left bottom)
					(hide yes)
				)
			)
			(property "License" "Apache-2.0"
				(at 20.32 -25.4 0)
				(effects
					(font
						(size 1.27 1.27)
						(thickness 0.15)
					)
					(justify left bottom)
					(hide yes)
				)
			)
			(property "Author" "Antmicro"
				(at 20.32 -27.94 0)
				(effects
					(font
						(size 1.27 1.27)
						(thickness 0.15)
					)
					(justify left bottom)
					(hide yes)
				)
			)
			(property "Val" "4k7"
				(at 20.32 -7.62 0)
				(effects
					(font
						(size 1.27 1.27)
						(thickness 0.15)
					)
					(justify left bottom)
				)
			)
			(property "Tolerance" "1%"
				(at 20.32 -10.16 0)
				(effects
					(font
						(size 1.27 1.27)
					)
					(justify left bottom)
					(hide yes)
				)
			)
			(property "ki_keywords" "0402, SMT, RESISTOR, PASSIVE"
				(at 0 0 0)
				(effects
					(font
						(size 1.27 1.27)
					)
					(hide yes)
				)
			)
			(symbol "R_4k7_0402_5_0_1"
				(rectangle
					(start 0.635 0.889)
					(end 4.445 -0.889)
					(stroke
						(width 0.254)
						(type default)
					)
					(fill
						(type none)
					)
				)
			)
			(symbol "R_4k7_0402_5_1_1"
				(pin passive line
					(at 0 0 0)
					(length 0.635)
					(name "~"
						(effects
							(font
								(size 1.27 1.27)
							)
						)
					)
					(number "1"
						(effects
							(font
								(size 1.27 1.27)
							)
						)
					)
				)
				(pin passive line
					(at 5.08 0 180)
					(length 0.635)
					(name "~"
						(effects
							(font
								(size 1.27 1.27)
							)
						)
					)
					(number "2"
						(effects
							(font
								(size 1.27 1.27)
							)
						)
					)
				)
			)
		)
	(symbol "SIC431AED-T1-GE3_1"
			(exclude_from_sim no)
			(in_bom yes)
			(on_board yes)
			(property "Reference" "U"
				(at 33.02 -2.54 0)
				(effects
					(font
						(size 1.27 1.27)
						(thickness 0.15)
					)
					(justify left bottom)
				)
			)
			(property "Value" "SIC431AED-T1-GE3"
				(at 33.02 -7.62 0)
				(effects
					(font
						(size 1.27 1.27)
						(thickness 0.15)
					)
					(justify left bottom)
					(hide yes)
				)
			)
			(property "Footprint" "antmicro-footprints:MLP44-24L_4x4x0.75mm"
				(at 33.02 -10.16 0)
				(effects
					(font
						(size 1.27 1.27)
						(thickness 0.15)
					)
					(justify left bottom)
					(hide yes)
				)
			)
			(property "Datasheet" "https://www.vishay.com/docs/74589/sic431.pdf"
				(at 33.02 -12.7 0)
				(effects
					(font
						(size 1.27 1.27)
						(thickness 0.15)
					)
					(justify left bottom)
					(hide yes)
				)
			)
			(property "Description" "DC/DC Synchronous Regulator, Adjustable, 3V to 24VIn, 0.6V to 22V/24AOut, 1MHz, MLP44-24L"
				(at 0 0 0)
				(effects
					(font
						(size 1.27 1.27)
					)
					(hide yes)
				)
			)
			(property "Manufacturer" "Vishay"
				(at 33.02 -15.24 0)
				(effects
					(font
						(size 1.27 1.27)
						(thickness 0.15)
					)
					(justify left bottom)
					(hide yes)
				)
			)
			(property "MPN" "SIC431AED-T1-GE3 "
				(at 33.02 -5.08 0)
				(effects
					(font
						(size 1.27 1.27)
						(thickness 0.15)
					)
					(justify left bottom)
				)
			)
			(property "Author" "Antmicro"
				(at 33.02 -17.78 0)
				(effects
					(font
						(size 1.27 1.27)
						(thickness 0.15)
					)
					(justify left bottom)
					(hide yes)
				)
			)
			(property "License" "Apache-2.0"
				(at 33.02 -20.32 0)
				(effects
					(font
						(size 1.27 1.27)
						(thickness 0.15)
					)
					(justify left bottom)
					(hide yes)
				)
			)
			(property "ki_keywords" "SMT, PMIC, IC, DC-DC, CONVERTER, SWITCHING, VOLTAGE"
				(at 0 0 0)
				(effects
					(font
						(size 1.27 1.27)
					)
					(hide yes)
				)
			)
			(symbol "SIC431AED-T1-GE3_1_1_1"
				(rectangle
					(start 2.54 2.54)
					(end 19.05 -22.86)
					(stroke
						(width 0.254)
						(type default)
					)
					(fill
						(type background)
					)
				)
				(pin power_in line
					(at 0 0 0)
					(length 2.54)
					(name "V_{IN}"
						(effects
							(font
								(size 1.27 1.27)
							)
						)
					)
					(number "1"
						(effects
							(font
								(size 1.27 1.27)
							)
						)
					)
				)
				(pin passive line
					(at 21.59 -7.62 180)
					(length 2.54)
					(name "GL"
						(effects
							(font
								(size 1.27 1.27)
							)
						)
					)
					(number "10"
						(effects
							(font
								(size 1.27 1.27)
							)
						)
					)
				)
				(pin passive line
					(at 21.59 -7.62 180)
					(length 2.54) hide
					(name "GL"
						(effects
							(font
								(size 1.27 1.27)
							)
						)
					)
					(number "11"
						(effects
							(font
								(size 1.27 1.27)
							)
						)
					)
				)
				(pin passive line
					(at 0 -17.78 0)
					(length 2.54)
					(name "V_{DRV}"
						(effects
							(font
								(size 1.27 1.27)
							)
						)
					)
					(number "12"
						(effects
							(font
								(size 1.27 1.27)
							)
						)
					)
				)
				(pin power_in line
					(at 21.59 -20.32 180)
					(length 2.54)
					(name "P_{GND}"
						(effects
							(font
								(size 1.27 1.27)
							)
						)
					)
					(number "13"
						(effects
							(font
								(size 1.27 1.27)
							)
						)
					)
				)
				(pin output line
					(at 0 -20.32 0)
					(length 2.54)
					(name "P_{GOOD}"
						(effects
							(font
								(size 1.27 1.27)
							)
						)
					)
					(number "14"
						(effects
							(font
								(size 1.27 1.27)
							)
						)
					)
				)
				(pin passive line
					(at 0 -15.24 0)
					(length 2.54)
					(name "V_{DD}"
						(effects
							(font
								(size 1.27 1.27)
							)
						)
					)
					(number "15"
						(effects
							(font
								(size 1.27 1.27)
							)
						)
					)
				)
				(pin power_in line
					(at 21.59 -17.78 180)
					(length 2.54)
					(name "A_{GND}"
						(effects
							(font
								(size 1.27 1.27)
							)
						)
					)
					(number "16"
						(effects
							(font
								(size 1.27 1.27)
							)
						)
					)
				)
				(pin passive line
					(at 21.59 -12.7 180)
					(length 2.54)
					(name "FB"
						(effects
							(font
								(size 1.27 1.27)
							)
						)
					)
					(number "17"
						(effects
							(font
								(size 1.27 1.27)
							)
						)
					)
				)
				(pin passive line
					(at 21.59 -10.16 180)
					(length 2.54)
					(name "V_{OUT}"
						(effects
							(font
								(size 1.27 1.27)
							)
						)
					)
					(number "18"
						(effects
							(font
								(size 1.27 1.27)
							)
						)
					)
				)
				(pin input line
					(at 0 -7.62 0)
					(length 2.54)
					(name "EN"
						(effects
							(font
								(size 1.27 1.27)
							)
						)
					)
					(number "19"
						(effects
							(font
								(size 1.27 1.27)
							)
						)
					)
				)
				(pin passive line
					(at 0 0 0)
					(length 2.54) hide
					(name "V_{IN}"
						(effects
							(font
								(size 1.27 1.27)
							)
						)
					)
					(number "2"
						(effects
							(font
								(size 1.27 1.27)
							)
						)
					)
				)
				(pin input line
					(at 0 -12.7 0)
					(length 2.54)
					(name "MODE2"
						(effects
							(font
								(size 1.27 1.27)
							)
						)
					)
					(number "20"
						(effects
							(font
								(size 1.27 1.27)
							)
						)
					)
				)
				(pin input line
					(at 0 -10.16 0)
					(length 2.54)
					(name "MODE1"
						(effects
							(font
								(size 1.27 1.27)
							)
						)
					)
					(number "21"
						(effects
							(font
								(size 1.27 1.27)
							)
						)
					)
				)
				(pin passive line
					(at 0 0 0)
					(length 2.54) hide
					(name "V_{IN}"
						(effects
							(font
								(size 1.27 1.27)
							)
						)
					)
					(number "22"
						(effects
							(font
								(size 1.27 1.27)
							)
						)
					)
				)
				(pin passive line
					(at 21.59 0 180)
					(length 2.54)
					(name "BOOT"
						(effects
							(font
								(size 1.27 1.27)
							)
						)
					)
					(number "23"
						(effects
							(font
								(size 1.27 1.27)
							)
						)
					)
				)
				(pin passive line
					(at 21.59 -2.54 180)
					(length 2.54)
					(name "PHASE"
						(effects
							(font
								(size 1.27 1.27)
							)
						)
					)
					(number "24"
						(effects
							(font
								(size 1.27 1.27)
							)
						)
					)
				)
				(pin passive line
					(at 21.59 -17.78 180)
					(length 2.54) hide
					(name "A_{GND}"
						(effects
							(font
								(size 1.27 1.27)
							)
						)
					)
					(number "25"
						(effects
							(font
								(size 1.27 1.27)
							)
						)
					)
				)
				(pin passive line
					(at 0 0 0)
					(length 2.54) hide
					(name "V_{IN}"
						(effects
							(font
								(size 1.27 1.27)
							)
						)
					)
					(number "26"
						(effects
							(font
								(size 1.27 1.27)
							)
						)
					)
				)
				(pin passive line
					(at 21.59 -20.32 180)
					(length 2.54) hide
					(name "P_{GND}"
						(effects
							(font
								(size 1.27 1.27)
							)
						)
					)
					(number "27"
						(effects
							(font
								(size 1.27 1.27)
							)
						)
					)
				)
				(pin passive line
					(at 21.59 -7.62 180)
					(length 2.54) hide
					(name "GL"
						(effects
							(font
								(size 1.27 1.27)
							)
						)
					)
					(number "28"
						(effects
							(font
								(size 1.27 1.27)
							)
						)
					)
				)
				(pin passive line
					(at 21.59 -20.32 180)
					(length 2.54) hide
					(name "P_{GND}"
						(effects
							(font
								(size 1.27 1.27)
							)
						)
					)
					(number "3"
						(effects
							(font
								(size 1.27 1.27)
							)
						)
					)
				)
				(pin passive line
					(at 21.59 -20.32 180)
					(length 2.54) hide
					(name "P_{GND}"
						(effects
							(font
								(size 1.27 1.27)
							)
						)
					)
					(number "4"
						(effects
							(font
								(size 1.27 1.27)
							)
						)
					)
				)
				(pin passive line
					(at 21.59 -5.08 180)
					(length 2.54)
					(name "SW"
						(effects
							(font
								(size 1.27 1.27)
							)
						)
					)
					(number "5"
						(effects
							(font
								(size 1.27 1.27)
							)
						)
					)
				)
				(pin passive line
					(at 21.59 -5.08 180)
					(length 2.54) hide
					(name "SW"
						(effects
							(font
								(size 1.27 1.27)
							)
						)
					)
					(number "6"
						(effects
							(font
								(size 1.27 1.27)
							)
						)
					)
				)
				(pin passive line
					(at 21.59 -5.08 180)
					(length 2.54) hide
					(name "SW"
						(effects
							(font
								(size 1.27 1.27)
							)
						)
					)
					(number "7"
						(effects
							(font
								(size 1.27 1.27)
							)
						)
					)
				)
				(pin passive line
					(at 21.59 -5.08 180)
					(length 2.54) hide
					(name "SW"
						(effects
							(font
								(size 1.27 1.27)
							)
						)
					)
					(number "8"
						(effects
							(font
								(size 1.27 1.27)
							)
						)
					)
				)
				(pin passive line
					(at 21.59 -5.08 180)
					(length 2.54) hide
					(name "SW"
						(effects
							(font
								(size 1.27 1.27)
							)
						)
					)
					(number "9"
						(effects
							(font
								(size 1.27 1.27)
							)
						)
					)
				)
			)
		)
	(symbol "Spacer_Drill3.7mm_H2.5mm_9774025151R_1"
			(exclude_from_sim no)
			(in_bom yes)
			(on_board yes)
			(property "Reference" "H"
				(at 22.86 -2.54 0)
				(effects
					(font
						(size 1.27 1.27)
						(thickness 0.15)
					)
					(justify left bottom)
				)
			)
			(property "Value" "Spacer_Drill3.7mm_H2.5mm_9774025151R"
				(at 22.86 -5.08 0)
				(effects
					(font
						(size 1.27 1.27)
						(thickness 0.15)
					)
					(justify left bottom)
				)
			)
			(property "Footprint" "antmicro-footprints:Spacer_Drill3.7mm_H2.5mm_9774025151R"
				(at 22.86 -7.62 0)
				(effects
					(font
						(size 1.27 1.27)
						(thickness 0.15)
					)
					(justify left bottom)
					(hide yes)
				)
			)
			(property "Datasheet" "https://www.we-online.com/components/products/datasheet/9774025151R.pdf"
				(at 22.86 -10.16 0)
				(effects
					(font
						(size 1.27 1.27)
						(thickness 0.15)
					)
					(justify left bottom)
					(hide yes)
				)
			)
			(property "Description" "Spacer, SMT, Non Stop, Steel, Swage Round, 5.1 mm x 2.5 mm, M2.5 Thread, WA-SMSI Series"
				(at 0 0 0)
				(effects
					(font
						(size 1.27 1.27)
					)
					(hide yes)
				)
			)
			(property "Manufacturer" "Würth Elektronik"
				(at 22.86 -12.7 0)
				(effects
					(font
						(size 1.27 1.27)
						(thickness 0.15)
					)
					(justify left bottom)
					(hide yes)
				)
			)
			(property "MPN" "9774025151R"
				(at 22.86 -15.24 0)
				(effects
					(font
						(size 1.27 1.27)
						(thickness 0.15)
					)
					(justify left bottom)
					(hide yes)
				)
			)
			(property "Author" "Antmicro"
				(at 22.86 -17.78 0)
				(effects
					(font
						(size 1.27 1.27)
						(thickness 0.15)
					)
					(justify left bottom)
					(hide yes)
				)
			)
			(property "License" "Apache-2.0"
				(at 22.86 -20.32 0)
				(effects
					(font
						(size 1.27 1.27)
						(thickness 0.15)
					)
					(justify left bottom)
					(hide yes)
				)
			)
			(property "ki_keywords" "MECHANICAL, SPACER"
				(at 0 0 0)
				(effects
					(font
						(size 1.27 1.27)
					)
					(hide yes)
				)
			)
			(symbol "Spacer_Drill3.7mm_H2.5mm_9774025151R_1_1_1"
				(rectangle
					(start 2.54 -2.54)
					(end 7.62 2.54)
					(stroke
						(width 0.254)
						(type default)
					)
					(fill
						(type background)
					)
				)
				(rectangle
					(start 3.81 -1.27)
					(end 6.35 1.27)
					(stroke
						(width 0.254)
						(type default)
					)
					(fill
						(type background)
					)
				)
				(pin passive line
					(at 0 0 0)
					(length 2.54)
					(name "~"
						(effects
							(font
								(size 1.27 1.27)
							)
						)
					)
					(number "1"
						(effects
							(font
								(size 1.27 1.27)
							)
						)
					)
				)
			)
		)
	(symbol "TPD4E05U06QDQARQ1_1"
			(exclude_from_sim no)
			(in_bom yes)
			(on_board yes)
			(property "Reference" "U"
				(at 24.13 0 0)
				(effects
					(font
						(size 1.27 1.27)
						(thickness 0.15)
					)
					(justify left bottom)
				)
			)
			(property "Value" "TPD4E05U06QDQARQ1"
				(at 24.13 -10.16 0)
				(effects
					(font
						(size 1.27 1.27)
						(thickness 0.15)
					)
					(justify left bottom)
					(hide yes)
				)
			)
			(property "Footprint" "antmicro-footprints:USON-10_2.5x1mm_P0.5mm"
				(at 24.13 -5.08 0)
				(effects
					(font
						(size 1.27 1.27)
						(thickness 0.15)
					)
					(justify left bottom)
					(hide yes)
				)
			)
			(property "Datasheet" "https://www.ti.com/lit/ds/symlink/tpd4e05u06-q1.pdf?HQS=dis-mous-null-mousermode-dsf-pf-null-wwe&ts=1663591265741&ref_url=https%253A%252F%252Fwww.mouser.com%252F"
				(at 24.13 -7.62 0)
				(effects
					(font
						(size 1.27 1.27)
						(thickness 0.15)
					)
					(justify left bottom)
					(hide yes)
				)
			)
			(property "Description" "TVS diode array, 12 kV, USON-10, 5.5 V, 0.5 pF"
				(at 0 0 0)
				(effects
					(font
						(size 1.27 1.27)
					)
					(hide yes)
				)
			)
			(property "MPN" "TPD4E05U06QDQARQ1"
				(at 24.13 -2.54 0)
				(effects
					(font
						(size 1.27 1.27)
						(thickness 0.15)
					)
					(justify left bottom)
				)
			)
			(property "Manufacturer" "Texas Instruments"
				(at 24.13 -12.7 0)
				(effects
					(font
						(size 1.27 1.27)
						(thickness 0.15)
					)
					(justify left bottom)
					(hide yes)
				)
			)
			(property "Author" "Antmicro"
				(at 24.13 -15.24 0)
				(effects
					(font
						(size 1.27 1.27)
						(thickness 0.15)
					)
					(justify left bottom)
					(hide yes)
				)
			)
			(property "License" "Apache-2.0"
				(at 24.13 -17.78 0)
				(effects
					(font
						(size 1.27 1.27)
						(thickness 0.15)
					)
					(justify left bottom)
					(hide yes)
				)
			)
			(property "ki_keywords" "SMT, DIODE, SEMICONDUCTOR, TVS, ESD"
				(at 0 0 0)
				(effects
					(font
						(size 1.27 1.27)
					)
					(hide yes)
				)
			)
			(symbol "TPD4E05U06QDQARQ1_1_1_1"
				(polyline
					(pts
						(xy 2.54 -7.62) (xy 7.62 -7.62)
					)
					(stroke
						(width 0.254)
						(type default)
					)
					(fill
						(type background)
					)
				)
				(polyline
					(pts
						(xy 2.54 -5.08) (xy 7.62 -5.08)
					)
					(stroke
						(width 0.254)
						(type default)
					)
					(fill
						(type background)
					)
				)
				(polyline
					(pts
						(xy 2.54 -2.54) (xy 7.62 -2.54)
					)
					(stroke
						(width 0.254)
						(type default)
					)
					(fill
						(type background)
					)
				)
				(polyline
					(pts
						(xy 2.54 0) (xy 7.62 0)
					)
					(stroke
						(width 0.254)
						(type default)
					)
					(fill
						(type background)
					)
				)
				(polyline
					(pts
						(xy 7.62 -10.16) (xy 2.54 -10.16)
					)
					(stroke
						(width 0.254)
						(type default)
					)
					(fill
						(type background)
					)
				)
				(polyline
					(pts
						(xy 7.62 0) (xy 7.62 -10.16)
					)
					(stroke
						(width 0.254)
						(type default)
					)
					(fill
						(type background)
					)
				)
				(polyline
					(pts
						(xy 4.826 -8.255) (xy 5.08 -8.001) (xy 5.08 -7.239) (xy 5.334 -6.985)
					)
					(stroke
						(width 0.254)
						(type default)
					)
					(fill
						(type background)
					)
				)
				(polyline
					(pts
						(xy 4.826 -5.715) (xy 5.08 -5.461) (xy 5.08 -4.699) (xy 5.334 -4.445)
					)
					(stroke
						(width 0.254)
						(type default)
					)
					(fill
						(type background)
					)
				)
				(polyline
					(pts
						(xy 4.826 -3.175) (xy 5.08 -2.921) (xy 5.08 -2.159) (xy 5.334 -1.905)
					)
					(stroke
						(width 0.254)
						(type default)
					)
					(fill
						(type background)
					)
				)
				(polyline
					(pts
						(xy 4.826 -0.635) (xy 5.08 -0.381) (xy 5.08 0.381) (xy 5.334 0.635)
					)
					(stroke
						(width 0.254)
						(type default)
					)
					(fill
						(type background)
					)
				)
				(polyline
					(pts
						(xy 5.08 -7.62) (xy 3.81 -8.255) (xy 3.81 -6.985) (xy 5.08 -7.62)
					)
					(stroke
						(width 0.254)
						(type default)
					)
					(fill
						(type background)
					)
				)
				(polyline
					(pts
						(xy 5.08 -5.08) (xy 3.81 -5.715) (xy 3.81 -4.445) (xy 5.08 -5.08)
					)
					(stroke
						(width 0.254)
						(type default)
					)
					(fill
						(type background)
					)
				)
				(polyline
					(pts
						(xy 5.08 -5.08) (xy 6.35 -4.445) (xy 6.35 -5.715) (xy 5.08 -5.08)
					)
					(stroke
						(width 0.254)
						(type default)
					)
					(fill
						(type background)
					)
				)
				(polyline
					(pts
						(xy 5.08 -2.54) (xy 3.81 -3.175) (xy 3.81 -1.905) (xy 5.08 -2.54)
					)
					(stroke
						(width 0.254)
						(type default)
					)
					(fill
						(type background)
					)
				)
				(polyline
					(pts
						(xy 5.08 -2.54) (xy 6.35 -3.175) (xy 6.35 -1.905) (xy 5.08 -2.54)
					)
					(stroke
						(width 0.254)
						(type default)
					)
					(fill
						(type background)
					)
				)
				(polyline
					(pts
						(xy 5.08 0) (xy 3.81 -0.635) (xy 3.81 0.635) (xy 5.08 0)
					)
					(stroke
						(width 0.254)
						(type default)
					)
					(fill
						(type background)
					)
				)
				(polyline
					(pts
						(xy 5.08 0) (xy 6.35 -0.635) (xy 6.35 0.635) (xy 5.08 0)
					)
					(stroke
						(width 0.254)
						(type default)
					)
					(fill
						(type background)
					)
				)
				(polyline
					(pts
						(xy 6.35 -6.985) (xy 6.35 -8.255) (xy 5.08 -7.62) (xy 6.35 -6.985)
					)
					(stroke
						(width 0.254)
						(type default)
					)
					(fill
						(type background)
					)
				)
				(rectangle
					(start 2.54 2.54)
					(end 8.89 -11.43)
					(stroke
						(width 0.254)
						(type default)
					)
					(fill
						(type background)
					)
				)
				(circle
					(center 7.62 -7.62)
					(radius 0.254)
					(stroke
						(width 0.254)
						(type default)
					)
					(fill
						(type background)
					)
				)
				(circle
					(center 7.62 -5.08)
					(radius 0.254)
					(stroke
						(width 0.254)
						(type default)
					)
					(fill
						(type background)
					)
				)
				(circle
					(center 7.62 -5.08)
					(radius 0.254)
					(stroke
						(width 0.254)
						(type default)
					)
					(fill
						(type background)
					)
				)
				(circle
					(center 7.62 -2.54)
					(radius 0.254)
					(stroke
						(width 0.254)
						(type default)
					)
					(fill
						(type background)
					)
				)
				(pin passive line
					(at 0 0 0)
					(length 2.54)
					(name "~"
						(effects
							(font
								(size 1.27 1.27)
							)
						)
					)
					(number "1"
						(effects
							(font
								(size 1.27 1.27)
							)
						)
					)
				)
				(pin passive line
					(at 0 0 0)
					(length 2.54) hide
					(name "~"
						(effects
							(font
								(size 1.27 1.27)
							)
						)
					)
					(number "10"
						(effects
							(font
								(size 1.27 1.27)
							)
						)
					)
				)
				(pin passive line
					(at 0 -2.54 0)
					(length 2.54)
					(name "~"
						(effects
							(font
								(size 1.27 1.27)
							)
						)
					)
					(number "2"
						(effects
							(font
								(size 1.27 1.27)
							)
						)
					)
				)
				(pin power_in line
					(at 0 -10.16 0)
					(length 2.54)
					(name "~"
						(effects
							(font
								(size 1.27 1.27)
							)
						)
					)
					(number "3"
						(effects
							(font
								(size 1.27 1.27)
							)
						)
					)
				)
				(pin passive line
					(at 0 -5.08 0)
					(length 2.54)
					(name "~"
						(effects
							(font
								(size 1.27 1.27)
							)
						)
					)
					(number "4"
						(effects
							(font
								(size 1.27 1.27)
							)
						)
					)
				)
				(pin passive line
					(at 0 -7.62 0)
					(length 2.54)
					(name "~"
						(effects
							(font
								(size 1.27 1.27)
							)
						)
					)
					(number "5"
						(effects
							(font
								(size 1.27 1.27)
							)
						)
					)
				)
				(pin passive line
					(at 0 -7.62 0)
					(length 2.54) hide
					(name "~"
						(effects
							(font
								(size 1.27 1.27)
							)
						)
					)
					(number "6"
						(effects
							(font
								(size 1.27 1.27)
							)
						)
					)
				)
				(pin passive line
					(at 0 -5.08 0)
					(length 2.54) hide
					(name "~"
						(effects
							(font
								(size 1.27 1.27)
							)
						)
					)
					(number "7"
						(effects
							(font
								(size 1.27 1.27)
							)
						)
					)
				)
				(pin passive line
					(at 0 -10.16 0)
					(length 2.54) hide
					(name "~"
						(effects
							(font
								(size 1.27 1.27)
							)
						)
					)
					(number "8"
						(effects
							(font
								(size 1.27 1.27)
							)
						)
					)
				)
				(pin passive line
					(at 0 -2.54 0)
					(length 2.54) hide
					(name "~"
						(effects
							(font
								(size 1.27 1.27)
							)
						)
					)
					(number "9"
						(effects
							(font
								(size 1.27 1.27)
							)
						)
					)
				)
			)
		)
	(symbol "TPS65988DHRSHR_1"
			(exclude_from_sim no)
			(in_bom yes)
			(on_board yes)
			(property "Reference" "U"
				(at 49.53 -2.54 0)
				(effects
					(font
						(size 1.27 1.27)
						(thickness 0.15)
					)
					(justify left bottom)
				)
			)
			(property "Value" "TPS65988DHRSHR"
				(at 49.53 -5.08 0)
				(effects
					(font
						(size 1.27 1.27)
						(thickness 0.15)
					)
					(justify left bottom)
					(hide yes)
				)
			)
			(property "Footprint" "antmicro-footprints:IC_TPS65987DDHRSHR"
				(at 49.53 -7.62 0)
				(effects
					(font
						(size 1.27 1.27)
						(thickness 0.15)
					)
					(justify left bottom)
					(hide yes)
				)
			)
			(property "Datasheet" "https://www.ti.com/lit/ds/symlink/tps65988.pdf?ts=1662726631004&ref_url=https%253A%252F%252Fwww.ti.com%252Fproduct%252FTPS65988"
				(at 49.53 -10.16 0)
				(effects
					(font
						(size 1.27 1.27)
						(thickness 0.15)
					)
					(justify left bottom)
					(hide yes)
				)
			)
			(property "Description" "USB, Type-C Controller PMIC 56-VQFN (7x7)"
				(at 0 0 0)
				(effects
					(font
						(size 1.27 1.27)
					)
					(hide yes)
				)
			)
			(property "MPN" "TPS65988DHRSHR "
				(at 49.53 -12.7 0)
				(effects
					(font
						(size 1.27 1.27)
						(thickness 0.15)
					)
					(justify left bottom)
				)
			)
			(property "Manufacturer" "Texas Instruments"
				(at 49.53 -15.24 0)
				(effects
					(font
						(size 1.27 1.27)
						(thickness 0.15)
					)
					(justify left bottom)
					(hide yes)
				)
			)
			(property "License" "Apache-2.0"
				(at 49.53 -17.78 0)
				(effects
					(font
						(size 1.27 1.27)
						(thickness 0.15)
					)
					(justify left bottom)
					(hide yes)
				)
			)
			(property "Author" "Antmicro"
				(at 49.53 -20.32 0)
				(effects
					(font
						(size 1.27 1.27)
						(thickness 0.15)
					)
					(justify left bottom)
					(hide yes)
				)
			)
			(property "ki_locked" ""
				(at 0 0 0)
				(effects
					(font
						(size 1.27 1.27)
					)
				)
			)
			(property "ki_keywords" "SMT, CONTROLLER, IC, USB"
				(at 0 0 0)
				(effects
					(font
						(size 1.27 1.27)
					)
					(hide yes)
				)
			)
			(symbol "TPS65988DHRSHR_1_1_1"
				(rectangle
					(start 2.54 2.54)
					(end 33.02 -69.85)
					(stroke
						(width 0.254)
						(type default)
					)
					(fill
						(type background)
					)
				)
				(pin input line
					(at 0 -34.29 0)
					(length 2.54)
					(name "ADCIN2"
						(effects
							(font
								(size 1.27 1.27)
							)
						)
					)
					(number "10"
						(effects
							(font
								(size 1.27 1.27)
							)
						)
					)
				)
				(pin bidirectional line
					(at 35.56 0 180)
					(length 2.54)
					(name "GPIO0"
						(effects
							(font
								(size 1.27 1.27)
							)
						)
					)
					(number "16"
						(effects
							(font
								(size 1.27 1.27)
							)
						)
					)
				)
				(pin bidirectional line
					(at 35.56 -2.54 180)
					(length 2.54)
					(name "GPIO1"
						(effects
							(font
								(size 1.27 1.27)
							)
						)
					)
					(number "17"
						(effects
							(font
								(size 1.27 1.27)
							)
						)
					)
				)
				(pin bidirectional line
					(at 35.56 -5.08 180)
					(length 2.54)
					(name "GPIO2"
						(effects
							(font
								(size 1.27 1.27)
							)
						)
					)
					(number "18"
						(effects
							(font
								(size 1.27 1.27)
							)
						)
					)
				)
				(pin power_in line
					(at 0 -64.77 0)
					(length 2.54)
					(name "GND"
						(effects
							(font
								(size 1.27 1.27)
							)
						)
					)
					(number "20"
						(effects
							(font
								(size 1.27 1.27)
							)
						)
					)
				)
				(pin bidirectional line
					(at 35.56 -13.97 180)
					(length 2.54)
					(name "I2C3_SCL/GPIO5"
						(effects
							(font
								(size 1.27 1.27)
							)
						)
					)
					(number "21"
						(effects
							(font
								(size 1.27 1.27)
							)
						)
					)
					(alternate "GPIO5" bidirectional line)
					(alternate "I2C3_SCL" bidirectional line)
				)
				(pin bidirectional line
					(at 35.56 -16.51 180)
					(length 2.54)
					(name "I2C3_SDA/GPIO6"
						(effects
							(font
								(size 1.27 1.27)
							)
						)
					)
					(number "22"
						(effects
							(font
								(size 1.27 1.27)
							)
						)
					)
					(alternate "GPIO6" bidirectional line)
					(alternate "I2C3_SDA" bidirectional line)
				)
				(pin bidirectional line
					(at 35.56 -19.05 180)
					(length 2.54)
					(name "~{I2C3_IRQ}/GPIO7"
						(effects
							(font
								(size 1.27 1.27)
							)
						)
					)
					(number "23"
						(effects
							(font
								(size 1.27 1.27)
							)
						)
					)
					(alternate "GPIO7" bidirectional line)
					(alternate "~{I2C3_IRQ}" bidirectional line)
				)
				(pin bidirectional line
					(at 35.56 -54.61 180)
					(length 2.54)
					(name "I2C1_SCL"
						(effects
							(font
								(size 1.27 1.27)
							)
						)
					)
					(number "27"
						(effects
							(font
								(size 1.27 1.27)
							)
						)
					)
				)
				(pin bidirectional line
					(at 35.56 -57.15 180)
					(length 2.54)
					(name "I2C1_SDA"
						(effects
							(font
								(size 1.27 1.27)
							)
						)
					)
					(number "28"
						(effects
							(font
								(size 1.27 1.27)
							)
						)
					)
				)
				(pin output line
					(at 35.56 -52.07 180)
					(length 2.54)
					(name "~{I2C1_IRQ}"
						(effects
							(font
								(size 1.27 1.27)
							)
						)
					)
					(number "29"
						(effects
							(font
								(size 1.27 1.27)
							)
						)
					)
				)
				(pin bidirectional line
					(at 35.56 -7.62 180)
					(length 2.54)
					(name "GPIO3/HPD1"
						(effects
							(font
								(size 1.27 1.27)
							)
						)
					)
					(number "30"
						(effects
							(font
								(size 1.27 1.27)
							)
						)
					)
					(alternate "GPIO3" bidirectional line)
					(alternate "HPD1" bidirectional line)
				)
				(pin bidirectional line
					(at 35.56 -10.16 180)
					(length 2.54)
					(name "GPIO4/HPD2"
						(effects
							(font
								(size 1.27 1.27)
							)
						)
					)
					(number "31"
						(effects
							(font
								(size 1.27 1.27)
							)
						)
					)
					(alternate "GPIO4" bidirectional line)
					(alternate "HPD2" bidirectional line)
				)
				(pin bidirectional line
					(at 35.56 -64.77 180)
					(length 2.54)
					(name "I2C2_SCL"
						(effects
							(font
								(size 1.27 1.27)
							)
						)
					)
					(number "32"
						(effects
							(font
								(size 1.27 1.27)
							)
						)
					)
				)
				(pin bidirectional line
					(at 35.56 -67.31 180)
					(length 2.54)
					(name "I2C2_SDA"
						(effects
							(font
								(size 1.27 1.27)
							)
						)
					)
					(number "33"
						(effects
							(font
								(size 1.27 1.27)
							)
						)
					)
				)
				(pin output line
					(at 35.56 -62.23 180)
					(length 2.54)
					(name "~{I2C2_IRQ}"
						(effects
							(font
								(size 1.27 1.27)
							)
						)
					)
					(number "34"
						(effects
							(font
								(size 1.27 1.27)
							)
						)
					)
				)
				(pin power_out line
					(at 0 -2.54 0)
					(length 2.54)
					(name "LDO_1V8"
						(effects
							(font
								(size 1.27 1.27)
							)
						)
					)
					(number "35"
						(effects
							(font
								(size 1.27 1.27)
							)
						)
					)
				)
				(pin bidirectional line
					(at 35.56 -22.86 180)
					(length 2.54)
					(name "SPI_POCI/GPIO8"
						(effects
							(font
								(size 1.27 1.27)
							)
						)
					)
					(number "36"
						(effects
							(font
								(size 1.27 1.27)
							)
						)
					)
					(alternate "GPIO8" bidirectional line)
					(alternate "SPI_POCI" bidirectional line)
				)
				(pin bidirectional line
					(at 35.56 -25.4 180)
					(length 2.54)
					(name "SPI_PICO/GPIO9"
						(effects
							(font
								(size 1.27 1.27)
							)
						)
					)
					(number "37"
						(effects
							(font
								(size 1.27 1.27)
							)
						)
					)
					(alternate "GPIO9" bidirectional line)
					(alternate "SPI_PICO" bidirectional line)
				)
				(pin bidirectional line
					(at 35.56 -27.94 180)
					(length 2.54)
					(name "SPI_CLK/GPIO10"
						(effects
							(font
								(size 1.27 1.27)
							)
						)
					)
					(number "38"
						(effects
							(font
								(size 1.27 1.27)
							)
						)
					)
					(alternate "GPIO10" bidirectional line)
					(alternate "SPI_CLK" bidirectional line)
				)
				(pin bidirectional line
					(at 35.56 -30.48 180)
					(length 2.54)
					(name "~{SPI_CS}/GPIO11"
						(effects
							(font
								(size 1.27 1.27)
							)
						)
					)
					(number "39"
						(effects
							(font
								(size 1.27 1.27)
							)
						)
					)
					(alternate "GPIO11" bidirectional line)
					(alternate "~{SPI_CS}" bidirectional line)
				)
				(pin bidirectional line
					(at 35.56 -34.29 180)
					(length 2.54)
					(name "GPIO12"
						(effects
							(font
								(size 1.27 1.27)
							)
						)
					)
					(number "40"
						(effects
							(font
								(size 1.27 1.27)
							)
						)
					)
				)
				(pin bidirectional line
					(at 35.56 -36.83 180)
					(length 2.54)
					(name "GPIO13"
						(effects
							(font
								(size 1.27 1.27)
							)
						)
					)
					(number "41"
						(effects
							(font
								(size 1.27 1.27)
							)
						)
					)
				)
				(pin bidirectional line
					(at 35.56 -39.37 180)
					(length 2.54)
					(name "GPIO14/PWM1"
						(effects
							(font
								(size 1.27 1.27)
							)
						)
					)
					(number "42"
						(effects
							(font
								(size 1.27 1.27)
							)
						)
					)
					(alternate "GPIO14" bidirectional line)
					(alternate "PWM1" output line)
				)
				(pin bidirectional line
					(at 35.56 -41.91 180)
					(length 2.54)
					(name "GPIO15/PWM2"
						(effects
							(font
								(size 1.27 1.27)
							)
						)
					)
					(number "43"
						(effects
							(font
								(size 1.27 1.27)
							)
						)
					)
					(alternate "GPIO15" bidirectional line)
					(alternate "PWM2" output line)
				)
				(pin input line
					(at 0 -13.97 0)
					(length 2.54)
					(name "HRESET"
						(effects
							(font
								(size 1.27 1.27)
							)
						)
					)
					(number "44"
						(effects
							(font
								(size 1.27 1.27)
							)
						)
					)
				)
				(pin bidirectional line
					(at 35.56 -44.45 180)
					(length 2.54)
					(name "GPIO16/PP_EXT1"
						(effects
							(font
								(size 1.27 1.27)
							)
						)
					)
					(number "48"
						(effects
							(font
								(size 1.27 1.27)
							)
						)
					)
					(alternate "GPIO16" bidirectional line)
					(alternate "PP_EXT1" output line)
				)
				(pin bidirectional line
					(at 35.56 -46.99 180)
					(length 2.54)
					(name "GPIO17/PP_EXT2"
						(effects
							(font
								(size 1.27 1.27)
							)
						)
					)
					(number "49"
						(effects
							(font
								(size 1.27 1.27)
							)
						)
					)
					(alternate "GPIO17" bidirectional line)
					(alternate "PP_EXT2" output line)
				)
				(pin power_in line
					(at 0 0 0)
					(length 2.54)
					(name "VIN_3V3"
						(effects
							(font
								(size 1.27 1.27)
							)
						)
					)
					(number "5"
						(effects
							(font
								(size 1.27 1.27)
							)
						)
					)
				)
				(pin passive line
					(at 0 -64.77 0)
					(length 2.54) hide
					(name "GND"
						(effects
							(font
								(size 1.27 1.27)
							)
						)
					)
					(number "51"
						(effects
							(font
								(size 1.27 1.27)
							)
						)
					)
				)
				(pin power_in line
					(at 0 -67.31 0)
					(length 2.54)
					(name "GND_EP"
						(effects
							(font
								(size 1.27 1.27)
							)
						)
					)
					(number "59"
						(effects
							(font
								(size 1.27 1.27)
							)
						)
					)
				)
				(pin input line
					(at 0 -22.86 0)
					(length 2.54)
					(name "ADCIN1"
						(effects
							(font
								(size 1.27 1.27)
							)
						)
					)
					(number "6"
						(effects
							(font
								(size 1.27 1.27)
							)
						)
					)
				)
				(pin power_out line
					(at 0 -5.08 0)
					(length 2.54)
					(name "LDO_3V3"
						(effects
							(font
								(size 1.27 1.27)
							)
						)
					)
					(number "9"
						(effects
							(font
								(size 1.27 1.27)
							)
						)
					)
				)
			)
			(symbol "TPS65988DHRSHR_1_2_1"
				(polyline
					(pts
						(xy 11.303 0) (xy 13.208 0)
					)
					(stroke
						(width 0.254)
						(type default)
					)
					(fill
						(type background)
					)
				)
				(polyline
					(pts
						(xy 13.208 0) (xy 16.002 1.651)
					)
					(stroke
						(width 0.254)
						(type default)
					)
					(fill
						(type background)
					)
				)
				(polyline
					(pts
						(xy 19.177 0) (xy 16.637 0)
					)
					(stroke
						(width 0.254)
						(type default)
					)
					(fill
						(type background)
					)
				)
				(rectangle
					(start 2.54 3.81)
					(end 29.21 -19.05)
					(stroke
						(width 0.254)
						(type default)
					)
					(fill
						(type background)
					)
				)
				(circle
					(center 13.208 0)
					(radius 0.1796)
					(stroke
						(width 0.254)
						(type default)
					)
					(fill
						(type background)
					)
				)
				(circle
					(center 16.637 0)
					(radius 0.1796)
					(stroke
						(width 0.254)
						(type default)
					)
					(fill
						(type background)
					)
				)
				(pin bidirectional line
					(at 31.75 0 180)
					(length 2.54)
					(name "PP_HV1"
						(effects
							(font
								(size 1.27 1.27)
							)
						)
					)
					(number "11"
						(effects
							(font
								(size 1.27 1.27)
							)
						)
					)
				)
				(pin bidirectional line
					(at 0 0 0)
					(length 2.54)
					(name "VBUS1"
						(effects
							(font
								(size 1.27 1.27)
							)
						)
					)
					(number "13"
						(effects
							(font
								(size 1.27 1.27)
							)
						)
					)
				)
				(pin passive line
					(at 31.75 -15.24 180)
					(length 2.54)
					(name "DRAIN1"
						(effects
							(font
								(size 1.27 1.27)
							)
						)
					)
					(number "15"
						(effects
							(font
								(size 1.27 1.27)
							)
						)
					)
				)
				(pin passive line
					(at 31.75 -15.24 180)
					(length 2.54) hide
					(name "DRAIN1"
						(effects
							(font
								(size 1.27 1.27)
							)
						)
					)
					(number "19"
						(effects
							(font
								(size 1.27 1.27)
							)
						)
					)
				)
				(pin bidirectional line
					(at 0 -5.08 0)
					(length 2.54)
					(name "C1_CC1"
						(effects
							(font
								(size 1.27 1.27)
							)
						)
					)
					(number "24"
						(effects
							(font
								(size 1.27 1.27)
							)
						)
					)
				)
				(pin power_in line
					(at 31.75 -3.81 180)
					(length 2.54)
					(name "PP1_CABLE"
						(effects
							(font
								(size 1.27 1.27)
							)
						)
					)
					(number "25"
						(effects
							(font
								(size 1.27 1.27)
							)
						)
					)
				)
				(pin bidirectional line
					(at 0 -7.62 0)
					(length 2.54)
					(name "C1_CC2"
						(effects
							(font
								(size 1.27 1.27)
							)
						)
					)
					(number "26"
						(effects
							(font
								(size 1.27 1.27)
							)
						)
					)
				)
				(pin bidirectional line
					(at 0 -15.24 0)
					(length 2.54)
					(name "C1_USB_P/GPIO18"
						(effects
							(font
								(size 1.27 1.27)
							)
						)
					)
					(number "50"
						(effects
							(font
								(size 1.27 1.27)
							)
						)
					)
					(alternate "C1_USB_P" bidirectional line)
					(alternate "GPIO18" bidirectional line)
				)
				(pin bidirectional line
					(at 0 -12.7 0)
					(length 2.54)
					(name "C1_USB_N/GPIO19"
						(effects
							(font
								(size 1.27 1.27)
							)
						)
					)
					(number "53"
						(effects
							(font
								(size 1.27 1.27)
							)
						)
					)
					(alternate "C1_USB_N" bidirectional line)
					(alternate "GPIO19" bidirectional line)
				)
				(pin passive line
					(at 31.75 -15.24 180)
					(length 2.54) hide
					(name "DRAIN1"
						(effects
							(font
								(size 1.27 1.27)
							)
						)
					)
					(number "58"
						(effects
							(font
								(size 1.27 1.27)
							)
						)
					)
				)
				(pin passive line
					(at 31.75 -15.24 180)
					(length 2.54) hide
					(name "DRAIN1"
						(effects
							(font
								(size 1.27 1.27)
							)
						)
					)
					(number "8"
						(effects
							(font
								(size 1.27 1.27)
							)
						)
					)
				)
			)
			(symbol "TPS65988DHRSHR_1_3_1"
				(polyline
					(pts
						(xy 11.557 0) (xy 13.462 0)
					)
					(stroke
						(width 0.254)
						(type default)
					)
					(fill
						(type background)
					)
				)
				(polyline
					(pts
						(xy 13.462 0) (xy 16.256 1.651)
					)
					(stroke
						(width 0.254)
						(type default)
					)
					(fill
						(type background)
					)
				)
				(polyline
					(pts
						(xy 19.431 0) (xy 16.891 0)
					)
					(stroke
						(width 0.254)
						(type default)
					)
					(fill
						(type background)
					)
				)
				(rectangle
					(start 2.54 3.81)
					(end 29.21 -19.05)
					(stroke
						(width 0.254)
						(type default)
					)
					(fill
						(type background)
					)
				)
				(circle
					(center 13.462 0)
					(radius 0.1796)
					(stroke
						(width 0.254)
						(type default)
					)
					(fill
						(type background)
					)
				)
				(circle
					(center 16.891 0)
					(radius 0.1796)
					(stroke
						(width 0.254)
						(type default)
					)
					(fill
						(type background)
					)
				)
				(pin bidirectional line
					(at 31.75 0 180)
					(length 2.54)
					(name "PP_HV2"
						(effects
							(font
								(size 1.27 1.27)
							)
						)
					)
					(number "1"
						(effects
							(font
								(size 1.27 1.27)
							)
						)
					)
				)
				(pin bidirectional line
					(at 0 0 0)
					(length 2.54)
					(name "VBUS2"
						(effects
							(font
								(size 1.27 1.27)
							)
						)
					)
					(number "3"
						(effects
							(font
								(size 1.27 1.27)
							)
						)
					)
				)
				(pin bidirectional line
					(at 0 -5.08 0)
					(length 2.54)
					(name "C2_CC1"
						(effects
							(font
								(size 1.27 1.27)
							)
						)
					)
					(number "45"
						(effects
							(font
								(size 1.27 1.27)
							)
						)
					)
				)
				(pin power_in line
					(at 31.75 -3.81 180)
					(length 2.54)
					(name "PP2_CABLE"
						(effects
							(font
								(size 1.27 1.27)
							)
						)
					)
					(number "46"
						(effects
							(font
								(size 1.27 1.27)
							)
						)
					)
				)
				(pin bidirectional line
					(at 0 -7.62 0)
					(length 2.54)
					(name "C2_CC2"
						(effects
							(font
								(size 1.27 1.27)
							)
						)
					)
					(number "47"
						(effects
							(font
								(size 1.27 1.27)
							)
						)
					)
				)
				(pin passive line
					(at 31.75 -15.24 180)
					(length 2.54)
					(name "DRAIN2"
						(effects
							(font
								(size 1.27 1.27)
							)
						)
					)
					(number "52"
						(effects
							(font
								(size 1.27 1.27)
							)
						)
					)
				)
				(pin bidirectional line
					(at 0 -15.24 0)
					(length 2.54)
					(name "C2_USB_P/GPIO20"
						(effects
							(font
								(size 1.27 1.27)
							)
						)
					)
					(number "54"
						(effects
							(font
								(size 1.27 1.27)
							)
						)
					)
					(alternate "C2_USB_P" bidirectional line)
					(alternate "GPIO20" bidirectional line)
				)
				(pin bidirectional line
					(at 0 -12.7 0)
					(length 2.54)
					(name "C2_USB_N/GPIO21"
						(effects
							(font
								(size 1.27 1.27)
							)
						)
					)
					(number "55"
						(effects
							(font
								(size 1.27 1.27)
							)
						)
					)
					(alternate "C2_USB_N" bidirectional line)
					(alternate "GPIO21" bidirectional line)
				)
				(pin passive line
					(at 31.75 -15.24 180)
					(length 2.54) hide
					(name "DRAIN2"
						(effects
							(font
								(size 1.27 1.27)
							)
						)
					)
					(number "56"
						(effects
							(font
								(size 1.27 1.27)
							)
						)
					)
				)
				(pin passive line
					(at 31.75 -15.24 180)
					(length 2.54) hide
					(name "DRAIN2"
						(effects
							(font
								(size 1.27 1.27)
							)
						)
					)
					(number "57"
						(effects
							(font
								(size 1.27 1.27)
							)
						)
					)
				)
				(pin passive line
					(at 31.75 -15.24 180)
					(length 2.54) hide
					(name "DRAIN2"
						(effects
							(font
								(size 1.27 1.27)
							)
						)
					)
					(number "7"
						(effects
							(font
								(size 1.27 1.27)
							)
						)
					)
				)
			)
		)
	(symbol "TPS65988DHRSHR_2"
			(exclude_from_sim no)
			(in_bom yes)
			(on_board yes)
			(property "Reference" "U"
				(at 49.53 -2.54 0)
				(effects
					(font
						(size 1.27 1.27)
						(thickness 0.15)
					)
					(justify left bottom)
				)
			)
			(property "Value" "TPS65988DHRSHR"
				(at 49.53 -5.08 0)
				(effects
					(font
						(size 1.27 1.27)
						(thickness 0.15)
					)
					(justify left bottom)
					(hide yes)
				)
			)
			(property "Footprint" "antmicro-footprints:IC_TPS65987DDHRSHR"
				(at 49.53 -7.62 0)
				(effects
					(font
						(size 1.27 1.27)
						(thickness 0.15)
					)
					(justify left bottom)
					(hide yes)
				)
			)
			(property "Datasheet" "https://www.ti.com/lit/ds/symlink/tps65988.pdf?ts=1662726631004&ref_url=https%253A%252F%252Fwww.ti.com%252Fproduct%252FTPS65988"
				(at 49.53 -10.16 0)
				(effects
					(font
						(size 1.27 1.27)
						(thickness 0.15)
					)
					(justify left bottom)
					(hide yes)
				)
			)
			(property "Description" "USB, Type-C Controller PMIC 56-VQFN (7x7)"
				(at 0 0 0)
				(effects
					(font
						(size 1.27 1.27)
					)
					(hide yes)
				)
			)
			(property "MPN" "TPS65988DHRSHR "
				(at 49.53 -12.7 0)
				(effects
					(font
						(size 1.27 1.27)
						(thickness 0.15)
					)
					(justify left bottom)
				)
			)
			(property "Manufacturer" "Texas Instruments"
				(at 49.53 -15.24 0)
				(effects
					(font
						(size 1.27 1.27)
						(thickness 0.15)
					)
					(justify left bottom)
					(hide yes)
				)
			)
			(property "License" "Apache-2.0"
				(at 49.53 -17.78 0)
				(effects
					(font
						(size 1.27 1.27)
						(thickness 0.15)
					)
					(justify left bottom)
					(hide yes)
				)
			)
			(property "Author" "Antmicro"
				(at 49.53 -20.32 0)
				(effects
					(font
						(size 1.27 1.27)
						(thickness 0.15)
					)
					(justify left bottom)
					(hide yes)
				)
			)
			(property "ki_locked" ""
				(at 0 0 0)
				(effects
					(font
						(size 1.27 1.27)
					)
				)
			)
			(property "ki_keywords" "SMT, CONTROLLER, IC, USB"
				(at 0 0 0)
				(effects
					(font
						(size 1.27 1.27)
					)
					(hide yes)
				)
			)
			(symbol "TPS65988DHRSHR_2_1_1"
				(rectangle
					(start 2.54 2.54)
					(end 33.02 -69.85)
					(stroke
						(width 0.254)
						(type default)
					)
					(fill
						(type background)
					)
				)
				(pin input line
					(at 0 -34.29 0)
					(length 2.54)
					(name "ADCIN2"
						(effects
							(font
								(size 1.27 1.27)
							)
						)
					)
					(number "10"
						(effects
							(font
								(size 1.27 1.27)
							)
						)
					)
				)
				(pin bidirectional line
					(at 35.56 0 180)
					(length 2.54)
					(name "GPIO0"
						(effects
							(font
								(size 1.27 1.27)
							)
						)
					)
					(number "16"
						(effects
							(font
								(size 1.27 1.27)
							)
						)
					)
				)
				(pin bidirectional line
					(at 35.56 -2.54 180)
					(length 2.54)
					(name "GPIO1"
						(effects
							(font
								(size 1.27 1.27)
							)
						)
					)
					(number "17"
						(effects
							(font
								(size 1.27 1.27)
							)
						)
					)
				)
				(pin bidirectional line
					(at 35.56 -5.08 180)
					(length 2.54)
					(name "GPIO2"
						(effects
							(font
								(size 1.27 1.27)
							)
						)
					)
					(number "18"
						(effects
							(font
								(size 1.27 1.27)
							)
						)
					)
				)
				(pin power_in line
					(at 0 -64.77 0)
					(length 2.54)
					(name "GND"
						(effects
							(font
								(size 1.27 1.27)
							)
						)
					)
					(number "20"
						(effects
							(font
								(size 1.27 1.27)
							)
						)
					)
				)
				(pin bidirectional line
					(at 35.56 -13.97 180)
					(length 2.54)
					(name "I2C3_SCL/GPIO5"
						(effects
							(font
								(size 1.27 1.27)
							)
						)
					)
					(number "21"
						(effects
							(font
								(size 1.27 1.27)
							)
						)
					)
					(alternate "GPIO5" bidirectional line)
					(alternate "I2C3_SCL" bidirectional line)
				)
				(pin bidirectional line
					(at 35.56 -16.51 180)
					(length 2.54)
					(name "I2C3_SDA/GPIO6"
						(effects
							(font
								(size 1.27 1.27)
							)
						)
					)
					(number "22"
						(effects
							(font
								(size 1.27 1.27)
							)
						)
					)
					(alternate "GPIO6" bidirectional line)
					(alternate "I2C3_SDA" bidirectional line)
				)
				(pin bidirectional line
					(at 35.56 -19.05 180)
					(length 2.54)
					(name "~{I2C3_IRQ}/GPIO7"
						(effects
							(font
								(size 1.27 1.27)
							)
						)
					)
					(number "23"
						(effects
							(font
								(size 1.27 1.27)
							)
						)
					)
					(alternate "GPIO7" bidirectional line)
					(alternate "~{I2C3_IRQ}" bidirectional line)
				)
				(pin bidirectional line
					(at 35.56 -54.61 180)
					(length 2.54)
					(name "I2C1_SCL"
						(effects
							(font
								(size 1.27 1.27)
							)
						)
					)
					(number "27"
						(effects
							(font
								(size 1.27 1.27)
							)
						)
					)
				)
				(pin bidirectional line
					(at 35.56 -57.15 180)
					(length 2.54)
					(name "I2C1_SDA"
						(effects
							(font
								(size 1.27 1.27)
							)
						)
					)
					(number "28"
						(effects
							(font
								(size 1.27 1.27)
							)
						)
					)
				)
				(pin output line
					(at 35.56 -52.07 180)
					(length 2.54)
					(name "~{I2C1_IRQ}"
						(effects
							(font
								(size 1.27 1.27)
							)
						)
					)
					(number "29"
						(effects
							(font
								(size 1.27 1.27)
							)
						)
					)
				)
				(pin bidirectional line
					(at 35.56 -7.62 180)
					(length 2.54)
					(name "GPIO3/HPD1"
						(effects
							(font
								(size 1.27 1.27)
							)
						)
					)
					(number "30"
						(effects
							(font
								(size 1.27 1.27)
							)
						)
					)
					(alternate "GPIO3" bidirectional line)
					(alternate "HPD1" bidirectional line)
				)
				(pin bidirectional line
					(at 35.56 -10.16 180)
					(length 2.54)
					(name "GPIO4/HPD2"
						(effects
							(font
								(size 1.27 1.27)
							)
						)
					)
					(number "31"
						(effects
							(font
								(size 1.27 1.27)
							)
						)
					)
					(alternate "GPIO4" bidirectional line)
					(alternate "HPD2" bidirectional line)
				)
				(pin bidirectional line
					(at 35.56 -64.77 180)
					(length 2.54)
					(name "I2C2_SCL"
						(effects
							(font
								(size 1.27 1.27)
							)
						)
					)
					(number "32"
						(effects
							(font
								(size 1.27 1.27)
							)
						)
					)
				)
				(pin bidirectional line
					(at 35.56 -67.31 180)
					(length 2.54)
					(name "I2C2_SDA"
						(effects
							(font
								(size 1.27 1.27)
							)
						)
					)
					(number "33"
						(effects
							(font
								(size 1.27 1.27)
							)
						)
					)
				)
				(pin output line
					(at 35.56 -62.23 180)
					(length 2.54)
					(name "~{I2C2_IRQ}"
						(effects
							(font
								(size 1.27 1.27)
							)
						)
					)
					(number "34"
						(effects
							(font
								(size 1.27 1.27)
							)
						)
					)
				)
				(pin power_out line
					(at 0 -2.54 0)
					(length 2.54)
					(name "LDO_1V8"
						(effects
							(font
								(size 1.27 1.27)
							)
						)
					)
					(number "35"
						(effects
							(font
								(size 1.27 1.27)
							)
						)
					)
				)
				(pin bidirectional line
					(at 35.56 -22.86 180)
					(length 2.54)
					(name "SPI_POCI/GPIO8"
						(effects
							(font
								(size 1.27 1.27)
							)
						)
					)
					(number "36"
						(effects
							(font
								(size 1.27 1.27)
							)
						)
					)
					(alternate "GPIO8" bidirectional line)
					(alternate "SPI_POCI" bidirectional line)
				)
				(pin bidirectional line
					(at 35.56 -25.4 180)
					(length 2.54)
					(name "SPI_PICO/GPIO9"
						(effects
							(font
								(size 1.27 1.27)
							)
						)
					)
					(number "37"
						(effects
							(font
								(size 1.27 1.27)
							)
						)
					)
					(alternate "GPIO9" bidirectional line)
					(alternate "SPI_PICO" bidirectional line)
				)
				(pin bidirectional line
					(at 35.56 -27.94 180)
					(length 2.54)
					(name "SPI_CLK/GPIO10"
						(effects
							(font
								(size 1.27 1.27)
							)
						)
					)
					(number "38"
						(effects
							(font
								(size 1.27 1.27)
							)
						)
					)
					(alternate "GPIO10" bidirectional line)
					(alternate "SPI_CLK" bidirectional line)
				)
				(pin bidirectional line
					(at 35.56 -30.48 180)
					(length 2.54)
					(name "~{SPI_CS}/GPIO11"
						(effects
							(font
								(size 1.27 1.27)
							)
						)
					)
					(number "39"
						(effects
							(font
								(size 1.27 1.27)
							)
						)
					)
					(alternate "GPIO11" bidirectional line)
					(alternate "~{SPI_CS}" bidirectional line)
				)
				(pin bidirectional line
					(at 35.56 -34.29 180)
					(length 2.54)
					(name "GPIO12"
						(effects
							(font
								(size 1.27 1.27)
							)
						)
					)
					(number "40"
						(effects
							(font
								(size 1.27 1.27)
							)
						)
					)
				)
				(pin bidirectional line
					(at 35.56 -36.83 180)
					(length 2.54)
					(name "GPIO13"
						(effects
							(font
								(size 1.27 1.27)
							)
						)
					)
					(number "41"
						(effects
							(font
								(size 1.27 1.27)
							)
						)
					)
				)
				(pin bidirectional line
					(at 35.56 -39.37 180)
					(length 2.54)
					(name "GPIO14/PWM1"
						(effects
							(font
								(size 1.27 1.27)
							)
						)
					)
					(number "42"
						(effects
							(font
								(size 1.27 1.27)
							)
						)
					)
					(alternate "GPIO14" bidirectional line)
					(alternate "PWM1" output line)
				)
				(pin bidirectional line
					(at 35.56 -41.91 180)
					(length 2.54)
					(name "GPIO15/PWM2"
						(effects
							(font
								(size 1.27 1.27)
							)
						)
					)
					(number "43"
						(effects
							(font
								(size 1.27 1.27)
							)
						)
					)
					(alternate "GPIO15" bidirectional line)
					(alternate "PWM2" output line)
				)
				(pin input line
					(at 0 -13.97 0)
					(length 2.54)
					(name "HRESET"
						(effects
							(font
								(size 1.27 1.27)
							)
						)
					)
					(number "44"
						(effects
							(font
								(size 1.27 1.27)
							)
						)
					)
				)
				(pin bidirectional line
					(at 35.56 -44.45 180)
					(length 2.54)
					(name "GPIO16/PP_EXT1"
						(effects
							(font
								(size 1.27 1.27)
							)
						)
					)
					(number "48"
						(effects
							(font
								(size 1.27 1.27)
							)
						)
					)
					(alternate "GPIO16" bidirectional line)
					(alternate "PP_EXT1" output line)
				)
				(pin bidirectional line
					(at 35.56 -46.99 180)
					(length 2.54)
					(name "GPIO17/PP_EXT2"
						(effects
							(font
								(size 1.27 1.27)
							)
						)
					)
					(number "49"
						(effects
							(font
								(size 1.27 1.27)
							)
						)
					)
					(alternate "GPIO17" bidirectional line)
					(alternate "PP_EXT2" output line)
				)
				(pin power_in line
					(at 0 0 0)
					(length 2.54)
					(name "VIN_3V3"
						(effects
							(font
								(size 1.27 1.27)
							)
						)
					)
					(number "5"
						(effects
							(font
								(size 1.27 1.27)
							)
						)
					)
				)
				(pin passive line
					(at 0 -64.77 0)
					(length 2.54) hide
					(name "GND"
						(effects
							(font
								(size 1.27 1.27)
							)
						)
					)
					(number "51"
						(effects
							(font
								(size 1.27 1.27)
							)
						)
					)
				)
				(pin power_in line
					(at 0 -67.31 0)
					(length 2.54)
					(name "GND_EP"
						(effects
							(font
								(size 1.27 1.27)
							)
						)
					)
					(number "59"
						(effects
							(font
								(size 1.27 1.27)
							)
						)
					)
				)
				(pin input line
					(at 0 -22.86 0)
					(length 2.54)
					(name "ADCIN1"
						(effects
							(font
								(size 1.27 1.27)
							)
						)
					)
					(number "6"
						(effects
							(font
								(size 1.27 1.27)
							)
						)
					)
				)
				(pin power_out line
					(at 0 -5.08 0)
					(length 2.54)
					(name "LDO_3V3"
						(effects
							(font
								(size 1.27 1.27)
							)
						)
					)
					(number "9"
						(effects
							(font
								(size 1.27 1.27)
							)
						)
					)
				)
			)
			(symbol "TPS65988DHRSHR_2_2_1"
				(polyline
					(pts
						(xy 11.303 0) (xy 13.208 0)
					)
					(stroke
						(width 0.254)
						(type default)
					)
					(fill
						(type background)
					)
				)
				(polyline
					(pts
						(xy 13.208 0) (xy 16.002 1.651)
					)
					(stroke
						(width 0.254)
						(type default)
					)
					(fill
						(type background)
					)
				)
				(polyline
					(pts
						(xy 19.177 0) (xy 16.637 0)
					)
					(stroke
						(width 0.254)
						(type default)
					)
					(fill
						(type background)
					)
				)
				(rectangle
					(start 2.54 3.81)
					(end 29.21 -19.05)
					(stroke
						(width 0.254)
						(type default)
					)
					(fill
						(type background)
					)
				)
				(circle
					(center 13.208 0)
					(radius 0.1796)
					(stroke
						(width 0.254)
						(type default)
					)
					(fill
						(type background)
					)
				)
				(circle
					(center 16.637 0)
					(radius 0.1796)
					(stroke
						(width 0.254)
						(type default)
					)
					(fill
						(type background)
					)
				)
				(pin bidirectional line
					(at 31.75 0 180)
					(length 2.54)
					(name "PP_HV1"
						(effects
							(font
								(size 1.27 1.27)
							)
						)
					)
					(number "11"
						(effects
							(font
								(size 1.27 1.27)
							)
						)
					)
				)
				(pin bidirectional line
					(at 0 0 0)
					(length 2.54)
					(name "VBUS1"
						(effects
							(font
								(size 1.27 1.27)
							)
						)
					)
					(number "13"
						(effects
							(font
								(size 1.27 1.27)
							)
						)
					)
				)
				(pin passive line
					(at 31.75 -15.24 180)
					(length 2.54)
					(name "DRAIN1"
						(effects
							(font
								(size 1.27 1.27)
							)
						)
					)
					(number "15"
						(effects
							(font
								(size 1.27 1.27)
							)
						)
					)
				)
				(pin passive line
					(at 31.75 -15.24 180)
					(length 2.54) hide
					(name "DRAIN1"
						(effects
							(font
								(size 1.27 1.27)
							)
						)
					)
					(number "19"
						(effects
							(font
								(size 1.27 1.27)
							)
						)
					)
				)
				(pin bidirectional line
					(at 0 -5.08 0)
					(length 2.54)
					(name "C1_CC1"
						(effects
							(font
								(size 1.27 1.27)
							)
						)
					)
					(number "24"
						(effects
							(font
								(size 1.27 1.27)
							)
						)
					)
				)
				(pin power_in line
					(at 31.75 -3.81 180)
					(length 2.54)
					(name "PP1_CABLE"
						(effects
							(font
								(size 1.27 1.27)
							)
						)
					)
					(number "25"
						(effects
							(font
								(size 1.27 1.27)
							)
						)
					)
				)
				(pin bidirectional line
					(at 0 -7.62 0)
					(length 2.54)
					(name "C1_CC2"
						(effects
							(font
								(size 1.27 1.27)
							)
						)
					)
					(number "26"
						(effects
							(font
								(size 1.27 1.27)
							)
						)
					)
				)
				(pin bidirectional line
					(at 0 -15.24 0)
					(length 2.54)
					(name "C1_USB_P/GPIO18"
						(effects
							(font
								(size 1.27 1.27)
							)
						)
					)
					(number "50"
						(effects
							(font
								(size 1.27 1.27)
							)
						)
					)
					(alternate "C1_USB_P" bidirectional line)
					(alternate "GPIO18" bidirectional line)
				)
				(pin bidirectional line
					(at 0 -12.7 0)
					(length 2.54)
					(name "C1_USB_N/GPIO19"
						(effects
							(font
								(size 1.27 1.27)
							)
						)
					)
					(number "53"
						(effects
							(font
								(size 1.27 1.27)
							)
						)
					)
					(alternate "C1_USB_N" bidirectional line)
					(alternate "GPIO19" bidirectional line)
				)
				(pin passive line
					(at 31.75 -15.24 180)
					(length 2.54) hide
					(name "DRAIN1"
						(effects
							(font
								(size 1.27 1.27)
							)
						)
					)
					(number "58"
						(effects
							(font
								(size 1.27 1.27)
							)
						)
					)
				)
				(pin passive line
					(at 31.75 -15.24 180)
					(length 2.54) hide
					(name "DRAIN1"
						(effects
							(font
								(size 1.27 1.27)
							)
						)
					)
					(number "8"
						(effects
							(font
								(size 1.27 1.27)
							)
						)
					)
				)
			)
			(symbol "TPS65988DHRSHR_2_3_1"
				(polyline
					(pts
						(xy 11.557 0) (xy 13.462 0)
					)
					(stroke
						(width 0.254)
						(type default)
					)
					(fill
						(type background)
					)
				)
				(polyline
					(pts
						(xy 13.462 0) (xy 16.256 1.651)
					)
					(stroke
						(width 0.254)
						(type default)
					)
					(fill
						(type background)
					)
				)
				(polyline
					(pts
						(xy 19.431 0) (xy 16.891 0)
					)
					(stroke
						(width 0.254)
						(type default)
					)
					(fill
						(type background)
					)
				)
				(rectangle
					(start 2.54 3.81)
					(end 29.21 -19.05)
					(stroke
						(width 0.254)
						(type default)
					)
					(fill
						(type background)
					)
				)
				(circle
					(center 13.462 0)
					(radius 0.1796)
					(stroke
						(width 0.254)
						(type default)
					)
					(fill
						(type background)
					)
				)
				(circle
					(center 16.891 0)
					(radius 0.1796)
					(stroke
						(width 0.254)
						(type default)
					)
					(fill
						(type background)
					)
				)
				(pin bidirectional line
					(at 31.75 0 180)
					(length 2.54)
					(name "PP_HV2"
						(effects
							(font
								(size 1.27 1.27)
							)
						)
					)
					(number "1"
						(effects
							(font
								(size 1.27 1.27)
							)
						)
					)
				)
				(pin bidirectional line
					(at 0 0 0)
					(length 2.54)
					(name "VBUS2"
						(effects
							(font
								(size 1.27 1.27)
							)
						)
					)
					(number "3"
						(effects
							(font
								(size 1.27 1.27)
							)
						)
					)
				)
				(pin bidirectional line
					(at 0 -5.08 0)
					(length 2.54)
					(name "C2_CC1"
						(effects
							(font
								(size 1.27 1.27)
							)
						)
					)
					(number "45"
						(effects
							(font
								(size 1.27 1.27)
							)
						)
					)
				)
				(pin power_in line
					(at 31.75 -3.81 180)
					(length 2.54)
					(name "PP2_CABLE"
						(effects
							(font
								(size 1.27 1.27)
							)
						)
					)
					(number "46"
						(effects
							(font
								(size 1.27 1.27)
							)
						)
					)
				)
				(pin bidirectional line
					(at 0 -7.62 0)
					(length 2.54)
					(name "C2_CC2"
						(effects
							(font
								(size 1.27 1.27)
							)
						)
					)
					(number "47"
						(effects
							(font
								(size 1.27 1.27)
							)
						)
					)
				)
				(pin passive line
					(at 31.75 -15.24 180)
					(length 2.54)
					(name "DRAIN2"
						(effects
							(font
								(size 1.27 1.27)
							)
						)
					)
					(number "52"
						(effects
							(font
								(size 1.27 1.27)
							)
						)
					)
				)
				(pin bidirectional line
					(at 0 -15.24 0)
					(length 2.54)
					(name "C2_USB_P/GPIO20"
						(effects
							(font
								(size 1.27 1.27)
							)
						)
					)
					(number "54"
						(effects
							(font
								(size 1.27 1.27)
							)
						)
					)
					(alternate "C2_USB_P" bidirectional line)
					(alternate "GPIO20" bidirectional line)
				)
				(pin bidirectional line
					(at 0 -12.7 0)
					(length 2.54)
					(name "C2_USB_N/GPIO21"
						(effects
							(font
								(size 1.27 1.27)
							)
						)
					)
					(number "55"
						(effects
							(font
								(size 1.27 1.27)
							)
						)
					)
					(alternate "C2_USB_N" bidirectional line)
					(alternate "GPIO21" bidirectional line)
				)
				(pin passive line
					(at 31.75 -15.24 180)
					(length 2.54) hide
					(name "DRAIN2"
						(effects
							(font
								(size 1.27 1.27)
							)
						)
					)
					(number "56"
						(effects
							(font
								(size 1.27 1.27)
							)
						)
					)
				)
				(pin passive line
					(at 31.75 -15.24 180)
					(length 2.54) hide
					(name "DRAIN2"
						(effects
							(font
								(size 1.27 1.27)
							)
						)
					)
					(number "57"
						(effects
							(font
								(size 1.27 1.27)
							)
						)
					)
				)
				(pin passive line
					(at 31.75 -15.24 180)
					(length 2.54) hide
					(name "DRAIN2"
						(effects
							(font
								(size 1.27 1.27)
							)
						)
					)
					(number "7"
						(effects
							(font
								(size 1.27 1.27)
							)
						)
					)
				)
			)
		)
	(symbol "TP_0.75mm_SMD_1"
			(pin_names hide)
			(exclude_from_sim no)
			(in_bom no)
			(on_board yes)
			(property "Reference" "TP"
				(at 10.16 -1.27 0)
				(effects
					(font
						(size 1.27 1.27)
						(thickness 0.15)
					)
					(justify left bottom)
				)
			)
			(property "Value" "TP_0.75mm_SMD"
				(at 10.16 -3.81 0)
				(effects
					(font
						(size 1.27 1.27)
						(thickness 0.15)
					)
					(justify left bottom)
					(hide yes)
				)
			)
			(property "Footprint" "antmicro-footprints:TP_SMD_0.75mm"
				(at 10.16 -6.35 0)
				(effects
					(font
						(size 1.27 1.27)
						(thickness 0.15)
					)
					(justify left bottom)
					(hide yes)
				)
			)
			(property "Datasheet" ""
				(at 17.78 -12.7 0)
				(effects
					(font
						(size 1.27 1.27)
						(thickness 0.15)
					)
					(justify left bottom)
					(hide yes)
				)
			)
			(property "Description" "SMT test point"
				(at 0 0 0)
				(effects
					(font
						(size 1.27 1.27)
					)
					(hide yes)
				)
			)
			(property "MPN" ""
				(at 10.795 -11.43 0)
				(effects
					(font
						(size 1.27 1.27)
						(thickness 0.15)
					)
					(justify left bottom)
					(hide yes)
				)
			)
			(property "Manufacturer" ""
				(at 10.795 -6.35 0)
				(effects
					(font
						(size 1.27 1.27)
						(thickness 0.15)
					)
					(justify left bottom)
					(hide yes)
				)
			)
			(property "Author" "Antmicro"
				(at 10.16 -8.89 0)
				(effects
					(font
						(size 1.27 1.27)
						(thickness 0.15)
					)
					(justify left bottom)
					(hide yes)
				)
			)
			(property "License" "Apache-2.0"
				(at 10.16 -11.43 0)
				(effects
					(font
						(size 1.27 1.27)
						(thickness 0.15)
					)
					(justify left bottom)
					(hide yes)
				)
			)
			(property "ki_keywords" "TESTPOINT"
				(at 0 0 0)
				(effects
					(font
						(size 1.27 1.27)
					)
					(hide yes)
				)
			)
			(symbol "TP_0.75mm_SMD_1_1_1"
				(circle
					(center 3.175 0)
					(radius 0.635)
					(stroke
						(width 0.254)
						(type default)
					)
					(fill
						(type none)
					)
				)
				(pin passive line
					(at 0 0 0)
					(length 2.54)
					(name "1"
						(effects
							(font
								(size 1.27 1.27)
							)
						)
					)
					(number "1"
						(effects
							(font
								(size 1.27 1.27)
							)
						)
					)
				)
			)
		)
	(symbol "TP_0.75mm_SMD_10"
			(pin_names hide)
			(exclude_from_sim no)
			(in_bom no)
			(on_board yes)
			(property "Reference" "TP"
				(at 10.16 -1.27 0)
				(effects
					(font
						(size 1.27 1.27)
						(thickness 0.15)
					)
					(justify left bottom)
				)
			)
			(property "Value" "TP_0.75mm_SMD"
				(at 10.16 -3.81 0)
				(effects
					(font
						(size 1.27 1.27)
						(thickness 0.15)
					)
					(justify left bottom)
					(hide yes)
				)
			)
			(property "Footprint" "antmicro-footprints:TP_SMD_0.75mm"
				(at 10.16 -6.35 0)
				(effects
					(font
						(size 1.27 1.27)
						(thickness 0.15)
					)
					(justify left bottom)
					(hide yes)
				)
			)
			(property "Datasheet" ""
				(at 17.78 -12.7 0)
				(effects
					(font
						(size 1.27 1.27)
						(thickness 0.15)
					)
					(justify left bottom)
					(hide yes)
				)
			)
			(property "Description" "SMT test point"
				(at 0 0 0)
				(effects
					(font
						(size 1.27 1.27)
					)
					(hide yes)
				)
			)
			(property "MPN" ""
				(at 10.795 -11.43 0)
				(effects
					(font
						(size 1.27 1.27)
						(thickness 0.15)
					)
					(justify left bottom)
					(hide yes)
				)
			)
			(property "Manufacturer" ""
				(at 10.795 -6.35 0)
				(effects
					(font
						(size 1.27 1.27)
						(thickness 0.15)
					)
					(justify left bottom)
					(hide yes)
				)
			)
			(property "Author" "Antmicro"
				(at 10.16 -8.89 0)
				(effects
					(font
						(size 1.27 1.27)
						(thickness 0.15)
					)
					(justify left bottom)
					(hide yes)
				)
			)
			(property "License" "Apache-2.0"
				(at 10.16 -11.43 0)
				(effects
					(font
						(size 1.27 1.27)
						(thickness 0.15)
					)
					(justify left bottom)
					(hide yes)
				)
			)
			(property "ki_keywords" "TESTPOINT"
				(at 0 0 0)
				(effects
					(font
						(size 1.27 1.27)
					)
					(hide yes)
				)
			)
			(symbol "TP_0.75mm_SMD_10_1_1"
				(circle
					(center 3.175 0)
					(radius 0.635)
					(stroke
						(width 0.254)
						(type default)
					)
					(fill
						(type none)
					)
				)
				(pin passive line
					(at 0 0 0)
					(length 2.54)
					(name "1"
						(effects
							(font
								(size 1.27 1.27)
							)
						)
					)
					(number "1"
						(effects
							(font
								(size 1.27 1.27)
							)
						)
					)
				)
			)
		)
	(symbol "TP_0.75mm_SMD_2"
			(pin_names hide)
			(exclude_from_sim no)
			(in_bom no)
			(on_board yes)
			(property "Reference" "TP"
				(at 10.16 -1.27 0)
				(effects
					(font
						(size 1.27 1.27)
						(thickness 0.15)
					)
					(justify left bottom)
				)
			)
			(property "Value" "TP_0.75mm_SMD"
				(at 10.16 -3.81 0)
				(effects
					(font
						(size 1.27 1.27)
						(thickness 0.15)
					)
					(justify left bottom)
					(hide yes)
				)
			)
			(property "Footprint" "antmicro-footprints:TP_SMD_0.75mm"
				(at 10.16 -6.35 0)
				(effects
					(font
						(size 1.27 1.27)
						(thickness 0.15)
					)
					(justify left bottom)
					(hide yes)
				)
			)
			(property "Datasheet" ""
				(at 17.78 -12.7 0)
				(effects
					(font
						(size 1.27 1.27)
						(thickness 0.15)
					)
					(justify left bottom)
					(hide yes)
				)
			)
			(property "Description" "SMT test point"
				(at 0 0 0)
				(effects
					(font
						(size 1.27 1.27)
					)
					(hide yes)
				)
			)
			(property "MPN" ""
				(at 10.795 -11.43 0)
				(effects
					(font
						(size 1.27 1.27)
						(thickness 0.15)
					)
					(justify left bottom)
					(hide yes)
				)
			)
			(property "Manufacturer" ""
				(at 10.795 -6.35 0)
				(effects
					(font
						(size 1.27 1.27)
						(thickness 0.15)
					)
					(justify left bottom)
					(hide yes)
				)
			)
			(property "Author" "Antmicro"
				(at 10.16 -8.89 0)
				(effects
					(font
						(size 1.27 1.27)
						(thickness 0.15)
					)
					(justify left bottom)
					(hide yes)
				)
			)
			(property "License" "Apache-2.0"
				(at 10.16 -11.43 0)
				(effects
					(font
						(size 1.27 1.27)
						(thickness 0.15)
					)
					(justify left bottom)
					(hide yes)
				)
			)
			(property "ki_keywords" "TESTPOINT"
				(at 0 0 0)
				(effects
					(font
						(size 1.27 1.27)
					)
					(hide yes)
				)
			)
			(symbol "TP_0.75mm_SMD_2_1_1"
				(circle
					(center 3.175 0)
					(radius 0.635)
					(stroke
						(width 0.254)
						(type default)
					)
					(fill
						(type none)
					)
				)
				(pin passive line
					(at 0 0 0)
					(length 2.54)
					(name "1"
						(effects
							(font
								(size 1.27 1.27)
							)
						)
					)
					(number "1"
						(effects
							(font
								(size 1.27 1.27)
							)
						)
					)
				)
			)
		)
	(symbol "TP_0.75mm_SMD_3"
			(pin_names hide)
			(exclude_from_sim no)
			(in_bom no)
			(on_board yes)
			(property "Reference" "TP"
				(at 10.16 -1.27 0)
				(effects
					(font
						(size 1.27 1.27)
						(thickness 0.15)
					)
					(justify left bottom)
				)
			)
			(property "Value" "TP_0.75mm_SMD"
				(at 10.16 -3.81 0)
				(effects
					(font
						(size 1.27 1.27)
						(thickness 0.15)
					)
					(justify left bottom)
					(hide yes)
				)
			)
			(property "Footprint" "antmicro-footprints:TP_SMD_0.75mm"
				(at 10.16 -6.35 0)
				(effects
					(font
						(size 1.27 1.27)
						(thickness 0.15)
					)
					(justify left bottom)
					(hide yes)
				)
			)
			(property "Datasheet" ""
				(at 17.78 -12.7 0)
				(effects
					(font
						(size 1.27 1.27)
						(thickness 0.15)
					)
					(justify left bottom)
					(hide yes)
				)
			)
			(property "Description" "SMT test point"
				(at 0 0 0)
				(effects
					(font
						(size 1.27 1.27)
					)
					(hide yes)
				)
			)
			(property "MPN" ""
				(at 10.795 -11.43 0)
				(effects
					(font
						(size 1.27 1.27)
						(thickness 0.15)
					)
					(justify left bottom)
					(hide yes)
				)
			)
			(property "Manufacturer" ""
				(at 10.795 -6.35 0)
				(effects
					(font
						(size 1.27 1.27)
						(thickness 0.15)
					)
					(justify left bottom)
					(hide yes)
				)
			)
			(property "Author" "Antmicro"
				(at 10.16 -8.89 0)
				(effects
					(font
						(size 1.27 1.27)
						(thickness 0.15)
					)
					(justify left bottom)
					(hide yes)
				)
			)
			(property "License" "Apache-2.0"
				(at 10.16 -11.43 0)
				(effects
					(font
						(size 1.27 1.27)
						(thickness 0.15)
					)
					(justify left bottom)
					(hide yes)
				)
			)
			(property "ki_keywords" "TESTPOINT"
				(at 0 0 0)
				(effects
					(font
						(size 1.27 1.27)
					)
					(hide yes)
				)
			)
			(symbol "TP_0.75mm_SMD_3_1_1"
				(circle
					(center 3.175 0)
					(radius 0.635)
					(stroke
						(width 0.254)
						(type default)
					)
					(fill
						(type none)
					)
				)
				(pin passive line
					(at 0 0 0)
					(length 2.54)
					(name "1"
						(effects
							(font
								(size 1.27 1.27)
							)
						)
					)
					(number "1"
						(effects
							(font
								(size 1.27 1.27)
							)
						)
					)
				)
			)
		)
	(symbol "TP_0.75mm_SMD_4"
			(pin_names hide)
			(exclude_from_sim no)
			(in_bom no)
			(on_board yes)
			(property "Reference" "TP"
				(at 10.16 -1.27 0)
				(effects
					(font
						(size 1.27 1.27)
						(thickness 0.15)
					)
					(justify left bottom)
				)
			)
			(property "Value" "TP_0.75mm_SMD"
				(at 10.16 -3.81 0)
				(effects
					(font
						(size 1.27 1.27)
						(thickness 0.15)
					)
					(justify left bottom)
					(hide yes)
				)
			)
			(property "Footprint" "antmicro-footprints:TP_SMD_0.75mm"
				(at 10.16 -6.35 0)
				(effects
					(font
						(size 1.27 1.27)
						(thickness 0.15)
					)
					(justify left bottom)
					(hide yes)
				)
			)
			(property "Datasheet" ""
				(at 17.78 -12.7 0)
				(effects
					(font
						(size 1.27 1.27)
						(thickness 0.15)
					)
					(justify left bottom)
					(hide yes)
				)
			)
			(property "Description" "SMT test point"
				(at 0 0 0)
				(effects
					(font
						(size 1.27 1.27)
					)
					(hide yes)
				)
			)
			(property "MPN" ""
				(at 10.795 -11.43 0)
				(effects
					(font
						(size 1.27 1.27)
						(thickness 0.15)
					)
					(justify left bottom)
					(hide yes)
				)
			)
			(property "Manufacturer" ""
				(at 10.795 -6.35 0)
				(effects
					(font
						(size 1.27 1.27)
						(thickness 0.15)
					)
					(justify left bottom)
					(hide yes)
				)
			)
			(property "Author" "Antmicro"
				(at 10.16 -8.89 0)
				(effects
					(font
						(size 1.27 1.27)
						(thickness 0.15)
					)
					(justify left bottom)
					(hide yes)
				)
			)
			(property "License" "Apache-2.0"
				(at 10.16 -11.43 0)
				(effects
					(font
						(size 1.27 1.27)
						(thickness 0.15)
					)
					(justify left bottom)
					(hide yes)
				)
			)
			(property "ki_keywords" "TESTPOINT"
				(at 0 0 0)
				(effects
					(font
						(size 1.27 1.27)
					)
					(hide yes)
				)
			)
			(symbol "TP_0.75mm_SMD_4_1_1"
				(circle
					(center 3.175 0)
					(radius 0.635)
					(stroke
						(width 0.254)
						(type default)
					)
					(fill
						(type none)
					)
				)
				(pin passive line
					(at 0 0 0)
					(length 2.54)
					(name "1"
						(effects
							(font
								(size 1.27 1.27)
							)
						)
					)
					(number "1"
						(effects
							(font
								(size 1.27 1.27)
							)
						)
					)
				)
			)
		)
	(symbol "TP_0.75mm_SMD_5"
			(pin_names hide)
			(exclude_from_sim no)
			(in_bom no)
			(on_board yes)
			(property "Reference" "TP"
				(at 10.16 -1.27 0)
				(effects
					(font
						(size 1.27 1.27)
						(thickness 0.15)
					)
					(justify left bottom)
				)
			)
			(property "Value" "TP_0.75mm_SMD"
				(at 10.16 -3.81 0)
				(effects
					(font
						(size 1.27 1.27)
						(thickness 0.15)
					)
					(justify left bottom)
					(hide yes)
				)
			)
			(property "Footprint" "antmicro-footprints:TP_SMD_0.75mm"
				(at 10.16 -6.35 0)
				(effects
					(font
						(size 1.27 1.27)
						(thickness 0.15)
					)
					(justify left bottom)
					(hide yes)
				)
			)
			(property "Datasheet" ""
				(at 17.78 -12.7 0)
				(effects
					(font
						(size 1.27 1.27)
						(thickness 0.15)
					)
					(justify left bottom)
					(hide yes)
				)
			)
			(property "Description" "SMT test point"
				(at 0 0 0)
				(effects
					(font
						(size 1.27 1.27)
					)
					(hide yes)
				)
			)
			(property "MPN" ""
				(at 10.795 -11.43 0)
				(effects
					(font
						(size 1.27 1.27)
						(thickness 0.15)
					)
					(justify left bottom)
					(hide yes)
				)
			)
			(property "Manufacturer" ""
				(at 10.795 -6.35 0)
				(effects
					(font
						(size 1.27 1.27)
						(thickness 0.15)
					)
					(justify left bottom)
					(hide yes)
				)
			)
			(property "Author" "Antmicro"
				(at 10.16 -8.89 0)
				(effects
					(font
						(size 1.27 1.27)
						(thickness 0.15)
					)
					(justify left bottom)
					(hide yes)
				)
			)
			(property "License" "Apache-2.0"
				(at 10.16 -11.43 0)
				(effects
					(font
						(size 1.27 1.27)
						(thickness 0.15)
					)
					(justify left bottom)
					(hide yes)
				)
			)
			(property "ki_keywords" "TESTPOINT"
				(at 0 0 0)
				(effects
					(font
						(size 1.27 1.27)
					)
					(hide yes)
				)
			)
			(symbol "TP_0.75mm_SMD_5_1_1"
				(circle
					(center 3.175 0)
					(radius 0.635)
					(stroke
						(width 0.254)
						(type default)
					)
					(fill
						(type none)
					)
				)
				(pin passive line
					(at 0 0 0)
					(length 2.54)
					(name "1"
						(effects
							(font
								(size 1.27 1.27)
							)
						)
					)
					(number "1"
						(effects
							(font
								(size 1.27 1.27)
							)
						)
					)
				)
			)
		)
	(symbol "TP_0.75mm_SMD_6"
			(pin_names hide)
			(exclude_from_sim no)
			(in_bom no)
			(on_board yes)
			(property "Reference" "TP"
				(at 10.16 -1.27 0)
				(effects
					(font
						(size 1.27 1.27)
						(thickness 0.15)
					)
					(justify left bottom)
				)
			)
			(property "Value" "TP_0.75mm_SMD"
				(at 10.16 -3.81 0)
				(effects
					(font
						(size 1.27 1.27)
						(thickness 0.15)
					)
					(justify left bottom)
					(hide yes)
				)
			)
			(property "Footprint" "antmicro-footprints:TP_SMD_0.75mm"
				(at 10.16 -6.35 0)
				(effects
					(font
						(size 1.27 1.27)
						(thickness 0.15)
					)
					(justify left bottom)
					(hide yes)
				)
			)
			(property "Datasheet" ""
				(at 17.78 -12.7 0)
				(effects
					(font
						(size 1.27 1.27)
						(thickness 0.15)
					)
					(justify left bottom)
					(hide yes)
				)
			)
			(property "Description" "SMT test point"
				(at 0 0 0)
				(effects
					(font
						(size 1.27 1.27)
					)
					(hide yes)
				)
			)
			(property "MPN" ""
				(at 10.795 -11.43 0)
				(effects
					(font
						(size 1.27 1.27)
						(thickness 0.15)
					)
					(justify left bottom)
					(hide yes)
				)
			)
			(property "Manufacturer" ""
				(at 10.795 -6.35 0)
				(effects
					(font
						(size 1.27 1.27)
						(thickness 0.15)
					)
					(justify left bottom)
					(hide yes)
				)
			)
			(property "Author" "Antmicro"
				(at 10.16 -8.89 0)
				(effects
					(font
						(size 1.27 1.27)
						(thickness 0.15)
					)
					(justify left bottom)
					(hide yes)
				)
			)
			(property "License" "Apache-2.0"
				(at 10.16 -11.43 0)
				(effects
					(font
						(size 1.27 1.27)
						(thickness 0.15)
					)
					(justify left bottom)
					(hide yes)
				)
			)
			(property "ki_keywords" "TESTPOINT"
				(at 0 0 0)
				(effects
					(font
						(size 1.27 1.27)
					)
					(hide yes)
				)
			)
			(symbol "TP_0.75mm_SMD_6_1_1"
				(circle
					(center 3.175 0)
					(radius 0.635)
					(stroke
						(width 0.254)
						(type default)
					)
					(fill
						(type none)
					)
				)
				(pin passive line
					(at 0 0 0)
					(length 2.54)
					(name "1"
						(effects
							(font
								(size 1.27 1.27)
							)
						)
					)
					(number "1"
						(effects
							(font
								(size 1.27 1.27)
							)
						)
					)
				)
			)
		)
	(symbol "TP_0.75mm_SMD_7"
			(pin_names hide)
			(exclude_from_sim no)
			(in_bom no)
			(on_board yes)
			(property "Reference" "TP"
				(at 10.16 -1.27 0)
				(effects
					(font
						(size 1.27 1.27)
						(thickness 0.15)
					)
					(justify left bottom)
				)
			)
			(property "Value" "TP_0.75mm_SMD"
				(at 10.16 -3.81 0)
				(effects
					(font
						(size 1.27 1.27)
						(thickness 0.15)
					)
					(justify left bottom)
					(hide yes)
				)
			)
			(property "Footprint" "antmicro-footprints:TP_SMD_0.75mm"
				(at 10.16 -6.35 0)
				(effects
					(font
						(size 1.27 1.27)
						(thickness 0.15)
					)
					(justify left bottom)
					(hide yes)
				)
			)
			(property "Datasheet" ""
				(at 17.78 -12.7 0)
				(effects
					(font
						(size 1.27 1.27)
						(thickness 0.15)
					)
					(justify left bottom)
					(hide yes)
				)
			)
			(property "Description" "SMT test point"
				(at 0 0 0)
				(effects
					(font
						(size 1.27 1.27)
					)
					(hide yes)
				)
			)
			(property "MPN" ""
				(at 10.795 -11.43 0)
				(effects
					(font
						(size 1.27 1.27)
						(thickness 0.15)
					)
					(justify left bottom)
					(hide yes)
				)
			)
			(property "Manufacturer" ""
				(at 10.795 -6.35 0)
				(effects
					(font
						(size 1.27 1.27)
						(thickness 0.15)
					)
					(justify left bottom)
					(hide yes)
				)
			)
			(property "Author" "Antmicro"
				(at 10.16 -8.89 0)
				(effects
					(font
						(size 1.27 1.27)
						(thickness 0.15)
					)
					(justify left bottom)
					(hide yes)
				)
			)
			(property "License" "Apache-2.0"
				(at 10.16 -11.43 0)
				(effects
					(font
						(size 1.27 1.27)
						(thickness 0.15)
					)
					(justify left bottom)
					(hide yes)
				)
			)
			(property "ki_keywords" "TESTPOINT"
				(at 0 0 0)
				(effects
					(font
						(size 1.27 1.27)
					)
					(hide yes)
				)
			)
			(symbol "TP_0.75mm_SMD_7_1_1"
				(circle
					(center 3.175 0)
					(radius 0.635)
					(stroke
						(width 0.254)
						(type default)
					)
					(fill
						(type none)
					)
				)
				(pin passive line
					(at 0 0 0)
					(length 2.54)
					(name "1"
						(effects
							(font
								(size 1.27 1.27)
							)
						)
					)
					(number "1"
						(effects
							(font
								(size 1.27 1.27)
							)
						)
					)
				)
			)
		)
	(symbol "Tag-Connect_TC2050-IDC-NL_2x5_P1.27mm_1"
			(exclude_from_sim no)
			(in_bom no)
			(on_board yes)
			(property "Reference" "J"
				(at 38.1 -1.27 0)
				(effects
					(font
						(size 1.27 1.27)
						(thickness 0.15)
					)
					(justify left bottom)
				)
			)
			(property "Value" "Tag-Connect_TC2050-IDC-NL_2x5_P1.27mm"
				(at 38.1 -3.81 0)
				(effects
					(font
						(size 1.27 1.27)
						(thickness 0.15)
					)
					(justify left bottom)
					(hide yes)
				)
			)
			(property "Footprint" "antmicro-footprints:Tag-Connect_TC2050-IDC-NL_2x5_P1.27mm"
				(at 38.1 -6.35 0)
				(effects
					(font
						(size 1.27 1.27)
						(thickness 0.15)
					)
					(justify left bottom)
					(hide yes)
				)
			)
			(property "Datasheet" "https://www.tag-connect.com/wp-content/uploads/bsk-pdf-manager/TC2050-IDC-NL_Datasheet_8.pdf"
				(at 38.1 -8.89 0)
				(effects
					(font
						(size 1.27 1.27)
						(thickness 0.15)
					)
					(justify left bottom)
					(hide yes)
				)
			)
			(property "Description" "Tag Connect 2x5 1.27mm terminal"
				(at 0 0 0)
				(effects
					(font
						(size 1.27 1.27)
					)
					(hide yes)
				)
			)
			(property "MPN" "TC2050-IDC-NL"
				(at 38.1 -11.43 0)
				(effects
					(font
						(size 1.27 1.27)
						(thickness 0.15)
					)
					(justify left bottom)
				)
			)
			(property "Manufacturer" "Tag Connect"
				(at 38.1 -13.97 0)
				(effects
					(font
						(size 1.27 1.27)
						(thickness 0.15)
					)
					(justify left bottom)
					(hide yes)
				)
			)
			(property "Author" "Antmicro"
				(at 38.1 -16.51 0)
				(effects
					(font
						(size 1.27 1.27)
						(thickness 0.15)
					)
					(justify left bottom)
					(hide yes)
				)
			)
			(property "License" "Apache-2.0"
				(at 38.1 -19.05 0)
				(effects
					(font
						(size 1.27 1.27)
						(thickness 0.15)
					)
					(justify left bottom)
					(hide yes)
				)
			)
			(property "ki_keywords" "POGO-PIN, CONNECTOR"
				(at 0 0 0)
				(effects
					(font
						(size 1.27 1.27)
					)
					(hide yes)
				)
			)
			(symbol "Tag-Connect_TC2050-IDC-NL_2x5_P1.27mm_1_1_1"
				(polyline
					(pts
						(xy 13.97 -8.636) (xy 15.875 -8.636) (xy 16.51 -8.001) (xy 16.51 -2.921) (xy 15.24 -1.016) (xy 13.97 -1.016)
						(xy 12.7 -2.921) (xy 12.7 -8.001) (xy 13.335 -8.636) (xy 13.97 -8.636)
					)
					(stroke
						(width 0)
						(type default)
					)
					(fill
						(type none)
					)
				)
				(rectangle
					(start 2.54 2.54)
					(end 26.67 -12.7)
					(stroke
						(width 0)
						(type default)
					)
					(fill
						(type background)
					)
				)
				(circle
					(center 13.843 -7.5184)
					(radius 0.4572)
					(stroke
						(width 0)
						(type default)
					)
					(fill
						(type none)
					)
				)
				(circle
					(center 14.097 -6.4008)
					(radius 0.2032)
					(stroke
						(width 0)
						(type default)
					)
					(fill
						(type outline)
					)
				)
				(circle
					(center 14.097 -5.6388)
					(radius 0.2032)
					(stroke
						(width 0)
						(type default)
					)
					(fill
						(type outline)
					)
				)
				(circle
					(center 14.097 -4.9276)
					(radius 0.2032)
					(stroke
						(width 0)
						(type default)
					)
					(fill
						(type outline)
					)
				)
				(circle
					(center 14.097 -4.1656)
					(radius 0.2032)
					(stroke
						(width 0)
						(type default)
					)
					(fill
						(type outline)
					)
				)
				(circle
					(center 14.097 -3.4544)
					(radius 0.2032)
					(stroke
						(width 0)
						(type default)
					)
					(fill
						(type outline)
					)
				)
				(circle
					(center 14.605 -2.1336)
					(radius 0.4572)
					(stroke
						(width 0)
						(type default)
					)
					(fill
						(type none)
					)
				)
				(circle
					(center 15.113 -6.4008)
					(radius 0.2032)
					(stroke
						(width 0)
						(type default)
					)
					(fill
						(type outline)
					)
				)
				(circle
					(center 15.113 -5.6388)
					(radius 0.2032)
					(stroke
						(width 0)
						(type default)
					)
					(fill
						(type outline)
					)
				)
				(circle
					(center 15.113 -4.9276)
					(radius 0.2032)
					(stroke
						(width 0)
						(type default)
					)
					(fill
						(type outline)
					)
				)
				(circle
					(center 15.113 -4.1656)
					(radius 0.2032)
					(stroke
						(width 0)
						(type default)
					)
					(fill
						(type outline)
					)
				)
				(circle
					(center 15.113 -3.4544)
					(radius 0.2032)
					(stroke
						(width 0)
						(type default)
					)
					(fill
						(type outline)
					)
				)
				(circle
					(center 15.4686 -7.5184)
					(radius 0.4572)
					(stroke
						(width 0)
						(type default)
					)
					(fill
						(type none)
					)
				)
				(text "ALT: 3.3V I2C/JTAG/SPI/SWD/FTDI"
					(at 14.732 -11.938 0)
					(effects
						(font
							(size 0.7 0.7)
						)
					)
				)
				(text "Tag-Connect"
					(at 14.605 1.651 0)
					(effects
						(font
							(size 0.7 0.7)
						)
					)
				)
				(pin passive line
					(at 0 0 0)
					(length 2.54)
					(name "1"
						(effects
							(font
								(size 1.27 1.27)
							)
						)
					)
					(number "1"
						(effects
							(font
								(size 1.27 1.27)
							)
						)
					)
					(alternate "3V3" passive line)
				)
				(pin passive line
					(at 29.21 0 180)
					(length 2.54)
					(name "10"
						(effects
							(font
								(size 1.27 1.27)
							)
						)
					)
					(number "10"
						(effects
							(font
								(size 1.27 1.27)
							)
						)
					)
					(alternate "ADBUS5" passive line)
					(alternate "I2C_NC" passive line)
					(alternate "JTAG_~{RESET}" passive line)
					(alternate "SPI_NC" passive line)
					(alternate "SWD_NC" passive line)
				)
				(pin passive line
					(at 0 -2.54 0)
					(length 2.54)
					(name "2"
						(effects
							(font
								(size 1.27 1.27)
							)
						)
					)
					(number "2"
						(effects
							(font
								(size 1.27 1.27)
							)
						)
					)
					(alternate "ADBUS3" passive line)
					(alternate "I2C_NC" passive line)
					(alternate "JTAG_TMS" passive line)
					(alternate "SPI_CS" passive line)
					(alternate "SWD_NC" passive line)
				)
				(pin passive line
					(at 0 -5.08 0)
					(length 2.54)
					(name "3"
						(effects
							(font
								(size 1.27 1.27)
							)
						)
					)
					(number "3"
						(effects
							(font
								(size 1.27 1.27)
							)
						)
					)
					(alternate "GND" passive line)
				)
				(pin passive line
					(at 0 -7.62 0)
					(length 2.54)
					(name "4"
						(effects
							(font
								(size 1.27 1.27)
							)
						)
					)
					(number "4"
						(effects
							(font
								(size 1.27 1.27)
							)
						)
					)
					(alternate "ADBUS0" passive line)
					(alternate "I2C_SCL" passive line)
					(alternate "JTAG_TCK" passive line)
					(alternate "SPI_SCK" passive line)
					(alternate "SWD_CLK" passive line)
				)
				(pin passive line
					(at 0 -10.16 0)
					(length 2.54)
					(name "5"
						(effects
							(font
								(size 1.27 1.27)
							)
						)
					)
					(number "5"
						(effects
							(font
								(size 1.27 1.27)
							)
						)
					)
					(alternate "GND" passive line)
				)
				(pin passive line
					(at 29.21 -10.16 180)
					(length 2.54)
					(name "6"
						(effects
							(font
								(size 1.27 1.27)
							)
						)
					)
					(number "6"
						(effects
							(font
								(size 1.27 1.27)
							)
						)
					)
					(alternate "ADBUS2" passive line)
					(alternate "I2C_SDA" passive line)
					(alternate "JTAG_TDO" passive line)
					(alternate "SPI_MISO" passive line)
					(alternate "SWD_IO" passive line)
				)
				(pin passive line
					(at 29.21 -7.62 180)
					(length 2.54)
					(name "7"
						(effects
							(font
								(size 1.27 1.27)
							)
						)
					)
					(number "7"
						(effects
							(font
								(size 1.27 1.27)
							)
						)
					)
					(alternate "NC" passive line)
				)
				(pin passive line
					(at 29.21 -5.08 180)
					(length 2.54)
					(name "8"
						(effects
							(font
								(size 1.27 1.27)
							)
						)
					)
					(number "8"
						(effects
							(font
								(size 1.27 1.27)
							)
						)
					)
					(alternate "ADBUS1" passive line)
					(alternate "I2C_SDA" passive line)
					(alternate "JTAG_TDI" passive line)
					(alternate "SPI_MOSI" passive line)
					(alternate "SWD_IO" passive line)
				)
				(pin passive line
					(at 29.21 -2.54 180)
					(length 2.54)
					(name "9"
						(effects
							(font
								(size 1.27 1.27)
							)
						)
					)
					(number "9"
						(effects
							(font
								(size 1.27 1.27)
							)
						)
					)
					(alternate "GND" passive line)
				)
			)
		)
	(symbol "antmicroB2BConnectors:Socket_Samtec_ERF8_2x40_ERF8-040-05.0-L-DV-K-TR"
			(pin_names hide)
			(exclude_from_sim no)
			(in_bom yes)
			(on_board yes)
			(property "Reference" "J"
				(at 30.48 0 0)
				(effects
					(font
						(size 1.27 1.27)
						(thickness 0.15)
					)
					(justify left bottom)
				)
			)
			(property "Value" "Socket_Samtec_ERF8_2x40_ERF8-040-05.0-L-DV-K-TR"
				(at 30.48 -5.08 0)
				(effects
					(font
						(size 1.27 1.27)
						(thickness 0.15)
					)
					(justify left bottom)
					(hide yes)
				)
			)
			(property "Footprint" "antmicro-footprints:Conn_Socket_Samtec_ERF8_2x40_ERF8-040-05.0-L-DV-K-TR"
				(at 30.48 -7.62 0)
				(effects
					(font
						(size 1.27 1.27)
						(thickness 0.15)
					)
					(justify left bottom)
					(hide yes)
				)
			)
			(property "Datasheet" "https://suddendocs.samtec.com/catalog_english/erf8.pdf"
				(at 30.48 -10.16 0)
				(effects
					(font
						(size 1.27 1.27)
						(thickness 0.15)
					)
					(justify left bottom)
					(hide yes)
				)
			)
			(property "Description" "Mezzanine Connector, Receptacle, 0.8 mm, 2 Rows, 80 Contacts, Surface Mount, Beryllium Copper"
				(at 0 0 0)
				(effects
					(font
						(size 1.27 1.27)
					)
					(hide yes)
				)
			)
			(property "MPN" "ERF8-040-05.0-L-DV-K-TR"
				(at 30.48 -2.54 0)
				(effects
					(font
						(size 1.27 1.27)
						(thickness 0.15)
					)
					(justify left bottom)
				)
			)
			(property "Manufacturer" "Samtec"
				(at 30.48 -12.7 0)
				(effects
					(font
						(size 1.27 1.27)
						(thickness 0.15)
					)
					(justify left bottom)
					(hide yes)
				)
			)
			(property "Author" "Antmicro"
				(at 30.48 -17.78 0)
				(effects
					(font
						(size 1.27 1.27)
						(thickness 0.15)
					)
					(justify left bottom)
					(hide yes)
				)
			)
			(property "License" "Apache-2.0"
				(at 30.48 -20.32 0)
				(effects
					(font
						(size 1.27 1.27)
						(thickness 0.15)
					)
					(justify left bottom)
					(hide yes)
				)
			)
			(property "Pitch" "0.8 mm"
				(at 30.48 -15.24 0)
				(effects
					(font
						(size 1.27 1.27)
					)
					(justify left bottom)
					(hide yes)
				)
			)
			(property "ki_keywords" "CONNECTOR, B2B, SOCKET"
				(at 0 0 0)
				(effects
					(font
						(size 1.27 1.27)
					)
					(hide yes)
				)
			)
			(symbol "Socket_Samtec_ERF8_2x40_ERF8-040-05.0-L-DV-K-TR_1_1"
				(rectangle
					(start 2.54 2.54)
					(end 8.89 -101.6)
					(stroke
						(width 0.254)
						(type default)
					)
					(fill
						(type background)
					)
				)
				(rectangle
					(start 3.81 1.27)
					(end 7.62 -100.33)
					(stroke
						(width 0.254)
						(type default)
					)
					(fill
						(type background)
					)
				)
				(pin passive line
					(at 0 0 0)
					(length 2.54)
					(name "~"
						(effects
							(font
								(size 1.27 1.27)
							)
						)
					)
					(number "1"
						(effects
							(font
								(size 1.27 1.27)
							)
						)
					)
				)
				(pin passive line
					(at 11.43 -10.16 180)
					(length 2.54)
					(name "~"
						(effects
							(font
								(size 1.27 1.27)
							)
						)
					)
					(number "10"
						(effects
							(font
								(size 1.27 1.27)
							)
						)
					)
				)
				(pin passive line
					(at 0 -12.7 0)
					(length 2.54)
					(name "~"
						(effects
							(font
								(size 1.27 1.27)
							)
						)
					)
					(number "11"
						(effects
							(font
								(size 1.27 1.27)
							)
						)
					)
				)
				(pin passive line
					(at 11.43 -12.7 180)
					(length 2.54)
					(name "~"
						(effects
							(font
								(size 1.27 1.27)
							)
						)
					)
					(number "12"
						(effects
							(font
								(size 1.27 1.27)
							)
						)
					)
				)
				(pin passive line
					(at 0 -15.24 0)
					(length 2.54)
					(name "~"
						(effects
							(font
								(size 1.27 1.27)
							)
						)
					)
					(number "13"
						(effects
							(font
								(size 1.27 1.27)
							)
						)
					)
				)
				(pin passive line
					(at 11.43 -15.24 180)
					(length 2.54)
					(name "~"
						(effects
							(font
								(size 1.27 1.27)
							)
						)
					)
					(number "14"
						(effects
							(font
								(size 1.27 1.27)
							)
						)
					)
				)
				(pin passive line
					(at 0 -17.78 0)
					(length 2.54)
					(name "~"
						(effects
							(font
								(size 1.27 1.27)
							)
						)
					)
					(number "15"
						(effects
							(font
								(size 1.27 1.27)
							)
						)
					)
				)
				(pin passive line
					(at 11.43 -17.78 180)
					(length 2.54)
					(name "~"
						(effects
							(font
								(size 1.27 1.27)
							)
						)
					)
					(number "16"
						(effects
							(font
								(size 1.27 1.27)
							)
						)
					)
				)
				(pin passive line
					(at 0 -20.32 0)
					(length 2.54)
					(name "~"
						(effects
							(font
								(size 1.27 1.27)
							)
						)
					)
					(number "17"
						(effects
							(font
								(size 1.27 1.27)
							)
						)
					)
				)
				(pin passive line
					(at 11.43 -20.32 180)
					(length 2.54)
					(name "~"
						(effects
							(font
								(size 1.27 1.27)
							)
						)
					)
					(number "18"
						(effects
							(font
								(size 1.27 1.27)
							)
						)
					)
				)
				(pin passive line
					(at 0 -22.86 0)
					(length 2.54)
					(name "~"
						(effects
							(font
								(size 1.27 1.27)
							)
						)
					)
					(number "19"
						(effects
							(font
								(size 1.27 1.27)
							)
						)
					)
				)
				(pin passive line
					(at 11.43 0 180)
					(length 2.54)
					(name "~"
						(effects
							(font
								(size 1.27 1.27)
							)
						)
					)
					(number "2"
						(effects
							(font
								(size 1.27 1.27)
							)
						)
					)
				)
				(pin passive line
					(at 11.43 -22.86 180)
					(length 2.54)
					(name "~"
						(effects
							(font
								(size 1.27 1.27)
							)
						)
					)
					(number "20"
						(effects
							(font
								(size 1.27 1.27)
							)
						)
					)
				)
				(pin passive line
					(at 0 -25.4 0)
					(length 2.54)
					(name "~"
						(effects
							(font
								(size 1.27 1.27)
							)
						)
					)
					(number "21"
						(effects
							(font
								(size 1.27 1.27)
							)
						)
					)
				)
				(pin passive line
					(at 11.43 -25.4 180)
					(length 2.54)
					(name "~"
						(effects
							(font
								(size 1.27 1.27)
							)
						)
					)
					(number "22"
						(effects
							(font
								(size 1.27 1.27)
							)
						)
					)
				)
				(pin passive line
					(at 0 -27.94 0)
					(length 2.54)
					(name "~"
						(effects
							(font
								(size 1.27 1.27)
							)
						)
					)
					(number "23"
						(effects
							(font
								(size 1.27 1.27)
							)
						)
					)
				)
				(pin passive line
					(at 11.43 -27.94 180)
					(length 2.54)
					(name "~"
						(effects
							(font
								(size 1.27 1.27)
							)
						)
					)
					(number "24"
						(effects
							(font
								(size 1.27 1.27)
							)
						)
					)
				)
				(pin passive line
					(at 0 -30.48 0)
					(length 2.54)
					(name "~"
						(effects
							(font
								(size 1.27 1.27)
							)
						)
					)
					(number "25"
						(effects
							(font
								(size 1.27 1.27)
							)
						)
					)
				)
				(pin passive line
					(at 11.43 -30.48 180)
					(length 2.54)
					(name "~"
						(effects
							(font
								(size 1.27 1.27)
							)
						)
					)
					(number "26"
						(effects
							(font
								(size 1.27 1.27)
							)
						)
					)
				)
				(pin passive line
					(at 0 -33.02 0)
					(length 2.54)
					(name "~"
						(effects
							(font
								(size 1.27 1.27)
							)
						)
					)
					(number "27"
						(effects
							(font
								(size 1.27 1.27)
							)
						)
					)
				)
				(pin passive line
					(at 11.43 -33.02 180)
					(length 2.54)
					(name "~"
						(effects
							(font
								(size 1.27 1.27)
							)
						)
					)
					(number "28"
						(effects
							(font
								(size 1.27 1.27)
							)
						)
					)
				)
				(pin passive line
					(at 0 -35.56 0)
					(length 2.54)
					(name "~"
						(effects
							(font
								(size 1.27 1.27)
							)
						)
					)
					(number "29"
						(effects
							(font
								(size 1.27 1.27)
							)
						)
					)
				)
				(pin passive line
					(at 0 -2.54 0)
					(length 2.54)
					(name "~"
						(effects
							(font
								(size 1.27 1.27)
							)
						)
					)
					(number "3"
						(effects
							(font
								(size 1.27 1.27)
							)
						)
					)
				)
				(pin passive line
					(at 11.43 -35.56 180)
					(length 2.54)
					(name "~"
						(effects
							(font
								(size 1.27 1.27)
							)
						)
					)
					(number "30"
						(effects
							(font
								(size 1.27 1.27)
							)
						)
					)
				)
				(pin passive line
					(at 0 -38.1 0)
					(length 2.54)
					(name "~"
						(effects
							(font
								(size 1.27 1.27)
							)
						)
					)
					(number "31"
						(effects
							(font
								(size 1.27 1.27)
							)
						)
					)
				)
				(pin passive line
					(at 11.43 -38.1 180)
					(length 2.54)
					(name "~"
						(effects
							(font
								(size 1.27 1.27)
							)
						)
					)
					(number "32"
						(effects
							(font
								(size 1.27 1.27)
							)
						)
					)
				)
				(pin passive line
					(at 0 -40.64 0)
					(length 2.54)
					(name "~"
						(effects
							(font
								(size 1.27 1.27)
							)
						)
					)
					(number "33"
						(effects
							(font
								(size 1.27 1.27)
							)
						)
					)
				)
				(pin passive line
					(at 11.43 -40.64 180)
					(length 2.54)
					(name "~"
						(effects
							(font
								(size 1.27 1.27)
							)
						)
					)
					(number "34"
						(effects
							(font
								(size 1.27 1.27)
							)
						)
					)
				)
				(pin passive line
					(at 0 -43.18 0)
					(length 2.54)
					(name "~"
						(effects
							(font
								(size 1.27 1.27)
							)
						)
					)
					(number "35"
						(effects
							(font
								(size 1.27 1.27)
							)
						)
					)
				)
				(pin passive line
					(at 11.43 -43.18 180)
					(length 2.54)
					(name "~"
						(effects
							(font
								(size 1.27 1.27)
							)
						)
					)
					(number "36"
						(effects
							(font
								(size 1.27 1.27)
							)
						)
					)
				)
				(pin passive line
					(at 0 -45.72 0)
					(length 2.54)
					(name "~"
						(effects
							(font
								(size 1.27 1.27)
							)
						)
					)
					(number "37"
						(effects
							(font
								(size 1.27 1.27)
							)
						)
					)
				)
				(pin passive line
					(at 11.43 -45.72 180)
					(length 2.54)
					(name "~"
						(effects
							(font
								(size 1.27 1.27)
							)
						)
					)
					(number "38"
						(effects
							(font
								(size 1.27 1.27)
							)
						)
					)
				)
				(pin passive line
					(at 0 -48.26 0)
					(length 2.54)
					(name "~"
						(effects
							(font
								(size 1.27 1.27)
							)
						)
					)
					(number "39"
						(effects
							(font
								(size 1.27 1.27)
							)
						)
					)
				)
				(pin passive line
					(at 11.43 -2.54 180)
					(length 2.54)
					(name "~"
						(effects
							(font
								(size 1.27 1.27)
							)
						)
					)
					(number "4"
						(effects
							(font
								(size 1.27 1.27)
							)
						)
					)
				)
				(pin passive line
					(at 11.43 -48.26 180)
					(length 2.54)
					(name "~"
						(effects
							(font
								(size 1.27 1.27)
							)
						)
					)
					(number "40"
						(effects
							(font
								(size 1.27 1.27)
							)
						)
					)
				)
				(pin passive line
					(at 0 -50.8 0)
					(length 2.54)
					(name "~"
						(effects
							(font
								(size 1.27 1.27)
							)
						)
					)
					(number "41"
						(effects
							(font
								(size 1.27 1.27)
							)
						)
					)
				)
				(pin passive line
					(at 11.43 -50.8 180)
					(length 2.54)
					(name "~"
						(effects
							(font
								(size 1.27 1.27)
							)
						)
					)
					(number "42"
						(effects
							(font
								(size 1.27 1.27)
							)
						)
					)
				)
				(pin passive line
					(at 0 -53.34 0)
					(length 2.54)
					(name "~"
						(effects
							(font
								(size 1.27 1.27)
							)
						)
					)
					(number "43"
						(effects
							(font
								(size 1.27 1.27)
							)
						)
					)
				)
				(pin passive line
					(at 11.43 -53.34 180)
					(length 2.54)
					(name "~"
						(effects
							(font
								(size 1.27 1.27)
							)
						)
					)
					(number "44"
						(effects
							(font
								(size 1.27 1.27)
							)
						)
					)
				)
				(pin passive line
					(at 0 -55.88 0)
					(length 2.54)
					(name "~"
						(effects
							(font
								(size 1.27 1.27)
							)
						)
					)
					(number "45"
						(effects
							(font
								(size 1.27 1.27)
							)
						)
					)
				)
				(pin passive line
					(at 11.43 -55.88 180)
					(length 2.54)
					(name "~"
						(effects
							(font
								(size 1.27 1.27)
							)
						)
					)
					(number "46"
						(effects
							(font
								(size 1.27 1.27)
							)
						)
					)
				)
				(pin passive line
					(at 0 -58.42 0)
					(length 2.54)
					(name "~"
						(effects
							(font
								(size 1.27 1.27)
							)
						)
					)
					(number "47"
						(effects
							(font
								(size 1.27 1.27)
							)
						)
					)
				)
				(pin passive line
					(at 11.43 -58.42 180)
					(length 2.54)
					(name "~"
						(effects
							(font
								(size 1.27 1.27)
							)
						)
					)
					(number "48"
						(effects
							(font
								(size 1.27 1.27)
							)
						)
					)
				)
				(pin passive line
					(at 0 -60.96 0)
					(length 2.54)
					(name "~"
						(effects
							(font
								(size 1.27 1.27)
							)
						)
					)
					(number "49"
						(effects
							(font
								(size 1.27 1.27)
							)
						)
					)
				)
				(pin passive line
					(at 0 -5.08 0)
					(length 2.54)
					(name "~"
						(effects
							(font
								(size 1.27 1.27)
							)
						)
					)
					(number "5"
						(effects
							(font
								(size 1.27 1.27)
							)
						)
					)
				)
				(pin passive line
					(at 11.43 -60.96 180)
					(length 2.54)
					(name "~"
						(effects
							(font
								(size 1.27 1.27)
							)
						)
					)
					(number "50"
						(effects
							(font
								(size 1.27 1.27)
							)
						)
					)
				)
				(pin passive line
					(at 0 -63.5 0)
					(length 2.54)
					(name "~"
						(effects
							(font
								(size 1.27 1.27)
							)
						)
					)
					(number "51"
						(effects
							(font
								(size 1.27 1.27)
							)
						)
					)
				)
				(pin passive line
					(at 11.43 -63.5 180)
					(length 2.54)
					(name "~"
						(effects
							(font
								(size 1.27 1.27)
							)
						)
					)
					(number "52"
						(effects
							(font
								(size 1.27 1.27)
							)
						)
					)
				)
				(pin passive line
					(at 0 -66.04 0)
					(length 2.54)
					(name "~"
						(effects
							(font
								(size 1.27 1.27)
							)
						)
					)
					(number "53"
						(effects
							(font
								(size 1.27 1.27)
							)
						)
					)
				)
				(pin passive line
					(at 11.43 -66.04 180)
					(length 2.54)
					(name "~"
						(effects
							(font
								(size 1.27 1.27)
							)
						)
					)
					(number "54"
						(effects
							(font
								(size 1.27 1.27)
							)
						)
					)
				)
				(pin passive line
					(at 0 -68.58 0)
					(length 2.54)
					(name "~"
						(effects
							(font
								(size 1.27 1.27)
							)
						)
					)
					(number "55"
						(effects
							(font
								(size 1.27 1.27)
							)
						)
					)
				)
				(pin passive line
					(at 11.43 -68.58 180)
					(length 2.54)
					(name "~"
						(effects
							(font
								(size 1.27 1.27)
							)
						)
					)
					(number "56"
						(effects
							(font
								(size 1.27 1.27)
							)
						)
					)
				)
				(pin passive line
					(at 0 -71.12 0)
					(length 2.54)
					(name "~"
						(effects
							(font
								(size 1.27 1.27)
							)
						)
					)
					(number "57"
						(effects
							(font
								(size 1.27 1.27)
							)
						)
					)
				)
				(pin passive line
					(at 11.43 -71.12 180)
					(length 2.54)
					(name "~"
						(effects
							(font
								(size 1.27 1.27)
							)
						)
					)
					(number "58"
						(effects
							(font
								(size 1.27 1.27)
							)
						)
					)
				)
				(pin passive line
					(at 0 -73.66 0)
					(length 2.54)
					(name "~"
						(effects
							(font
								(size 1.27 1.27)
							)
						)
					)
					(number "59"
						(effects
							(font
								(size 1.27 1.27)
							)
						)
					)
				)
				(pin passive line
					(at 11.43 -5.08 180)
					(length 2.54)
					(name "~"
						(effects
							(font
								(size 1.27 1.27)
							)
						)
					)
					(number "6"
						(effects
							(font
								(size 1.27 1.27)
							)
						)
					)
				)
				(pin passive line
					(at 11.43 -73.66 180)
					(length 2.54)
					(name "~"
						(effects
							(font
								(size 1.27 1.27)
							)
						)
					)
					(number "60"
						(effects
							(font
								(size 1.27 1.27)
							)
						)
					)
				)
				(pin passive line
					(at 0 -76.2 0)
					(length 2.54)
					(name "~"
						(effects
							(font
								(size 1.27 1.27)
							)
						)
					)
					(number "61"
						(effects
							(font
								(size 1.27 1.27)
							)
						)
					)
				)
				(pin passive line
					(at 11.43 -76.2 180)
					(length 2.54)
					(name "~"
						(effects
							(font
								(size 1.27 1.27)
							)
						)
					)
					(number "62"
						(effects
							(font
								(size 1.27 1.27)
							)
						)
					)
				)
				(pin passive line
					(at 0 -78.74 0)
					(length 2.54)
					(name "~"
						(effects
							(font
								(size 1.27 1.27)
							)
						)
					)
					(number "63"
						(effects
							(font
								(size 1.27 1.27)
							)
						)
					)
				)
				(pin passive line
					(at 11.43 -78.74 180)
					(length 2.54)
					(name "~"
						(effects
							(font
								(size 1.27 1.27)
							)
						)
					)
					(number "64"
						(effects
							(font
								(size 1.27 1.27)
							)
						)
					)
				)
				(pin passive line
					(at 0 -81.28 0)
					(length 2.54)
					(name "~"
						(effects
							(font
								(size 1.27 1.27)
							)
						)
					)
					(number "65"
						(effects
							(font
								(size 1.27 1.27)
							)
						)
					)
				)
				(pin passive line
					(at 11.43 -81.28 180)
					(length 2.54)
					(name "~"
						(effects
							(font
								(size 1.27 1.27)
							)
						)
					)
					(number "66"
						(effects
							(font
								(size 1.27 1.27)
							)
						)
					)
				)
				(pin passive line
					(at 0 -83.82 0)
					(length 2.54)
					(name "~"
						(effects
							(font
								(size 1.27 1.27)
							)
						)
					)
					(number "67"
						(effects
							(font
								(size 1.27 1.27)
							)
						)
					)
				)
				(pin passive line
					(at 11.43 -83.82 180)
					(length 2.54)
					(name "~"
						(effects
							(font
								(size 1.27 1.27)
							)
						)
					)
					(number "68"
						(effects
							(font
								(size 1.27 1.27)
							)
						)
					)
				)
				(pin passive line
					(at 0 -86.36 0)
					(length 2.54)
					(name "~"
						(effects
							(font
								(size 1.27 1.27)
							)
						)
					)
					(number "69"
						(effects
							(font
								(size 1.27 1.27)
							)
						)
					)
				)
				(pin passive line
					(at 0 -7.62 0)
					(length 2.54)
					(name "~"
						(effects
							(font
								(size 1.27 1.27)
							)
						)
					)
					(number "7"
						(effects
							(font
								(size 1.27 1.27)
							)
						)
					)
				)
				(pin passive line
					(at 11.43 -86.36 180)
					(length 2.54)
					(name "~"
						(effects
							(font
								(size 1.27 1.27)
							)
						)
					)
					(number "70"
						(effects
							(font
								(size 1.27 1.27)
							)
						)
					)
				)
				(pin passive line
					(at 0 -88.9 0)
					(length 2.54)
					(name "~"
						(effects
							(font
								(size 1.27 1.27)
							)
						)
					)
					(number "71"
						(effects
							(font
								(size 1.27 1.27)
							)
						)
					)
				)
				(pin passive line
					(at 11.43 -88.9 180)
					(length 2.54)
					(name "~"
						(effects
							(font
								(size 1.27 1.27)
							)
						)
					)
					(number "72"
						(effects
							(font
								(size 1.27 1.27)
							)
						)
					)
				)
				(pin passive line
					(at 0 -91.44 0)
					(length 2.54)
					(name "~"
						(effects
							(font
								(size 1.27 1.27)
							)
						)
					)
					(number "73"
						(effects
							(font
								(size 1.27 1.27)
							)
						)
					)
				)
				(pin passive line
					(at 11.43 -91.44 180)
					(length 2.54)
					(name "~"
						(effects
							(font
								(size 1.27 1.27)
							)
						)
					)
					(number "74"
						(effects
							(font
								(size 1.27 1.27)
							)
						)
					)
				)
				(pin passive line
					(at 0 -93.98 0)
					(length 2.54)
					(name "~"
						(effects
							(font
								(size 1.27 1.27)
							)
						)
					)
					(number "75"
						(effects
							(font
								(size 1.27 1.27)
							)
						)
					)
				)
				(pin passive line
					(at 11.43 -93.98 180)
					(length 2.54)
					(name "~"
						(effects
							(font
								(size 1.27 1.27)
							)
						)
					)
					(number "76"
						(effects
							(font
								(size 1.27 1.27)
							)
						)
					)
				)
				(pin passive line
					(at 0 -96.52 0)
					(length 2.54)
					(name "~"
						(effects
							(font
								(size 1.27 1.27)
							)
						)
					)
					(number "77"
						(effects
							(font
								(size 1.27 1.27)
							)
						)
					)
				)
				(pin passive line
					(at 11.43 -96.52 180)
					(length 2.54)
					(name "~"
						(effects
							(font
								(size 1.27 1.27)
							)
						)
					)
					(number "78"
						(effects
							(font
								(size 1.27 1.27)
							)
						)
					)
				)
				(pin passive line
					(at 0 -99.06 0)
					(length 2.54)
					(name "~"
						(effects
							(font
								(size 1.27 1.27)
							)
						)
					)
					(number "79"
						(effects
							(font
								(size 1.27 1.27)
							)
						)
					)
				)
				(pin passive line
					(at 11.43 -7.62 180)
					(length 2.54)
					(name "~"
						(effects
							(font
								(size 1.27 1.27)
							)
						)
					)
					(number "8"
						(effects
							(font
								(size 1.27 1.27)
							)
						)
					)
				)
				(pin passive line
					(at 11.43 -99.06 180)
					(length 2.54)
					(name "~"
						(effects
							(font
								(size 1.27 1.27)
							)
						)
					)
					(number "80"
						(effects
							(font
								(size 1.27 1.27)
							)
						)
					)
				)
				(pin passive line
					(at 0 -10.16 0)
					(length 2.54)
					(name "~"
						(effects
							(font
								(size 1.27 1.27)
							)
						)
					)
					(number "9"
						(effects
							(font
								(size 1.27 1.27)
							)
						)
					)
				)
			)
		)
	(symbol "antmicroBatteryHoldersClipsContacts:Battery_Holder_MS621FE-FL11E"
			(pin_names
				(offset 0)
			)
			(exclude_from_sim no)
			(in_bom yes)
			(on_board yes)
			(property "Reference" "BT"
				(at 17.78 -2.54 0)
				(effects
					(font
						(size 1.27 1.27)
						(thickness 0.15)
					)
					(justify left bottom)
				)
			)
			(property "Value" "Battery_Holder_MS621FE-FL11E"
				(at 17.78 -7.62 0)
				(effects
					(font
						(size 1.27 1.27)
						(thickness 0.15)
					)
					(justify left bottom)
					(hide yes)
				)
			)
			(property "Footprint" "antmicro-footprints:MS621FE-FL11E"
				(at 17.78 -10.16 0)
				(effects
					(font
						(size 1.27 1.27)
						(thickness 0.15)
					)
					(justify left bottom)
					(hide yes)
				)
			)
			(property "Datasheet" "https://www.sii.co.jp/en/me/datasheets/ms-rechargeable/ms621fe/"
				(at 17.78 -12.7 0)
				(effects
					(font
						(size 1.27 1.27)
						(thickness 0.15)
					)
					(justify left bottom)
					(hide yes)
				)
			)
			(property "Description" "Rechargeable Battery, Coin Cell, Single Cell, 3 V, Lithium Manganese Dioxide, 5.5 mAh, Button Cell"
				(at 0 0 0)
				(effects
					(font
						(size 1.27 1.27)
					)
					(hide yes)
				)
			)
			(property "Manufacturer" "Seiko Instruments"
				(at 17.78 -15.24 0)
				(effects
					(font
						(size 1.27 1.27)
						(thickness 0.15)
					)
					(justify left bottom)
					(hide yes)
				)
			)
			(property "MPN" "MS621FE-FL11E"
				(at 17.78 -5.08 0)
				(effects
					(font
						(size 1.27 1.27)
						(thickness 0.15)
					)
					(justify left bottom)
				)
			)
			(property "Author" "Antmicro"
				(at 17.78 -17.78 0)
				(effects
					(font
						(size 1.27 1.27)
						(thickness 0.15)
					)
					(justify left bottom)
					(hide yes)
				)
			)
			(property "License" "Apache-2.0"
				(at 17.78 -20.32 0)
				(effects
					(font
						(size 1.27 1.27)
						(thickness 0.15)
					)
					(justify left bottom)
					(hide yes)
				)
			)
			(property "ki_keywords" "HORIZONTAL, SMT, HOLDER, BATTERY"
				(at 0 0 0)
				(effects
					(font
						(size 1.27 1.27)
					)
					(hide yes)
				)
			)
			(symbol "Battery_Holder_MS621FE-FL11E_0_1"
				(rectangle
					(start -1.27 -5.08)
					(end 1.27 -4.826)
					(stroke
						(width 0.254)
						(type default)
					)
					(fill
						(type outline)
					)
				)
				(polyline
					(pts
						(xy 0 -2.54) (xy 0 -3.81)
					)
					(stroke
						(width 0.254)
						(type default)
					)
					(fill
						(type none)
					)
				)
			)
			(symbol "Battery_Holder_MS621FE-FL11E_1_1"
				(polyline
					(pts
						(xy -2.54 -3.81) (xy 2.54 -3.81)
					)
					(stroke
						(width 0.254)
						(type default)
					)
					(fill
						(type background)
					)
				)
				(polyline
					(pts
						(xy 0 -6.35) (xy 0 -5.08)
					)
					(stroke
						(width 0.254)
						(type default)
					)
					(fill
						(type background)
					)
				)
				(pin passive line
					(at 0 0 270)
					(length 2.54)
					(name "+"
						(effects
							(font
								(size 1.27 1.27)
							)
						)
					)
					(number "1"
						(effects
							(font
								(size 1.27 1.27)
							)
						)
					)
				)
				(pin passive line
					(at 0 -8.89 90)
					(length 2.54)
					(name "-"
						(effects
							(font
								(size 1.27 1.27)
							)
						)
					)
					(number "2"
						(effects
							(font
								(size 1.27 1.27)
							)
						)
					)
				)
			)
		)
	(symbol "antmicroCapacitors0402:C_100n_0402"
			(pin_numbers hide)
			(pin_names hide)
			(exclude_from_sim no)
			(in_bom yes)
			(on_board yes)
			(property "Reference" "C"
				(at 20.32 -5.08 0)
				(effects
					(font
						(size 1.27 1.27)
						(thickness 0.15)
					)
					(justify left bottom)
				)
			)
			(property "Value" "C_100n_0402"
				(at 20.32 -10.16 0)
				(effects
					(font
						(size 1.27 1.27)
						(thickness 0.15)
					)
					(justify left bottom)
					(hide yes)
				)
			)
			(property "Footprint" "antmicro-footprints:C_0402_1005Metric"
				(at 20.32 -12.7 0)
				(effects
					(font
						(size 1.27 1.27)
						(thickness 0.15)
					)
					(justify left bottom)
					(hide yes)
				)
			)
			(property "Datasheet" "https://www.murata.com/products/productdetail?partno=GRM155R61H104KE14%23"
				(at 20.32 -15.24 0)
				(effects
					(font
						(size 1.27 1.27)
						(thickness 0.15)
					)
					(justify left bottom)
					(hide yes)
				)
			)
			(property "Description" "SMD Multilayer Ceramic Capacitor, 0.1 µF, 50 V, 0402 [1005 Metric], ± 10%, X5R, GRM Series"
				(at 0 0 0)
				(effects
					(font
						(size 1.27 1.27)
					)
					(hide yes)
				)
			)
			(property "MPN" "GRM155R61H104KE14D"
				(at 20.32 -17.78 0)
				(effects
					(font
						(size 1.27 1.27)
						(thickness 0.15)
					)
					(justify left bottom)
					(hide yes)
				)
			)
			(property "Manufacturer" "Murata"
				(at 20.32 -20.32 0)
				(effects
					(font
						(size 1.27 1.27)
						(thickness 0.15)
					)
					(justify left bottom)
					(hide yes)
				)
			)
			(property "License" "Apache-2.0"
				(at 20.32 -22.86 0)
				(effects
					(font
						(size 1.27 1.27)
						(thickness 0.15)
					)
					(justify left bottom)
					(hide yes)
				)
			)
			(property "Author" "Antmicro"
				(at 20.32 -25.4 0)
				(effects
					(font
						(size 1.27 1.27)
						(thickness 0.15)
					)
					(justify left bottom)
					(hide yes)
				)
			)
			(property "Val" "100n"
				(at 20.32 -7.62 0)
				(effects
					(font
						(size 1.27 1.27)
						(thickness 0.15)
					)
					(justify left bottom)
				)
			)
			(property "Voltage" "50V"
				(at 20.32 -27.94 0)
				(effects
					(font
						(size 1.27 1.27)
					)
					(justify left bottom)
					(hide yes)
				)
			)
			(property "Dielectric" "X5R"
				(at 20.32 -30.48 0)
				(effects
					(font
						(size 1.27 1.27)
					)
					(justify left bottom)
					(hide yes)
				)
			)
			(property "ki_keywords" "0402, SMT, CAPACITOR, PASSIVE, CERAMIC, MLCC"
				(at 0 0 0)
				(effects
					(font
						(size 1.27 1.27)
					)
					(hide yes)
				)
			)
			(symbol "C_100n_0402_0_1"
				(polyline
					(pts
						(xy 2.032 -1.524) (xy 2.032 1.524)
					)
					(stroke
						(width 0.3048)
						(type default)
					)
					(fill
						(type none)
					)
				)
				(polyline
					(pts
						(xy 3.048 -1.524) (xy 3.048 1.524)
					)
					(stroke
						(width 0.3302)
						(type default)
					)
					(fill
						(type none)
					)
				)
			)
			(symbol "C_100n_0402_1_1"
				(pin passive line
					(at 0 0 0)
					(length 2.032)
					(name "~"
						(effects
							(font
								(size 1.27 1.27)
							)
						)
					)
					(number "1"
						(effects
							(font
								(size 1.27 1.27)
							)
						)
					)
				)
				(pin passive line
					(at 5.08 0 180)
					(length 2.032)
					(name "~"
						(effects
							(font
								(size 1.27 1.27)
							)
						)
					)
					(number "2"
						(effects
							(font
								(size 1.27 1.27)
							)
						)
					)
				)
			)
		)
	(symbol "antmicroCapacitors0402:C_10u_0402"
			(pin_numbers hide)
			(pin_names hide)
			(exclude_from_sim no)
			(in_bom yes)
			(on_board yes)
			(property "Reference" "C"
				(at 20.32 -5.08 0)
				(effects
					(font
						(size 1.27 1.27)
						(thickness 0.15)
					)
					(justify left bottom)
				)
			)
			(property "Value" "C_10u_0402"
				(at 20.32 -10.16 0)
				(effects
					(font
						(size 1.27 1.27)
						(thickness 0.15)
					)
					(justify left bottom)
					(hide yes)
				)
			)
			(property "Footprint" "antmicro-footprints:C_0402_1005Metric"
				(at 20.32 -12.7 0)
				(effects
					(font
						(size 1.27 1.27)
						(thickness 0.15)
					)
					(justify left bottom)
					(hide yes)
				)
			)
			(property "Datasheet" "https://www.yageo.com/en/Chart/Download/pdf/CC0402MRX5R5BB106"
				(at 20.32 -15.24 0)
				(effects
					(font
						(size 1.27 1.27)
						(thickness 0.15)
					)
					(justify left bottom)
					(hide yes)
				)
			)
			(property "Description" "SMD Multilayer Ceramic Capacitor, 10 µF, 6.3 V, 0402 [1005 Metric], ± 20%, X5R, CC Series"
				(at 0 0 0)
				(effects
					(font
						(size 1.27 1.27)
					)
					(hide yes)
				)
			)
			(property "MPN" "CC0402MRX5R5BB106"
				(at 20.32 -17.78 0)
				(effects
					(font
						(size 1.27 1.27)
						(thickness 0.15)
					)
					(justify left bottom)
					(hide yes)
				)
			)
			(property "Manufacturer" "YAGEO"
				(at 20.32 -20.32 0)
				(effects
					(font
						(size 1.27 1.27)
						(thickness 0.15)
					)
					(justify left bottom)
					(hide yes)
				)
			)
			(property "License" "Apache-2.0"
				(at 20.32 -22.86 0)
				(effects
					(font
						(size 1.27 1.27)
						(thickness 0.15)
					)
					(justify left bottom)
					(hide yes)
				)
			)
			(property "Author" "Antmicro"
				(at 20.32 -25.4 0)
				(effects
					(font
						(size 1.27 1.27)
						(thickness 0.15)
					)
					(justify left bottom)
					(hide yes)
				)
			)
			(property "Val" "10u"
				(at 20.32 -7.62 0)
				(effects
					(font
						(size 1.27 1.27)
						(thickness 0.15)
					)
					(justify left bottom)
				)
			)
			(property "Voltage" ""
				(at 20.32 -27.94 0)
				(effects
					(font
						(size 1.27 1.27)
					)
					(justify left bottom)
					(hide yes)
				)
			)
			(property "Dielectric" ""
				(at 20.32 -30.48 0)
				(effects
					(font
						(size 1.27 1.27)
					)
					(justify left bottom)
					(hide yes)
				)
			)
			(property "ki_keywords" "0402, SMT, CAPACITOR, PASSIVE, MLCC, CERAMIC"
				(at 0 0 0)
				(effects
					(font
						(size 1.27 1.27)
					)
					(hide yes)
				)
			)
			(symbol "C_10u_0402_0_1"
				(polyline
					(pts
						(xy 2.032 -1.524) (xy 2.032 1.524)
					)
					(stroke
						(width 0.3048)
						(type default)
					)
					(fill
						(type none)
					)
				)
				(polyline
					(pts
						(xy 3.048 -1.524) (xy 3.048 1.524)
					)
					(stroke
						(width 0.3302)
						(type default)
					)
					(fill
						(type none)
					)
				)
			)
			(symbol "C_10u_0402_1_1"
				(pin passive line
					(at 0 0 0)
					(length 2.032)
					(name "~"
						(effects
							(font
								(size 1.27 1.27)
							)
						)
					)
					(number "1"
						(effects
							(font
								(size 1.27 1.27)
							)
						)
					)
				)
				(pin passive line
					(at 5.08 0 180)
					(length 2.032)
					(name "~"
						(effects
							(font
								(size 1.27 1.27)
							)
						)
					)
					(number "2"
						(effects
							(font
								(size 1.27 1.27)
							)
						)
					)
				)
			)
		)
	(symbol "antmicroCapacitors0402:C_1n_0402"
			(pin_numbers hide)
			(pin_names hide)
			(exclude_from_sim no)
			(in_bom yes)
			(on_board yes)
			(property "Reference" "C"
				(at 20.32 -5.08 0)
				(effects
					(font
						(size 1.27 1.27)
						(thickness 0.15)
					)
					(justify left bottom)
				)
			)
			(property "Value" "C_1n_0402"
				(at 20.32 -10.16 0)
				(effects
					(font
						(size 1.27 1.27)
						(thickness 0.15)
					)
					(justify left bottom)
					(hide yes)
				)
			)
			(property "Footprint" "antmicro-footprints:C_0402_1005Metric"
				(at 20.32 -12.7 0)
				(effects
					(font
						(size 1.27 1.27)
						(thickness 0.15)
					)
					(justify left bottom)
					(hide yes)
				)
			)
			(property "Datasheet" "https://www.murata.com/products/productdetail?partno=GRM1555C1H102JA01%23"
				(at 20.32 -15.24 0)
				(effects
					(font
						(size 1.27 1.27)
						(thickness 0.15)
					)
					(justify left bottom)
					(hide yes)
				)
			)
			(property "Description" "SMD Multilayer Ceramic Capacitor, 1000 pF, 50 V, 0402 [1005 Metric], ± 5%, C0G / NP0, GRM Series"
				(at 0 0 0)
				(effects
					(font
						(size 1.27 1.27)
					)
					(hide yes)
				)
			)
			(property "MPN" "GRM1555C1H102JA01D"
				(at 20.32 -17.78 0)
				(effects
					(font
						(size 1.27 1.27)
						(thickness 0.15)
					)
					(justify left bottom)
					(hide yes)
				)
			)
			(property "Manufacturer" "Murata"
				(at 20.32 -20.32 0)
				(effects
					(font
						(size 1.27 1.27)
						(thickness 0.15)
					)
					(justify left bottom)
					(hide yes)
				)
			)
			(property "License" "Apache-2.0"
				(at 20.32 -22.86 0)
				(effects
					(font
						(size 1.27 1.27)
						(thickness 0.15)
					)
					(justify left bottom)
					(hide yes)
				)
			)
			(property "Author" "Antmicro"
				(at 20.32 -25.4 0)
				(effects
					(font
						(size 1.27 1.27)
						(thickness 0.15)
					)
					(justify left bottom)
					(hide yes)
				)
			)
			(property "Val" "1n"
				(at 20.32 -7.62 0)
				(effects
					(font
						(size 1.27 1.27)
						(thickness 0.15)
					)
					(justify left bottom)
				)
			)
			(property "Voltage" "50V"
				(at 20.32 -27.94 0)
				(effects
					(font
						(size 1.27 1.27)
					)
					(justify left bottom)
					(hide yes)
				)
			)
			(property "Dielectric" "C0G"
				(at 20.32 -30.48 0)
				(effects
					(font
						(size 1.27 1.27)
					)
					(justify left bottom)
					(hide yes)
				)
			)
			(property "ki_keywords" "0402, SMT, CAPACITOR, PASSIVE, CERAMIC, MLCC"
				(at 0 0 0)
				(effects
					(font
						(size 1.27 1.27)
					)
					(hide yes)
				)
			)
			(symbol "C_1n_0402_0_1"
				(polyline
					(pts
						(xy 2.032 -1.524) (xy 2.032 1.524)
					)
					(stroke
						(width 0.3048)
						(type default)
					)
					(fill
						(type none)
					)
				)
				(polyline
					(pts
						(xy 3.048 -1.524) (xy 3.048 1.524)
					)
					(stroke
						(width 0.3302)
						(type default)
					)
					(fill
						(type none)
					)
				)
			)
			(symbol "C_1n_0402_1_1"
				(pin passive line
					(at 0 0 0)
					(length 2.032)
					(name "~"
						(effects
							(font
								(size 1.27 1.27)
							)
						)
					)
					(number "1"
						(effects
							(font
								(size 1.27 1.27)
							)
						)
					)
				)
				(pin passive line
					(at 5.08 0 180)
					(length 2.032)
					(name "~"
						(effects
							(font
								(size 1.27 1.27)
							)
						)
					)
					(number "2"
						(effects
							(font
								(size 1.27 1.27)
							)
						)
					)
				)
			)
		)
	(symbol "antmicroCapacitors0402:C_1n_16V_X7R_0402"
			(pin_numbers hide)
			(pin_names hide)
			(exclude_from_sim no)
			(in_bom yes)
			(on_board yes)
			(property "Reference" "C"
				(at 15.24 -5.08 0)
				(effects
					(font
						(size 1.27 1.27)
						(thickness 0.15)
					)
					(justify left bottom)
				)
			)
			(property "Value" "C_1n_16V_X7R_0402"
				(at 15.24 -10.16 0)
				(effects
					(font
						(size 1.27 1.27)
						(thickness 0.15)
					)
					(justify left bottom)
					(hide yes)
				)
			)
			(property "Footprint" "antmicro-footprints:C_0402_1005Metric"
				(at 15.24 -12.7 0)
				(effects
					(font
						(size 1.27 1.27)
						(thickness 0.15)
					)
					(justify left bottom)
					(hide yes)
				)
			)
			(property "Datasheet" "https://www.kemet.com/en/us/capacitors/product/C0402C102J4RACTU.html"
				(at 15.24 -15.24 0)
				(effects
					(font
						(size 1.27 1.27)
						(thickness 0.15)
					)
					(justify left bottom)
					(hide yes)
				)
			)
			(property "Description" "SMD Multilayer Ceramic Capacitor, 1nF, 16V, 0402, ±5%, X7R"
				(at 0 0 0)
				(effects
					(font
						(size 1.27 1.27)
					)
					(hide yes)
				)
			)
			(property "MPN" "C0402C102J4RACTU"
				(at 15.24 -17.78 0)
				(effects
					(font
						(size 1.27 1.27)
						(thickness 0.15)
					)
					(justify left bottom)
					(hide yes)
				)
			)
			(property "Val" "1n"
				(at 15.24 -7.62 0)
				(effects
					(font
						(size 1.27 1.27)
						(thickness 0.15)
					)
					(justify left bottom)
				)
			)
			(property "Voltage" "16V"
				(at 15.24 -20.32 0)
				(effects
					(font
						(size 1.27 1.27)
						(thickness 0.15)
					)
					(justify left bottom)
					(hide yes)
				)
			)
			(property "Dielectric" "X7R"
				(at 15.24 -22.86 0)
				(effects
					(font
						(size 1.27 1.27)
						(thickness 0.15)
					)
					(justify left bottom)
					(hide yes)
				)
			)
			(property "Manufacturer" "KEMET"
				(at 15.24 -25.4 0)
				(effects
					(font
						(size 1.27 1.27)
						(thickness 0.15)
					)
					(justify left bottom)
					(hide yes)
				)
			)
			(property "License" "Apache-2.0"
				(at 15.24 -27.94 0)
				(effects
					(font
						(size 1.27 1.27)
						(thickness 0.15)
					)
					(justify left bottom)
					(hide yes)
				)
			)
			(property "Author" "Antmicro"
				(at 15.24 -30.48 0)
				(effects
					(font
						(size 1.27 1.27)
						(thickness 0.15)
					)
					(justify left bottom)
					(hide yes)
				)
			)
			(property "ki_keywords" "SMT, CAPACITOR, PASSIVE"
				(at 0 0 0)
				(effects
					(font
						(size 1.27 1.27)
					)
					(hide yes)
				)
			)
			(symbol "C_1n_16V_X7R_0402_0_1"
				(polyline
					(pts
						(xy 2.032 -1.524) (xy 2.032 1.524)
					)
					(stroke
						(width 0.3048)
						(type default)
					)
					(fill
						(type none)
					)
				)
				(polyline
					(pts
						(xy 3.048 -1.524) (xy 3.048 1.524)
					)
					(stroke
						(width 0.3302)
						(type default)
					)
					(fill
						(type none)
					)
				)
			)
			(symbol "C_1n_16V_X7R_0402_1_1"
				(pin passive line
					(at 0 0 0)
					(length 2.032)
					(name "~"
						(effects
							(font
								(size 1.27 1.27)
							)
						)
					)
					(number "1"
						(effects
							(font
								(size 1.27 1.27)
							)
						)
					)
				)
				(pin passive line
					(at 5.08 0 180)
					(length 2.032)
					(name "~"
						(effects
							(font
								(size 1.27 1.27)
							)
						)
					)
					(number "2"
						(effects
							(font
								(size 1.27 1.27)
							)
						)
					)
				)
			)
		)
	(symbol "antmicroCapacitors0402:C_1u_0402"
			(pin_numbers hide)
			(pin_names hide)
			(exclude_from_sim no)
			(in_bom yes)
			(on_board yes)
			(property "Reference" "C"
				(at 20.32 -5.08 0)
				(effects
					(font
						(size 1.27 1.27)
						(thickness 0.15)
					)
					(justify left bottom)
				)
			)
			(property "Value" "C_1u_0402"
				(at 20.32 -10.16 0)
				(effects
					(font
						(size 1.27 1.27)
						(thickness 0.15)
					)
					(justify left bottom)
					(hide yes)
				)
			)
			(property "Footprint" "antmicro-footprints:C_0402_1005Metric"
				(at 20.32 -12.7 0)
				(effects
					(font
						(size 1.27 1.27)
						(thickness 0.15)
					)
					(justify left bottom)
					(hide yes)
				)
			)
			(property "Datasheet" "https://product.tdk.com/en/search/capacitor/ceramic/mlcc/info?part_no=C1005X6S1A105K050BC"
				(at 20.32 -15.24 0)
				(effects
					(font
						(size 1.27 1.27)
						(thickness 0.15)
					)
					(justify left bottom)
					(hide yes)
				)
			)
			(property "Description" "SMD Multilayer Ceramic Capacitor, 1 µF, 10 V, 0402 [1005 Metric], ± 10%, X6S, C"
				(at 0 0 0)
				(effects
					(font
						(size 1.27 1.27)
					)
					(hide yes)
				)
			)
			(property "MPN" "C1005X6S1A105K050BC"
				(at 20.32 -17.78 0)
				(effects
					(font
						(size 1.27 1.27)
						(thickness 0.15)
					)
					(justify left bottom)
					(hide yes)
				)
			)
			(property "Manufacturer" "TDK"
				(at 20.32 -20.32 0)
				(effects
					(font
						(size 1.27 1.27)
						(thickness 0.15)
					)
					(justify left bottom)
					(hide yes)
				)
			)
			(property "License" "Apache-2.0"
				(at 20.32 -22.86 0)
				(effects
					(font
						(size 1.27 1.27)
						(thickness 0.15)
					)
					(justify left bottom)
					(hide yes)
				)
			)
			(property "Author" "Antmicro"
				(at 20.32 -25.4 0)
				(effects
					(font
						(size 1.27 1.27)
						(thickness 0.15)
					)
					(justify left bottom)
					(hide yes)
				)
			)
			(property "Val" "1u"
				(at 20.32 -7.62 0)
				(effects
					(font
						(size 1.27 1.27)
						(thickness 0.15)
					)
					(justify left bottom)
				)
			)
			(property "Voltage" ""
				(at 20.32 -27.94 0)
				(effects
					(font
						(size 1.27 1.27)
					)
					(justify left bottom)
					(hide yes)
				)
			)
			(property "Dielectric" ""
				(at 20.32 -30.48 0)
				(effects
					(font
						(size 1.27 1.27)
					)
					(justify left bottom)
					(hide yes)
				)
			)
			(property "ki_keywords" "0402, SMT, CAPACITOR, PASSIVE, CERAMIC, MLCC"
				(at 0 0 0)
				(effects
					(font
						(size 1.27 1.27)
					)
					(hide yes)
				)
			)
			(symbol "C_1u_0402_0_1"
				(polyline
					(pts
						(xy 2.032 -1.524) (xy 2.032 1.524)
					)
					(stroke
						(width 0.3048)
						(type default)
					)
					(fill
						(type none)
					)
				)
				(polyline
					(pts
						(xy 3.048 -1.524) (xy 3.048 1.524)
					)
					(stroke
						(width 0.3302)
						(type default)
					)
					(fill
						(type none)
					)
				)
			)
			(symbol "C_1u_0402_1_1"
				(pin passive line
					(at 0 0 0)
					(length 2.032)
					(name "~"
						(effects
							(font
								(size 1.27 1.27)
							)
						)
					)
					(number "1"
						(effects
							(font
								(size 1.27 1.27)
							)
						)
					)
				)
				(pin passive line
					(at 5.08 0 180)
					(length 2.032)
					(name "~"
						(effects
							(font
								(size 1.27 1.27)
							)
						)
					)
					(number "2"
						(effects
							(font
								(size 1.27 1.27)
							)
						)
					)
				)
			)
		)
	(symbol "antmicroCapacitors0402:C_1u_25V_0402"
			(pin_numbers hide)
			(pin_names hide)
			(exclude_from_sim no)
			(in_bom yes)
			(on_board yes)
			(property "Reference" "C"
				(at 20.32 -5.08 0)
				(effects
					(font
						(size 1.27 1.27)
						(thickness 0.15)
					)
					(justify left bottom)
				)
			)
			(property "Value" "C_1u_25V_0402"
				(at 20.32 -10.16 0)
				(effects
					(font
						(size 1.27 1.27)
						(thickness 0.15)
					)
					(justify left bottom)
					(hide yes)
				)
			)
			(property "Footprint" "antmicro-footprints:C_0402_1005Metric"
				(at 20.32 -12.7 0)
				(effects
					(font
						(size 1.27 1.27)
						(thickness 0.15)
					)
					(justify left bottom)
					(hide yes)
				)
			)
			(property "Datasheet" "https://www.murata.com/products/productdetail?partno=GRM155R61E105KE11%23"
				(at 20.32 -15.24 0)
				(effects
					(font
						(size 1.27 1.27)
						(thickness 0.15)
					)
					(justify left bottom)
					(hide yes)
				)
			)
			(property "Description" "SMD Multilayer Ceramic Capacitor, 1 µF, 25 V, 0402 [1005 Metric], ± 10%, X5R, GRM Series"
				(at 0 0 0)
				(effects
					(font
						(size 1.27 1.27)
					)
					(hide yes)
				)
			)
			(property "MPN" "GRM155R61E105KE11J"
				(at 20.32 -17.78 0)
				(effects
					(font
						(size 1.27 1.27)
						(thickness 0.15)
					)
					(justify left bottom)
					(hide yes)
				)
			)
			(property "Manufacturer" "Murata"
				(at 20.32 -20.32 0)
				(effects
					(font
						(size 1.27 1.27)
						(thickness 0.15)
					)
					(justify left bottom)
					(hide yes)
				)
			)
			(property "License" "Apache-2.0"
				(at 20.32 -22.86 0)
				(effects
					(font
						(size 1.27 1.27)
						(thickness 0.15)
					)
					(justify left bottom)
					(hide yes)
				)
			)
			(property "Author" "Antmicro"
				(at 20.32 -25.4 0)
				(effects
					(font
						(size 1.27 1.27)
						(thickness 0.15)
					)
					(justify left bottom)
					(hide yes)
				)
			)
			(property "Val" "1u"
				(at 20.32 -7.62 0)
				(effects
					(font
						(size 1.27 1.27)
						(thickness 0.15)
					)
					(justify left bottom)
				)
			)
			(property "Voltage" "25V"
				(at 20.32 -27.94 0)
				(effects
					(font
						(size 1.27 1.27)
					)
					(justify left bottom)
					(hide yes)
				)
			)
			(property "Dielectric" "X5R"
				(at 20.32 -30.48 0)
				(effects
					(font
						(size 1.27 1.27)
					)
					(justify left bottom)
					(hide yes)
				)
			)
			(property "ki_keywords" "0402, SMT, CAPACITOR, PASSIVE, CERAMIC"
				(at 0 0 0)
				(effects
					(font
						(size 1.27 1.27)
					)
					(hide yes)
				)
			)
			(symbol "C_1u_25V_0402_0_1"
				(polyline
					(pts
						(xy 2.032 -1.524) (xy 2.032 1.524)
					)
					(stroke
						(width 0.3048)
						(type default)
					)
					(fill
						(type none)
					)
				)
				(polyline
					(pts
						(xy 3.048 -1.524) (xy 3.048 1.524)
					)
					(stroke
						(width 0.3302)
						(type default)
					)
					(fill
						(type none)
					)
				)
			)
			(symbol "C_1u_25V_0402_1_1"
				(pin passive line
					(at 0 0 0)
					(length 2.032)
					(name "~"
						(effects
							(font
								(size 1.27 1.27)
							)
						)
					)
					(number "1"
						(effects
							(font
								(size 1.27 1.27)
							)
						)
					)
				)
				(pin passive line
					(at 5.08 0 180)
					(length 2.032)
					(name "~"
						(effects
							(font
								(size 1.27 1.27)
							)
						)
					)
					(number "2"
						(effects
							(font
								(size 1.27 1.27)
							)
						)
					)
				)
			)
		)
	(symbol "antmicroCapacitors0402:C_220n_0402"
			(pin_numbers hide)
			(pin_names hide)
			(exclude_from_sim no)
			(in_bom yes)
			(on_board yes)
			(property "Reference" "C"
				(at 20.32 -5.08 0)
				(effects
					(font
						(size 1.27 1.27)
						(thickness 0.15)
					)
					(justify left bottom)
				)
			)
			(property "Value" "C_220n_0402"
				(at 20.32 -10.16 0)
				(effects
					(font
						(size 1.27 1.27)
						(thickness 0.15)
					)
					(justify left bottom)
					(hide yes)
				)
			)
			(property "Footprint" "antmicro-footprints:C_0402_1005Metric"
				(at 20.32 -12.7 0)
				(effects
					(font
						(size 1.27 1.27)
						(thickness 0.15)
					)
					(justify left bottom)
					(hide yes)
				)
			)
			(property "Datasheet" "https://www.yageo.com/en/Chart/Download/pdf/CC0402KRX5R6BB224"
				(at 20.32 -15.24 0)
				(effects
					(font
						(size 1.27 1.27)
						(thickness 0.15)
					)
					(justify left bottom)
					(hide yes)
				)
			)
			(property "Description" "SMD Multilayer Ceramic Capacitor, 0.22 µF, 10 V, 0402 [1005 Metric], ± 10%, X5R, CC Series"
				(at 0 0 0)
				(effects
					(font
						(size 1.27 1.27)
					)
					(hide yes)
				)
			)
			(property "MPN" "CC0402KRX5R6BB224"
				(at 20.32 -17.78 0)
				(effects
					(font
						(size 1.27 1.27)
						(thickness 0.15)
					)
					(justify left bottom)
					(hide yes)
				)
			)
			(property "Manufacturer" "YAGEO"
				(at 20.32 -20.32 0)
				(effects
					(font
						(size 1.27 1.27)
						(thickness 0.15)
					)
					(justify left bottom)
					(hide yes)
				)
			)
			(property "License" "Apache-2.0"
				(at 20.32 -22.86 0)
				(effects
					(font
						(size 1.27 1.27)
						(thickness 0.15)
					)
					(justify left bottom)
					(hide yes)
				)
			)
			(property "Author" "Antmicro"
				(at 20.32 -25.4 0)
				(effects
					(font
						(size 1.27 1.27)
						(thickness 0.15)
					)
					(justify left bottom)
					(hide yes)
				)
			)
			(property "Val" "220n"
				(at 20.32 -7.62 0)
				(effects
					(font
						(size 1.27 1.27)
						(thickness 0.15)
					)
					(justify left bottom)
				)
			)
			(property "Voltage" ""
				(at 20.32 -27.94 0)
				(effects
					(font
						(size 1.27 1.27)
					)
					(justify left bottom)
					(hide yes)
				)
			)
			(property "Dielectric" ""
				(at 20.32 -30.48 0)
				(effects
					(font
						(size 1.27 1.27)
					)
					(justify left bottom)
					(hide yes)
				)
			)
			(property "ki_keywords" "0402, SMT, CAPACITOR, PASSIVE, MLCC, CERAMIC"
				(at 0 0 0)
				(effects
					(font
						(size 1.27 1.27)
					)
					(hide yes)
				)
			)
			(symbol "C_220n_0402_0_1"
				(polyline
					(pts
						(xy 2.032 -1.524) (xy 2.032 1.524)
					)
					(stroke
						(width 0.3048)
						(type default)
					)
					(fill
						(type none)
					)
				)
				(polyline
					(pts
						(xy 3.048 -1.524) (xy 3.048 1.524)
					)
					(stroke
						(width 0.3302)
						(type default)
					)
					(fill
						(type none)
					)
				)
			)
			(symbol "C_220n_0402_1_1"
				(pin passive line
					(at 0 0 0)
					(length 2.032)
					(name "~"
						(effects
							(font
								(size 1.27 1.27)
							)
						)
					)
					(number "1"
						(effects
							(font
								(size 1.27 1.27)
							)
						)
					)
				)
				(pin passive line
					(at 5.08 0 180)
					(length 2.032)
					(name "~"
						(effects
							(font
								(size 1.27 1.27)
							)
						)
					)
					(number "2"
						(effects
							(font
								(size 1.27 1.27)
							)
						)
					)
				)
			)
		)
	(symbol "antmicroCapacitors0402:C_47p_0402"
			(pin_numbers hide)
			(pin_names hide)
			(exclude_from_sim no)
			(in_bom yes)
			(on_board yes)
			(property "Reference" "C"
				(at 20.32 -5.08 0)
				(effects
					(font
						(size 1.27 1.27)
						(thickness 0.15)
					)
					(justify left bottom)
				)
			)
			(property "Value" "C_47p_0402"
				(at 20.32 -10.16 0)
				(effects
					(font
						(size 1.27 1.27)
						(thickness 0.15)
					)
					(justify left bottom)
					(hide yes)
				)
			)
			(property "Footprint" "antmicro-footprints:C_0402_1005Metric"
				(at 20.32 -12.7 0)
				(effects
					(font
						(size 1.27 1.27)
						(thickness 0.15)
					)
					(justify left bottom)
					(hide yes)
				)
			)
			(property "Datasheet" "https://www.kemet.com/en/us/capacitors/product/C0402C470J5GACTU.html"
				(at 20.32 -15.24 0)
				(effects
					(font
						(size 1.27 1.27)
						(thickness 0.15)
					)
					(justify left bottom)
					(hide yes)
				)
			)
			(property "Description" "SMD Multilayer Ceramic Capacitor, 47 pF, 50 V, 0402 [1005 Metric], ± 5%, C0G / NP0, C Series KEMET"
				(at 0 0 0)
				(effects
					(font
						(size 1.27 1.27)
					)
					(hide yes)
				)
			)
			(property "MPN" "C0402C470J5GACTU"
				(at 20.32 -17.78 0)
				(effects
					(font
						(size 1.27 1.27)
						(thickness 0.15)
					)
					(justify left bottom)
					(hide yes)
				)
			)
			(property "Manufacturer" "KEMET"
				(at 20.32 -20.32 0)
				(effects
					(font
						(size 1.27 1.27)
						(thickness 0.15)
					)
					(justify left bottom)
					(hide yes)
				)
			)
			(property "License" "Apache-2.0"
				(at 20.32 -22.86 0)
				(effects
					(font
						(size 1.27 1.27)
						(thickness 0.15)
					)
					(justify left bottom)
					(hide yes)
				)
			)
			(property "Author" "Antmicro"
				(at 20.32 -25.4 0)
				(effects
					(font
						(size 1.27 1.27)
						(thickness 0.15)
					)
					(justify left bottom)
					(hide yes)
				)
			)
			(property "Val" "47p"
				(at 20.32 -7.62 0)
				(effects
					(font
						(size 1.27 1.27)
						(thickness 0.15)
					)
					(justify left bottom)
				)
			)
			(property "Voltage" ""
				(at 20.32 -27.94 0)
				(effects
					(font
						(size 1.27 1.27)
					)
					(justify left bottom)
					(hide yes)
				)
			)
			(property "Dielectric" "C0G"
				(at 20.32 -30.48 0)
				(effects
					(font
						(size 1.27 1.27)
					)
					(justify left bottom)
					(hide yes)
				)
			)
			(property "ki_keywords" "0402, SMT, CAPACITOR, PASSIVE, CERAMIC, MLCC"
				(at 0 0 0)
				(effects
					(font
						(size 1.27 1.27)
					)
					(hide yes)
				)
			)
			(symbol "C_47p_0402_0_1"
				(polyline
					(pts
						(xy 2.032 -1.524) (xy 2.032 1.524)
					)
					(stroke
						(width 0.3048)
						(type default)
					)
					(fill
						(type none)
					)
				)
				(polyline
					(pts
						(xy 3.048 -1.524) (xy 3.048 1.524)
					)
					(stroke
						(width 0.3302)
						(type default)
					)
					(fill
						(type none)
					)
				)
			)
			(symbol "C_47p_0402_1_1"
				(pin passive line
					(at 0 0 0)
					(length 2.032)
					(name "~"
						(effects
							(font
								(size 1.27 1.27)
							)
						)
					)
					(number "1"
						(effects
							(font
								(size 1.27 1.27)
							)
						)
					)
				)
				(pin passive line
					(at 5.08 0 180)
					(length 2.032)
					(name "~"
						(effects
							(font
								(size 1.27 1.27)
							)
						)
					)
					(number "2"
						(effects
							(font
								(size 1.27 1.27)
							)
						)
					)
				)
			)
		)
	(symbol "antmicroCapacitors0402:C_4u7_25V_0402"
			(pin_numbers hide)
			(pin_names hide)
			(exclude_from_sim no)
			(in_bom yes)
			(on_board yes)
			(property "Reference" "C"
				(at 20.32 -5.08 0)
				(effects
					(font
						(size 1.27 1.27)
						(thickness 0.15)
					)
					(justify left bottom)
				)
			)
			(property "Value" "C_4u7_25V_0402"
				(at 20.32 -10.16 0)
				(effects
					(font
						(size 1.27 1.27)
						(thickness 0.15)
					)
					(justify left bottom)
					(hide yes)
				)
			)
			(property "Footprint" "antmicro-footprints:C_0402_1005Metric"
				(at 20.32 -12.7 0)
				(effects
					(font
						(size 1.27 1.27)
						(thickness 0.15)
					)
					(justify left bottom)
					(hide yes)
				)
			)
			(property "Datasheet" "https://www.murata.com/products/productdetail?partno=GRM155C61E475ME15%23"
				(at 20.32 -15.24 0)
				(effects
					(font
						(size 1.27 1.27)
						(thickness 0.15)
					)
					(justify left bottom)
					(hide yes)
				)
			)
			(property "Description" "SMD Multilayer Ceramic Capacitor"
				(at 0 0 0)
				(effects
					(font
						(size 1.27 1.27)
					)
					(hide yes)
				)
			)
			(property "MPN" "GRM155C61E475ME15J"
				(at 20.32 -17.78 0)
				(effects
					(font
						(size 1.27 1.27)
						(thickness 0.15)
					)
					(justify left bottom)
					(hide yes)
				)
			)
			(property "Manufacturer" "Murata"
				(at 20.32 -20.32 0)
				(effects
					(font
						(size 1.27 1.27)
						(thickness 0.15)
					)
					(justify left bottom)
					(hide yes)
				)
			)
			(property "License" "Apache-2.0"
				(at 20.32 -22.86 0)
				(effects
					(font
						(size 1.27 1.27)
						(thickness 0.15)
					)
					(justify left bottom)
					(hide yes)
				)
			)
			(property "Author" "Antmicro"
				(at 20.32 -25.4 0)
				(effects
					(font
						(size 1.27 1.27)
						(thickness 0.15)
					)
					(justify left bottom)
					(hide yes)
				)
			)
			(property "Val" "4u7"
				(at 20.32 -7.62 0)
				(effects
					(font
						(size 1.27 1.27)
						(thickness 0.15)
					)
					(justify left bottom)
				)
			)
			(property "Voltage" "25V"
				(at 20.32 -27.94 0)
				(effects
					(font
						(size 1.27 1.27)
					)
					(justify left bottom)
					(hide yes)
				)
			)
			(property "Dielectric" "X5S"
				(at 20.32 -30.48 0)
				(effects
					(font
						(size 1.27 1.27)
					)
					(justify left bottom)
					(hide yes)
				)
			)
			(property "ki_keywords" "0402, SMT, CAPACITOR, PASSIVE, CERAMIC"
				(at 0 0 0)
				(effects
					(font
						(size 1.27 1.27)
					)
					(hide yes)
				)
			)
			(symbol "C_4u7_25V_0402_0_1"
				(polyline
					(pts
						(xy 2.032 -1.524) (xy 2.032 1.524)
					)
					(stroke
						(width 0.3048)
						(type default)
					)
					(fill
						(type none)
					)
				)
				(polyline
					(pts
						(xy 3.048 -1.524) (xy 3.048 1.524)
					)
					(stroke
						(width 0.3302)
						(type default)
					)
					(fill
						(type none)
					)
				)
			)
			(symbol "C_4u7_25V_0402_1_1"
				(pin passive line
					(at 0 0 0)
					(length 2.032)
					(name "~"
						(effects
							(font
								(size 1.27 1.27)
							)
						)
					)
					(number "1"
						(effects
							(font
								(size 1.27 1.27)
							)
						)
					)
				)
				(pin passive line
					(at 5.08 0 180)
					(length 2.032)
					(name "~"
						(effects
							(font
								(size 1.27 1.27)
							)
						)
					)
					(number "2"
						(effects
							(font
								(size 1.27 1.27)
							)
						)
					)
				)
			)
		)
	(symbol "antmicroCapacitors0603:C_10n_0603"
			(pin_numbers hide)
			(pin_names hide)
			(exclude_from_sim no)
			(in_bom yes)
			(on_board yes)
			(property "Reference" "C"
				(at 20.32 -5.08 0)
				(effects
					(font
						(size 1.27 1.27)
						(thickness 0.15)
					)
					(justify left bottom)
				)
			)
			(property "Value" "C_10n_0603"
				(at 20.32 -10.16 0)
				(effects
					(font
						(size 1.27 1.27)
						(thickness 0.15)
					)
					(justify left bottom)
					(hide yes)
				)
			)
			(property "Footprint" "antmicro-footprints:C_0603_1608Metric"
				(at 20.32 -12.7 0)
				(effects
					(font
						(size 1.27 1.27)
						(thickness 0.15)
					)
					(justify left bottom)
					(hide yes)
				)
			)
			(property "Datasheet" "https://spicat.kyocera-avx.com/product/mlcc/chartview/06031C103JAT2A/"
				(at 20.32 -15.24 0)
				(effects
					(font
						(size 1.27 1.27)
						(thickness 0.15)
					)
					(justify left bottom)
					(hide yes)
				)
			)
			(property "Description" "SMD Multilayer Ceramic Capacitor, 10000 pF, 100 V, 0603 [1608 Metric], ± 5%, X7R, AVX 0603 MLCC"
				(at 0 0 0)
				(effects
					(font
						(size 1.27 1.27)
					)
					(hide yes)
				)
			)
			(property "MPN" "06031C103JAT2A"
				(at 20.32 -17.78 0)
				(effects
					(font
						(size 1.27 1.27)
						(thickness 0.15)
					)
					(justify left bottom)
					(hide yes)
				)
			)
			(property "Manufacturer" "AVX"
				(at 20.32 -20.32 0)
				(effects
					(font
						(size 1.27 1.27)
						(thickness 0.15)
					)
					(justify left bottom)
					(hide yes)
				)
			)
			(property "License" "Apache-2.0"
				(at 20.32 -22.86 0)
				(effects
					(font
						(size 1.27 1.27)
						(thickness 0.15)
					)
					(justify left bottom)
					(hide yes)
				)
			)
			(property "Author" "Antmicro"
				(at 20.32 -25.4 0)
				(effects
					(font
						(size 1.27 1.27)
						(thickness 0.15)
					)
					(justify left bottom)
					(hide yes)
				)
			)
			(property "Val" "10n"
				(at 20.32 -7.62 0)
				(effects
					(font
						(size 1.27 1.27)
						(thickness 0.15)
					)
					(justify left bottom)
				)
			)
			(property "Voltage" ""
				(at 20.32 -27.94 0)
				(effects
					(font
						(size 1.27 1.27)
					)
					(justify left bottom)
					(hide yes)
				)
			)
			(property "Dielectric" ""
				(at 20.32 -30.48 0)
				(effects
					(font
						(size 1.27 1.27)
					)
					(justify left bottom)
					(hide yes)
				)
			)
			(property "ki_keywords" "0603, SMT, CAPACITOR, PASSIVE, CERAMIC, MLCC"
				(at 0 0 0)
				(effects
					(font
						(size 1.27 1.27)
					)
					(hide yes)
				)
			)
			(symbol "C_10n_0603_0_1"
				(polyline
					(pts
						(xy 2.032 -1.524) (xy 2.032 1.524)
					)
					(stroke
						(width 0.3048)
						(type default)
					)
					(fill
						(type none)
					)
				)
				(polyline
					(pts
						(xy 3.048 -1.524) (xy 3.048 1.524)
					)
					(stroke
						(width 0.3302)
						(type default)
					)
					(fill
						(type none)
					)
				)
			)
			(symbol "C_10n_0603_1_1"
				(pin passive line
					(at 0 0 0)
					(length 2.032)
					(name "~"
						(effects
							(font
								(size 1.27 1.27)
							)
						)
					)
					(number "1"
						(effects
							(font
								(size 1.27 1.27)
							)
						)
					)
				)
				(pin passive line
					(at 5.08 0 180)
					(length 2.032)
					(name "~"
						(effects
							(font
								(size 1.27 1.27)
							)
						)
					)
					(number "2"
						(effects
							(font
								(size 1.27 1.27)
							)
						)
					)
				)
			)
		)
	(symbol "antmicroCapacitors0603:C_10u_0603"
			(pin_numbers hide)
			(pin_names hide)
			(exclude_from_sim no)
			(in_bom yes)
			(on_board yes)
			(property "Reference" "C"
				(at 20.32 -5.08 0)
				(effects
					(font
						(size 1.27 1.27)
						(thickness 0.15)
					)
					(justify left bottom)
				)
			)
			(property "Value" "C_10u_0603"
				(at 20.32 -10.16 0)
				(effects
					(font
						(size 1.27 1.27)
						(thickness 0.15)
					)
					(justify left bottom)
					(hide yes)
				)
			)
			(property "Footprint" "antmicro-footprints:C_0603_1608Metric"
				(at 20.32 -12.7 0)
				(effects
					(font
						(size 1.27 1.27)
						(thickness 0.15)
					)
					(justify left bottom)
					(hide yes)
				)
			)
			(property "Datasheet" "https://www.murata.com/products/productdetail?partno=GRM188R61A106KE69%23"
				(at 20.32 -15.24 0)
				(effects
					(font
						(size 1.27 1.27)
						(thickness 0.15)
					)
					(justify left bottom)
					(hide yes)
				)
			)
			(property "Description" "SMD Multilayer Ceramic Capacitor, 10 µF, 10 V, 0603 [1608 Metric], ± 10%, X5R, GRM Series"
				(at 0 0 0)
				(effects
					(font
						(size 1.27 1.27)
					)
					(hide yes)
				)
			)
			(property "MPN" "GRM188R61A106KE69D"
				(at 20.32 -17.78 0)
				(effects
					(font
						(size 1.27 1.27)
						(thickness 0.15)
					)
					(justify left bottom)
					(hide yes)
				)
			)
			(property "Manufacturer" "Murata"
				(at 20.32 -20.32 0)
				(effects
					(font
						(size 1.27 1.27)
						(thickness 0.15)
					)
					(justify left bottom)
					(hide yes)
				)
			)
			(property "License" "Apache-2.0"
				(at 20.32 -22.86 0)
				(effects
					(font
						(size 1.27 1.27)
						(thickness 0.15)
					)
					(justify left bottom)
					(hide yes)
				)
			)
			(property "Author" "Antmicro"
				(at 20.32 -25.4 0)
				(effects
					(font
						(size 1.27 1.27)
						(thickness 0.15)
					)
					(justify left bottom)
					(hide yes)
				)
			)
			(property "Val" "10u"
				(at 20.32 -7.62 0)
				(effects
					(font
						(size 1.27 1.27)
						(thickness 0.15)
					)
					(justify left bottom)
				)
			)
			(property "Voltage" ""
				(at 20.32 -27.94 0)
				(effects
					(font
						(size 1.27 1.27)
					)
					(justify left bottom)
					(hide yes)
				)
			)
			(property "Dielectric" "template_dielectric"
				(at 20.32 -30.48 0)
				(effects
					(font
						(size 1.27 1.27)
					)
					(justify left bottom)
					(hide yes)
				)
			)
			(property "ki_keywords" "0603, SMT, CAPACITOR, PASSIVE, CERAMIC, MLCC"
				(at 0 0 0)
				(effects
					(font
						(size 1.27 1.27)
					)
					(hide yes)
				)
			)
			(symbol "C_10u_0603_0_1"
				(polyline
					(pts
						(xy 2.032 -1.524) (xy 2.032 1.524)
					)
					(stroke
						(width 0.3048)
						(type default)
					)
					(fill
						(type none)
					)
				)
				(polyline
					(pts
						(xy 3.048 -1.524) (xy 3.048 1.524)
					)
					(stroke
						(width 0.3302)
						(type default)
					)
					(fill
						(type none)
					)
				)
			)
			(symbol "C_10u_0603_1_1"
				(pin passive line
					(at 0 0 0)
					(length 2.032)
					(name "~"
						(effects
							(font
								(size 1.27 1.27)
							)
						)
					)
					(number "1"
						(effects
							(font
								(size 1.27 1.27)
							)
						)
					)
				)
				(pin passive line
					(at 5.08 0 180)
					(length 2.032)
					(name "~"
						(effects
							(font
								(size 1.27 1.27)
							)
						)
					)
					(number "2"
						(effects
							(font
								(size 1.27 1.27)
							)
						)
					)
				)
			)
		)
	(symbol "antmicroCapacitors0603:C_10u_25V_0603"
			(pin_numbers hide)
			(pin_names hide)
			(exclude_from_sim no)
			(in_bom yes)
			(on_board yes)
			(property "Reference" "C"
				(at 20.32 -5.08 0)
				(effects
					(font
						(size 1.27 1.27)
						(thickness 0.15)
					)
					(justify left bottom)
				)
			)
			(property "Value" "C_10u_25V_0603"
				(at 20.32 -10.16 0)
				(effects
					(font
						(size 1.27 1.27)
						(thickness 0.15)
					)
					(justify left bottom)
					(hide yes)
				)
			)
			(property "Footprint" "antmicro-footprints:C_0603_1608Metric"
				(at 20.32 -12.7 0)
				(effects
					(font
						(size 1.27 1.27)
						(thickness 0.15)
					)
					(justify left bottom)
					(hide yes)
				)
			)
			(property "Datasheet" "https://product.tdk.com/en/search/capacitor/ceramic/mlcc/info?part_no=C1608X5R1E106M080AC"
				(at 20.32 -15.24 0)
				(effects
					(font
						(size 1.27 1.27)
						(thickness 0.15)
					)
					(justify left bottom)
					(hide yes)
				)
			)
			(property "Description" "SMD Multilayer Ceramic Capacitor, 10 µF, 25 V, 0603 [1608 Metric], ± 20%, X5R, C"
				(at 0 0 0)
				(effects
					(font
						(size 1.27 1.27)
					)
					(hide yes)
				)
			)
			(property "MPN" "C1608X5R1E106M080AC"
				(at 20.32 -17.78 0)
				(effects
					(font
						(size 1.27 1.27)
						(thickness 0.15)
					)
					(justify left bottom)
					(hide yes)
				)
			)
			(property "Manufacturer" "TDK"
				(at 20.32 -20.32 0)
				(effects
					(font
						(size 1.27 1.27)
						(thickness 0.15)
					)
					(justify left bottom)
					(hide yes)
				)
			)
			(property "License" "Apache-2.0"
				(at 20.32 -22.86 0)
				(effects
					(font
						(size 1.27 1.27)
						(thickness 0.15)
					)
					(justify left bottom)
					(hide yes)
				)
			)
			(property "Author" "Antmicro"
				(at 20.32 -25.4 0)
				(effects
					(font
						(size 1.27 1.27)
						(thickness 0.15)
					)
					(justify left bottom)
					(hide yes)
				)
			)
			(property "Val" "10u"
				(at 20.32 -7.62 0)
				(effects
					(font
						(size 1.27 1.27)
						(thickness 0.15)
					)
					(justify left bottom)
				)
			)
			(property "Voltage" "25V"
				(at 20.32 -27.94 0)
				(effects
					(font
						(size 1.27 1.27)
					)
					(justify left bottom)
					(hide yes)
				)
			)
			(property "Dielectric" ""
				(at 20.32 -30.48 0)
				(effects
					(font
						(size 1.27 1.27)
					)
					(justify left bottom)
					(hide yes)
				)
			)
			(property "ki_keywords" "0603, SMT, CAPACITOR, PASSIVE, CERAMIC, MLCC"
				(at 0 0 0)
				(effects
					(font
						(size 1.27 1.27)
					)
					(hide yes)
				)
			)
			(symbol "C_10u_25V_0603_0_1"
				(polyline
					(pts
						(xy 2.032 -1.524) (xy 2.032 1.524)
					)
					(stroke
						(width 0.3048)
						(type default)
					)
					(fill
						(type none)
					)
				)
				(polyline
					(pts
						(xy 3.048 -1.524) (xy 3.048 1.524)
					)
					(stroke
						(width 0.3302)
						(type default)
					)
					(fill
						(type none)
					)
				)
			)
			(symbol "C_10u_25V_0603_1_1"
				(pin passive line
					(at 0 0 0)
					(length 2.032)
					(name "~"
						(effects
							(font
								(size 1.27 1.27)
							)
						)
					)
					(number "1"
						(effects
							(font
								(size 1.27 1.27)
							)
						)
					)
				)
				(pin passive line
					(at 5.08 0 180)
					(length 2.032)
					(name "~"
						(effects
							(font
								(size 1.27 1.27)
							)
						)
					)
					(number "2"
						(effects
							(font
								(size 1.27 1.27)
							)
						)
					)
				)
			)
		)
	(symbol "antmicroCapacitors0603:C_22u_16V_0603"
			(pin_numbers hide)
			(pin_names hide)
			(exclude_from_sim no)
			(in_bom yes)
			(on_board yes)
			(property "Reference" "C"
				(at 20.32 -5.08 0)
				(effects
					(font
						(size 1.27 1.27)
						(thickness 0.15)
					)
					(justify left bottom)
				)
			)
			(property "Value" "C_22u_16V_0603"
				(at 20.32 -10.16 0)
				(effects
					(font
						(size 1.27 1.27)
						(thickness 0.15)
					)
					(justify left bottom)
					(hide yes)
				)
			)
			(property "Footprint" "antmicro-footprints:C_0603_1608Metric_EIA"
				(at 20.32 -12.7 0)
				(effects
					(font
						(size 1.27 1.27)
						(thickness 0.15)
					)
					(justify left bottom)
					(hide yes)
				)
			)
			(property "Datasheet" "https://product.samsungsem.com/mlcc/CL10A226MO7JZN.do"
				(at 20.32 -15.24 0)
				(effects
					(font
						(size 1.27 1.27)
						(thickness 0.15)
					)
					(justify left bottom)
					(hide yes)
				)
			)
			(property "Description" "SMD Multilayer Ceramic Capacitor"
				(at 0 0 0)
				(effects
					(font
						(size 1.27 1.27)
					)
					(hide yes)
				)
			)
			(property "MPN" "CL10A226MO7JZNC"
				(at 20.32 -17.78 0)
				(effects
					(font
						(size 1.27 1.27)
						(thickness 0.15)
					)
					(justify left bottom)
					(hide yes)
				)
			)
			(property "Manufacturer" "Samsung Electro-Mechanics"
				(at 20.32 -20.32 0)
				(effects
					(font
						(size 1.27 1.27)
						(thickness 0.15)
					)
					(justify left bottom)
					(hide yes)
				)
			)
			(property "License" "Apache-2.0"
				(at 20.32 -22.86 0)
				(effects
					(font
						(size 1.27 1.27)
						(thickness 0.15)
					)
					(justify left bottom)
					(hide yes)
				)
			)
			(property "Author" "Antmicro"
				(at 20.32 -25.4 0)
				(effects
					(font
						(size 1.27 1.27)
						(thickness 0.15)
					)
					(justify left bottom)
					(hide yes)
				)
			)
			(property "Val" "22u"
				(at 20.32 -7.62 0)
				(effects
					(font
						(size 1.27 1.27)
						(thickness 0.15)
					)
					(justify left bottom)
				)
			)
			(property "Voltage" "16V"
				(at 20.32 -27.94 0)
				(effects
					(font
						(size 1.27 1.27)
					)
					(justify left bottom)
					(hide yes)
				)
			)
			(property "Dielectric" ""
				(at 20.32 -30.48 0)
				(effects
					(font
						(size 1.27 1.27)
					)
					(justify left bottom)
					(hide yes)
				)
			)
			(property "ki_keywords" "0603, SMT, CAPACITOR, PASSIVE, CERAMIC"
				(at 0 0 0)
				(effects
					(font
						(size 1.27 1.27)
					)
					(hide yes)
				)
			)
			(symbol "C_22u_16V_0603_0_1"
				(polyline
					(pts
						(xy 2.032 -1.524) (xy 2.032 1.524)
					)
					(stroke
						(width 0.3048)
						(type default)
					)
					(fill
						(type none)
					)
				)
				(polyline
					(pts
						(xy 3.048 -1.524) (xy 3.048 1.524)
					)
					(stroke
						(width 0.3302)
						(type default)
					)
					(fill
						(type none)
					)
				)
			)
			(symbol "C_22u_16V_0603_1_1"
				(pin passive line
					(at 0 0 0)
					(length 2.032)
					(name "~"
						(effects
							(font
								(size 1.27 1.27)
							)
						)
					)
					(number "1"
						(effects
							(font
								(size 1.27 1.27)
							)
						)
					)
				)
				(pin passive line
					(at 5.08 0 180)
					(length 2.032)
					(name "~"
						(effects
							(font
								(size 1.27 1.27)
							)
						)
					)
					(number "2"
						(effects
							(font
								(size 1.27 1.27)
							)
						)
					)
				)
			)
		)
	(symbol "antmicroCapacitorsmisc:C_100n_100V_0805"
			(pin_numbers hide)
			(pin_names hide)
			(exclude_from_sim no)
			(in_bom yes)
			(on_board yes)
			(property "Reference" "C"
				(at 20.32 -5.08 0)
				(effects
					(font
						(size 1.27 1.27)
						(thickness 0.15)
					)
					(justify left bottom)
				)
			)
			(property "Value" "C_100n_100V_0805"
				(at 20.32 -10.16 0)
				(effects
					(font
						(size 1.27 1.27)
						(thickness 0.15)
					)
					(justify left bottom)
					(hide yes)
				)
			)
			(property "Footprint" "antmicro-footprints:C_0805_2012Metric"
				(at 20.32 -12.7 0)
				(effects
					(font
						(size 1.27 1.27)
						(thickness 0.15)
					)
					(justify left bottom)
					(hide yes)
				)
			)
			(property "Datasheet" "https://product.samsungsem.com/mlcc/CL21B104KCFNNN.do"
				(at 20.32 -15.24 0)
				(effects
					(font
						(size 1.27 1.27)
						(thickness 0.15)
					)
					(justify left bottom)
					(hide yes)
				)
			)
			(property "Description" "SMT Multilayer Ceramic Capacitor, 0.1 µF, 100 V, 0805 [2012 Metric], ± 10%, X7R, CL"
				(at 0 0 0)
				(effects
					(font
						(size 1.27 1.27)
					)
					(hide yes)
				)
			)
			(property "MPN" "CL21B104KCFNNNE"
				(at 20.32 -17.78 0)
				(effects
					(font
						(size 1.27 1.27)
						(thickness 0.15)
					)
					(justify left bottom)
					(hide yes)
				)
			)
			(property "Manufacturer" "Samsung Electro-Mechanics"
				(at 20.32 -20.32 0)
				(effects
					(font
						(size 1.27 1.27)
						(thickness 0.15)
					)
					(justify left bottom)
					(hide yes)
				)
			)
			(property "License" "Apache-2.0"
				(at 20.32 -22.86 0)
				(effects
					(font
						(size 1.27 1.27)
						(thickness 0.15)
					)
					(justify left bottom)
					(hide yes)
				)
			)
			(property "Author" "Antmicro"
				(at 20.32 -25.4 0)
				(effects
					(font
						(size 1.27 1.27)
						(thickness 0.15)
					)
					(justify left bottom)
					(hide yes)
				)
			)
			(property "Val" "100n"
				(at 20.32 -7.62 0)
				(effects
					(font
						(size 1.27 1.27)
						(thickness 0.15)
					)
					(justify left bottom)
				)
			)
			(property "Voltage" "100V"
				(at 20.32 -27.94 0)
				(effects
					(font
						(size 1.27 1.27)
					)
					(justify left bottom)
				)
			)
			(property "Dielectric" "X7R"
				(at 20.32 -30.48 0)
				(effects
					(font
						(size 1.27 1.27)
					)
					(justify left bottom)
					(hide yes)
				)
			)
			(property "Public" "False"
				(at 20.32 -33.02 0)
				(effects
					(font
						(size 1.27 1.27)
					)
					(justify left bottom)
					(hide yes)
				)
			)
			(property "ki_keywords" "0805, SMT, CAPACITOR, PASSIVE"
				(at 0 0 0)
				(effects
					(font
						(size 1.27 1.27)
					)
					(hide yes)
				)
			)
			(symbol "C_100n_100V_0805_0_1"
				(polyline
					(pts
						(xy 2.032 -1.524) (xy 2.032 1.524)
					)
					(stroke
						(width 0.3048)
						(type default)
					)
					(fill
						(type none)
					)
				)
				(polyline
					(pts
						(xy 3.048 -1.524) (xy 3.048 1.524)
					)
					(stroke
						(width 0.3302)
						(type default)
					)
					(fill
						(type none)
					)
				)
			)
			(symbol "C_100n_100V_0805_1_1"
				(pin passive line
					(at 0 0 0)
					(length 2.032)
					(name "~"
						(effects
							(font
								(size 1.27 1.27)
							)
						)
					)
					(number "1"
						(effects
							(font
								(size 1.27 1.27)
							)
						)
					)
				)
				(pin passive line
					(at 5.08 0 180)
					(length 2.032)
					(name "~"
						(effects
							(font
								(size 1.27 1.27)
							)
						)
					)
					(number "2"
						(effects
							(font
								(size 1.27 1.27)
							)
						)
					)
				)
			)
		)
	(symbol "antmicroCapacitorsmisc:C_22u_100V_2220"
			(pin_numbers hide)
			(pin_names hide)
			(exclude_from_sim no)
			(in_bom yes)
			(on_board yes)
			(property "Reference" "C"
				(at 20.32 -5.08 0)
				(effects
					(font
						(size 1.27 1.27)
						(thickness 0.15)
					)
					(justify left bottom)
				)
			)
			(property "Value" "C_22u_100V_2220"
				(at 20.32 -10.16 0)
				(effects
					(font
						(size 1.27 1.27)
						(thickness 0.15)
					)
					(justify left bottom)
					(hide yes)
				)
			)
			(property "Footprint" "antmicro-footprints:C_2220_5650Metric"
				(at 20.32 -12.7 0)
				(effects
					(font
						(size 1.27 1.27)
						(thickness 0.15)
					)
					(justify left bottom)
					(hide yes)
				)
			)
			(property "Datasheet" "https://product.tdk.com/en/search/capacitor/ceramic/mlcc/info?part_no=C5750X7S2A226M280KB"
				(at 20.32 -15.24 0)
				(effects
					(font
						(size 1.27 1.27)
						(thickness 0.15)
					)
					(justify left bottom)
					(hide yes)
				)
			)
			(property "Description" "SMT Multilayer Ceramic Capacitor, 22 µF, 100 V, 2220 [5750 Metric], ± 20%, X7S, C"
				(at 0 0 0)
				(effects
					(font
						(size 1.27 1.27)
					)
					(hide yes)
				)
			)
			(property "MPN" "C5750X7S2A226M280KB"
				(at 20.32 -17.78 0)
				(effects
					(font
						(size 1.27 1.27)
						(thickness 0.15)
					)
					(justify left bottom)
					(hide yes)
				)
			)
			(property "Manufacturer" "TDK"
				(at 20.32 -20.32 0)
				(effects
					(font
						(size 1.27 1.27)
						(thickness 0.15)
					)
					(justify left bottom)
					(hide yes)
				)
			)
			(property "License" "Apache-2.0"
				(at 20.32 -22.86 0)
				(effects
					(font
						(size 1.27 1.27)
						(thickness 0.15)
					)
					(justify left bottom)
					(hide yes)
				)
			)
			(property "Author" "Antmicro"
				(at 20.32 -25.4 0)
				(effects
					(font
						(size 1.27 1.27)
						(thickness 0.15)
					)
					(justify left bottom)
					(hide yes)
				)
			)
			(property "Val" "22u"
				(at 20.32 -7.62 0)
				(effects
					(font
						(size 1.27 1.27)
						(thickness 0.15)
					)
					(justify left bottom)
				)
			)
			(property "Voltage" "100V"
				(at 20.32 -27.94 0)
				(effects
					(font
						(size 1.27 1.27)
					)
					(justify left bottom)
				)
			)
			(property "Dielectric" "X7S"
				(at 20.32 -30.48 0)
				(effects
					(font
						(size 1.27 1.27)
					)
					(justify left bottom)
					(hide yes)
				)
			)
			(property "Public" "False"
				(at 20.32 -33.02 0)
				(effects
					(font
						(size 1.27 1.27)
					)
					(justify left bottom)
					(hide yes)
				)
			)
			(property "ki_keywords" "SMT, CAPACITOR, PASSIVE"
				(at 0 0 0)
				(effects
					(font
						(size 1.27 1.27)
					)
					(hide yes)
				)
			)
			(symbol "C_22u_100V_2220_0_1"
				(polyline
					(pts
						(xy 2.032 -1.524) (xy 2.032 1.524)
					)
					(stroke
						(width 0.3048)
						(type default)
					)
					(fill
						(type none)
					)
				)
				(polyline
					(pts
						(xy 3.048 -1.524) (xy 3.048 1.524)
					)
					(stroke
						(width 0.3302)
						(type default)
					)
					(fill
						(type none)
					)
				)
			)
			(symbol "C_22u_100V_2220_1_1"
				(pin passive line
					(at 0 0 0)
					(length 2.032)
					(name "~"
						(effects
							(font
								(size 1.27 1.27)
							)
						)
					)
					(number "1"
						(effects
							(font
								(size 1.27 1.27)
							)
						)
					)
				)
				(pin passive line
					(at 5.08 0 180)
					(length 2.032)
					(name "~"
						(effects
							(font
								(size 1.27 1.27)
							)
						)
					)
					(number "2"
						(effects
							(font
								(size 1.27 1.27)
							)
						)
					)
				)
			)
		)
	(symbol "antmicroCapacitorsmisc:C_22u_25V_0805"
			(pin_numbers hide)
			(pin_names hide)
			(exclude_from_sim no)
			(in_bom yes)
			(on_board yes)
			(property "Reference" "C"
				(at 20.32 -5.08 0)
				(effects
					(font
						(size 1.27 1.27)
						(thickness 0.15)
					)
					(justify left bottom)
				)
			)
			(property "Value" "C_22u_25V_0805"
				(at 20.32 -10.16 0)
				(effects
					(font
						(size 1.27 1.27)
						(thickness 0.15)
					)
					(justify left bottom)
					(hide yes)
				)
			)
			(property "Footprint" "antmicro-footprints:C_0805_2012Metric"
				(at 20.32 -12.7 0)
				(effects
					(font
						(size 1.27 1.27)
						(thickness 0.15)
					)
					(justify left bottom)
					(hide yes)
				)
			)
			(property "Datasheet" "https://product.samsungsem.com/mlcc/CL21A226MAYNNN.do"
				(at 20.32 -15.24 0)
				(effects
					(font
						(size 1.27 1.27)
						(thickness 0.15)
					)
					(justify left bottom)
					(hide yes)
				)
			)
			(property "Description" "SMT Multilayer Ceramic Capacitor, 22uF, +/-20%, 25V, X5R, 0805 [2012 Metric]"
				(at 0 0 0)
				(effects
					(font
						(size 1.27 1.27)
					)
					(hide yes)
				)
			)
			(property "MPN" "CL21A226MAYNNNE"
				(at 20.32 -17.78 0)
				(effects
					(font
						(size 1.27 1.27)
						(thickness 0.15)
					)
					(justify left bottom)
					(hide yes)
				)
			)
			(property "Manufacturer" "Samsung Electro-Mechanics"
				(at 20.32 -20.32 0)
				(effects
					(font
						(size 1.27 1.27)
						(thickness 0.15)
					)
					(justify left bottom)
					(hide yes)
				)
			)
			(property "License" "Apache-2.0"
				(at 20.32 -22.86 0)
				(effects
					(font
						(size 1.27 1.27)
						(thickness 0.15)
					)
					(justify left bottom)
					(hide yes)
				)
			)
			(property "Author" "Antmicro"
				(at 20.32 -25.4 0)
				(effects
					(font
						(size 1.27 1.27)
						(thickness 0.15)
					)
					(justify left bottom)
					(hide yes)
				)
			)
			(property "Val" "22u"
				(at 20.32 -7.62 0)
				(effects
					(font
						(size 1.27 1.27)
						(thickness 0.15)
					)
					(justify left bottom)
				)
			)
			(property "Voltage" "25V"
				(at 20.32 -27.94 0)
				(effects
					(font
						(size 1.27 1.27)
					)
					(justify left bottom)
				)
			)
			(property "Dielectric" "X5R"
				(at 20.32 -30.48 0)
				(effects
					(font
						(size 1.27 1.27)
					)
					(justify left bottom)
					(hide yes)
				)
			)
			(property "Public" "False"
				(at 20.32 -33.02 0)
				(effects
					(font
						(size 1.27 1.27)
					)
					(justify left bottom)
					(hide yes)
				)
			)
			(property "ki_keywords" "0805, SMT, CAPACITOR, PASSIVE"
				(at 0 0 0)
				(effects
					(font
						(size 1.27 1.27)
					)
					(hide yes)
				)
			)
			(symbol "C_22u_25V_0805_0_1"
				(polyline
					(pts
						(xy 2.032 -1.524) (xy 2.032 1.524)
					)
					(stroke
						(width 0.3048)
						(type default)
					)
					(fill
						(type none)
					)
				)
				(polyline
					(pts
						(xy 3.048 -1.524) (xy 3.048 1.524)
					)
					(stroke
						(width 0.3302)
						(type default)
					)
					(fill
						(type none)
					)
				)
			)
			(symbol "C_22u_25V_0805_1_1"
				(pin passive line
					(at 0 0 0)
					(length 2.032)
					(name "~"
						(effects
							(font
								(size 1.27 1.27)
							)
						)
					)
					(number "1"
						(effects
							(font
								(size 1.27 1.27)
							)
						)
					)
				)
				(pin passive line
					(at 5.08 0 180)
					(length 2.032)
					(name "~"
						(effects
							(font
								(size 1.27 1.27)
							)
						)
					)
					(number "2"
						(effects
							(font
								(size 1.27 1.27)
							)
						)
					)
				)
			)
		)
	(symbol "antmicroCapacitorsmisc:C_47u_16V_1206"
			(pin_numbers hide)
			(pin_names hide)
			(exclude_from_sim no)
			(in_bom yes)
			(on_board yes)
			(property "Reference" "C"
				(at 20.32 -5.08 0)
				(effects
					(font
						(size 1.27 1.27)
						(thickness 0.15)
					)
					(justify left bottom)
				)
			)
			(property "Value" "C_47u_16V_1206"
				(at 20.32 -10.16 0)
				(effects
					(font
						(size 1.27 1.27)
						(thickness 0.15)
					)
					(justify left bottom)
					(hide yes)
				)
			)
			(property "Footprint" "antmicro-footprints:C_1206_3216Metric"
				(at 20.32 -12.7 0)
				(effects
					(font
						(size 1.27 1.27)
						(thickness 0.15)
					)
					(justify left bottom)
					(hide yes)
				)
			)
			(property "Datasheet" "https://product.tdk.com/en/search/capacitor/ceramic/mlcc/info?part_no=C3216X5R1C476M160AB"
				(at 20.32 -15.24 0)
				(effects
					(font
						(size 1.27 1.27)
						(thickness 0.15)
					)
					(justify left bottom)
					(hide yes)
				)
			)
			(property "Description" "SMD Multilayer Ceramic Capacitor, 47 µF, 16 V, 1206 [3216 Metric], ± 20%, X5R, C"
				(at 0 0 0)
				(effects
					(font
						(size 1.27 1.27)
					)
					(hide yes)
				)
			)
			(property "MPN" "C3216X5R1C476M160AB"
				(at 20.32 -17.78 0)
				(effects
					(font
						(size 1.27 1.27)
						(thickness 0.15)
					)
					(justify left bottom)
					(hide yes)
				)
			)
			(property "Manufacturer" "TDK"
				(at 20.32 -20.32 0)
				(effects
					(font
						(size 1.27 1.27)
						(thickness 0.15)
					)
					(justify left bottom)
					(hide yes)
				)
			)
			(property "License" "Apache-2.0"
				(at 20.32 -22.86 0)
				(effects
					(font
						(size 1.27 1.27)
						(thickness 0.15)
					)
					(justify left bottom)
					(hide yes)
				)
			)
			(property "Author" "Antmicro"
				(at 20.32 -25.4 0)
				(effects
					(font
						(size 1.27 1.27)
						(thickness 0.15)
					)
					(justify left bottom)
					(hide yes)
				)
			)
			(property "Val" "47u"
				(at 20.32 -7.62 0)
				(effects
					(font
						(size 1.27 1.27)
						(thickness 0.15)
					)
					(justify left bottom)
				)
			)
			(property "Voltage" "16V"
				(at 20.32 -27.94 0)
				(effects
					(font
						(size 1.27 1.27)
					)
					(justify left bottom)
				)
			)
			(property "Dielectric" "X5R"
				(at 20.32 -30.48 0)
				(effects
					(font
						(size 1.27 1.27)
					)
					(justify left bottom)
					(hide yes)
				)
			)
			(property "Public" "False"
				(at 20.32 -33.02 0)
				(effects
					(font
						(size 1.27 1.27)
					)
					(justify left bottom)
					(hide yes)
				)
			)
			(property "ki_keywords" "1206, SMT, CAPACITOR, PASSIVE"
				(at 0 0 0)
				(effects
					(font
						(size 1.27 1.27)
					)
					(hide yes)
				)
			)
			(symbol "C_47u_16V_1206_0_1"
				(polyline
					(pts
						(xy 2.032 -1.524) (xy 2.032 1.524)
					)
					(stroke
						(width 0.3048)
						(type default)
					)
					(fill
						(type none)
					)
				)
				(polyline
					(pts
						(xy 3.048 -1.524) (xy 3.048 1.524)
					)
					(stroke
						(width 0.3302)
						(type default)
					)
					(fill
						(type none)
					)
				)
			)
			(symbol "C_47u_16V_1206_1_1"
				(pin passive line
					(at 0 0 0)
					(length 2.032)
					(name "~"
						(effects
							(font
								(size 1.27 1.27)
							)
						)
					)
					(number "1"
						(effects
							(font
								(size 1.27 1.27)
							)
						)
					)
				)
				(pin passive line
					(at 5.08 0 180)
					(length 2.032)
					(name "~"
						(effects
							(font
								(size 1.27 1.27)
							)
						)
					)
					(number "2"
						(effects
							(font
								(size 1.27 1.27)
							)
						)
					)
				)
			)
		)
	(symbol "antmicroCapacitorspol:C_Pol_100u_25V_KEMET-T521-D-107"
			(pin_numbers hide)
			(pin_names hide)
			(exclude_from_sim no)
			(in_bom yes)
			(on_board yes)
			(property "Reference" "C"
				(at 13.97 0 0)
				(effects
					(font
						(size 1.27 1.27)
						(thickness 0.15)
					)
					(justify left bottom)
				)
			)
			(property "Value" "C_Pol_100u_25V_KEMET-T521-D-107"
				(at 13.97 -2.54 0)
				(effects
					(font
						(size 1.27 1.27)
						(thickness 0.15)
					)
					(justify left bottom)
					(hide yes)
				)
			)
			(property "Footprint" "antmicro-footprints:C_Pol_EIA-X"
				(at 13.97 -7.62 0)
				(effects
					(font
						(size 1.27 1.27)
						(thickness 0.15)
					)
					(justify left bottom)
					(hide yes)
				)
			)
			(property "Datasheet" "https://content.kemet.com/datasheets/KEM_T2076_T52X-530.pdf"
				(at 13.97 -10.16 0)
				(effects
					(font
						(size 1.27 1.27)
						(thickness 0.15)
					)
					(justify left bottom)
					(hide yes)
				)
			)
			(property "Description" "Surface Mount Tantalum Capacitor, 100 µF, 25 V, 2917 [7343 Metric], ± 20%, 0.04 ohm"
				(at 0 0 0)
				(effects
					(font
						(size 1.27 1.27)
					)
					(hide yes)
				)
			)
			(property "Val" "100u"
				(at 13.97 -5.08 0)
				(effects
					(font
						(size 1.27 1.27)
						(thickness 0.15)
					)
					(justify left bottom)
				)
			)
			(property "MPN" "T521D107M025ATE040"
				(at 13.97 -12.7 0)
				(effects
					(font
						(size 1.27 1.27)
						(thickness 0.15)
					)
					(justify left bottom)
					(hide yes)
				)
			)
			(property "Manufacturer" "KEMET"
				(at 13.97 -15.24 0)
				(effects
					(font
						(size 1.27 1.27)
						(thickness 0.15)
					)
					(justify left bottom)
					(hide yes)
				)
			)
			(property "License" "Apache-2.0"
				(at 13.97 -17.78 0)
				(effects
					(font
						(size 1.27 1.27)
						(thickness 0.15)
					)
					(justify left bottom)
					(hide yes)
				)
			)
			(property "Author" "Antmicro"
				(at 13.97 -20.32 0)
				(effects
					(font
						(size 1.27 1.27)
						(thickness 0.15)
					)
					(justify left bottom)
					(hide yes)
				)
			)
			(property "Voltage" "25V"
				(at 13.97 -22.86 0)
				(effects
					(font
						(size 1.27 1.27)
					)
					(justify left bottom)
					(hide yes)
				)
			)
			(property "Dielectric" "template_dielectric"
				(at 13.97 -25.4 0)
				(effects
					(font
						(size 1.27 1.27)
					)
					(justify left bottom)
					(hide yes)
				)
			)
			(property "ki_keywords" "SMT, CAPACITOR, PASSIVE, POLARIZED, POLYMER, TANTALUM"
				(at 0 0 0)
				(effects
					(font
						(size 1.27 1.27)
					)
					(hide yes)
				)
			)
			(symbol "C_Pol_100u_25V_KEMET-T521-D-107_0_1"
				(polyline
					(pts
						(xy 0.9652 1.27) (xy 0.9652 1.778)
					)
					(stroke
						(width 0)
						(type default)
					)
					(fill
						(type none)
					)
				)
				(polyline
					(pts
						(xy 1.2192 1.524) (xy 0.7112 1.524)
					)
					(stroke
						(width 0)
						(type default)
					)
					(fill
						(type none)
					)
				)
				(rectangle
					(start 1.905 -1.524)
					(end 2.286 1.524)
					(stroke
						(width 0)
						(type default)
					)
					(fill
						(type none)
					)
				)
				(rectangle
					(start 2.921 -1.524)
					(end 3.302 1.524)
					(stroke
						(width 0)
						(type default)
					)
					(fill
						(type outline)
					)
				)
			)
			(symbol "C_Pol_100u_25V_KEMET-T521-D-107_1_1"
				(pin passive line
					(at 0 0 0)
					(length 1.8542)
					(name "~"
						(effects
							(font
								(size 1.27 1.27)
							)
						)
					)
					(number "1"
						(effects
							(font
								(size 1.27 1.27)
							)
						)
					)
				)
				(pin passive line
					(at 5.08 0 180)
					(length 1.8542)
					(name "~"
						(effects
							(font
								(size 1.27 1.27)
							)
						)
					)
					(number "2"
						(effects
							(font
								(size 1.27 1.27)
							)
						)
					)
				)
			)
		)
	(symbol "antmicroDCDCConverters:MP2386GG"
			(exclude_from_sim no)
			(in_bom yes)
			(on_board yes)
			(property "Reference" "U"
				(at 0 17.78 0)
				(effects
					(font
						(size 1.27 1.27)
					)
				)
			)
			(property "Value" "MP2386GG-P_1"
				(at 0 15.24 0)
				(effects
					(font
						(size 1.27 1.27)
					)
				)
			)
			(property "Footprint" "antmicro-footprints:QFN-11_2x2mm_P0.5mm"
				(at 0 -30.48 0)
				(effects
					(font
						(size 1.27 1.27)
					)
					(hide yes)
				)
			)
			(property "Datasheet" "https://www.monolithicpower.com/en/documentview/productdocument/index/version/2/document_type/Datasheet/lang/en/sku/MP2386GG-Z/document_id/4066/"
				(at 0 -27.94 0)
				(effects
					(font
						(size 1.27 1.27)
					)
					(hide yes)
				)
			)
			(property "Description" "Buck Switching Regulator IC Positive Adjustable 0.6V 1 Output 8A,  4.5-24V input, 700kHz, 11-VFQFN "
				(at 0 0 0)
				(effects
					(font
						(size 1.27 1.27)
					)
					(hide yes)
				)
			)
			(property "Manufacturer" "Monolithic Power Systems (MPS)"
				(at 0 -33.02 0)
				(effects
					(font
						(size 1.27 1.27)
					)
					(hide yes)
				)
			)
			(property "MPN" "MP2386GG-P"
				(at 0 -35.56 0)
				(effects
					(font
						(size 1.27 1.27)
					)
					(hide yes)
				)
			)
			(symbol "MP2386GG_0_1"
				(rectangle
					(start -7.62 12.7)
					(end 5.08 -10.16)
					(stroke
						(width 0.1524)
						(type default)
					)
					(fill
						(type background)
					)
				)
			)
			(symbol "MP2386GG_1_1"
				(pin power_in line
					(at -10.16 0 0)
					(length 2.54)
					(name "VIN"
						(effects
							(font
								(size 1.27 1.27)
							)
						)
					)
					(number "1"
						(effects
							(font
								(size 1.27 1.27)
							)
						)
					)
				)
				(pin input line
					(at 7.62 -7.62 180)
					(length 2.54)
					(name "FB"
						(effects
							(font
								(size 1.27 1.27)
							)
						)
					)
					(number "10"
						(effects
							(font
								(size 1.27 1.27)
							)
						)
					)
				)
				(pin input line
					(at -10.16 10.16 0)
					(length 2.54)
					(name "EN"
						(effects
							(font
								(size 1.27 1.27)
							)
						)
					)
					(number "11"
						(effects
							(font
								(size 1.27 1.27)
							)
						)
					)
				)
				(pin power_in line
					(at -2.54 -12.7 90)
					(length 2.54)
					(name "PGND"
						(effects
							(font
								(size 1.27 1.27)
							)
						)
					)
					(number "2"
						(effects
							(font
								(size 1.27 1.27)
							)
						)
					)
				)
				(pin power_in line
					(at -2.54 -12.7 90)
					(length 2.54) hide
					(name "PGND"
						(effects
							(font
								(size 1.27 1.27)
							)
						)
					)
					(number "3"
						(effects
							(font
								(size 1.27 1.27)
							)
						)
					)
				)
				(pin power_in line
					(at -2.54 -12.7 90)
					(length 2.54) hide
					(name "PGND"
						(effects
							(font
								(size 1.27 1.27)
							)
						)
					)
					(number "4"
						(effects
							(font
								(size 1.27 1.27)
							)
						)
					)
				)
				(pin open_collector line
					(at 7.62 10.16 180)
					(length 2.54)
					(name "PG"
						(effects
							(font
								(size 1.27 1.27)
							)
						)
					)
					(number "5"
						(effects
							(font
								(size 1.27 1.27)
							)
						)
					)
				)
				(pin power_out line
					(at 7.62 0 180)
					(length 2.54)
					(name "SW"
						(effects
							(font
								(size 1.27 1.27)
							)
						)
					)
					(number "6"
						(effects
							(font
								(size 1.27 1.27)
							)
						)
					)
				)
				(pin input line
					(at 7.62 7.62 180)
					(length 2.54)
					(name "BST"
						(effects
							(font
								(size 1.27 1.27)
							)
						)
					)
					(number "7"
						(effects
							(font
								(size 1.27 1.27)
							)
						)
					)
				)
				(pin power_out line
					(at -10.16 -7.62 0)
					(length 2.54)
					(name "VCC"
						(effects
							(font
								(size 1.27 1.27)
							)
						)
					)
					(number "8"
						(effects
							(font
								(size 1.27 1.27)
							)
						)
					)
				)
				(pin power_in line
					(at 0 -12.7 90)
					(length 2.54)
					(name "AGND"
						(effects
							(font
								(size 1.27 1.27)
							)
						)
					)
					(number "9"
						(effects
							(font
								(size 1.27 1.27)
							)
						)
					)
				)
			)
		)
	(symbol "antmicroDCDCConverters:SIC431AED-T1-GE3"
			(exclude_from_sim no)
			(in_bom yes)
			(on_board yes)
			(property "Reference" "U"
				(at 33.02 -2.54 0)
				(effects
					(font
						(size 1.27 1.27)
						(thickness 0.15)
					)
					(justify left bottom)
				)
			)
			(property "Value" "SIC431AED-T1-GE3"
				(at 33.02 -7.62 0)
				(effects
					(font
						(size 1.27 1.27)
						(thickness 0.15)
					)
					(justify left bottom)
					(hide yes)
				)
			)
			(property "Footprint" "antmicro-footprints:MLP44-24L_4x4x0.75mm"
				(at 33.02 -10.16 0)
				(effects
					(font
						(size 1.27 1.27)
						(thickness 0.15)
					)
					(justify left bottom)
					(hide yes)
				)
			)
			(property "Datasheet" "https://www.vishay.com/docs/74589/sic431.pdf"
				(at 33.02 -12.7 0)
				(effects
					(font
						(size 1.27 1.27)
						(thickness 0.15)
					)
					(justify left bottom)
					(hide yes)
				)
			)
			(property "Description" "DC/DC Synchronous Regulator, Adjustable, 3V to 24VIn, 0.6V to 22V/24AOut, 1MHz, MLP44-24L"
				(at 0 0 0)
				(effects
					(font
						(size 1.27 1.27)
					)
					(hide yes)
				)
			)
			(property "Manufacturer" "Vishay"
				(at 33.02 -15.24 0)
				(effects
					(font
						(size 1.27 1.27)
						(thickness 0.15)
					)
					(justify left bottom)
					(hide yes)
				)
			)
			(property "MPN" "SIC431AED-T1-GE3 "
				(at 33.02 -5.08 0)
				(effects
					(font
						(size 1.27 1.27)
						(thickness 0.15)
					)
					(justify left bottom)
				)
			)
			(property "Author" "Antmicro"
				(at 33.02 -17.78 0)
				(effects
					(font
						(size 1.27 1.27)
						(thickness 0.15)
					)
					(justify left bottom)
					(hide yes)
				)
			)
			(property "License" "Apache-2.0"
				(at 33.02 -20.32 0)
				(effects
					(font
						(size 1.27 1.27)
						(thickness 0.15)
					)
					(justify left bottom)
					(hide yes)
				)
			)
			(property "ki_keywords" "SMT, PMIC, IC, DC-DC, CONVERTER, SWITCHING, VOLTAGE"
				(at 0 0 0)
				(effects
					(font
						(size 1.27 1.27)
					)
					(hide yes)
				)
			)
			(symbol "SIC431AED-T1-GE3_1_1"
				(rectangle
					(start 2.54 2.54)
					(end 19.05 -22.86)
					(stroke
						(width 0.254)
						(type default)
					)
					(fill
						(type background)
					)
				)
				(pin power_in line
					(at 0 0 0)
					(length 2.54)
					(name "V_{IN}"
						(effects
							(font
								(size 1.27 1.27)
							)
						)
					)
					(number "1"
						(effects
							(font
								(size 1.27 1.27)
							)
						)
					)
				)
				(pin passive line
					(at 21.59 -7.62 180)
					(length 2.54)
					(name "GL"
						(effects
							(font
								(size 1.27 1.27)
							)
						)
					)
					(number "10"
						(effects
							(font
								(size 1.27 1.27)
							)
						)
					)
				)
				(pin passive line
					(at 21.59 -7.62 180)
					(length 2.54) hide
					(name "GL"
						(effects
							(font
								(size 1.27 1.27)
							)
						)
					)
					(number "11"
						(effects
							(font
								(size 1.27 1.27)
							)
						)
					)
				)
				(pin passive line
					(at 0 -17.78 0)
					(length 2.54)
					(name "V_{DRV}"
						(effects
							(font
								(size 1.27 1.27)
							)
						)
					)
					(number "12"
						(effects
							(font
								(size 1.27 1.27)
							)
						)
					)
				)
				(pin power_in line
					(at 21.59 -20.32 180)
					(length 2.54)
					(name "P_{GND}"
						(effects
							(font
								(size 1.27 1.27)
							)
						)
					)
					(number "13"
						(effects
							(font
								(size 1.27 1.27)
							)
						)
					)
				)
				(pin output line
					(at 0 -20.32 0)
					(length 2.54)
					(name "P_{GOOD}"
						(effects
							(font
								(size 1.27 1.27)
							)
						)
					)
					(number "14"
						(effects
							(font
								(size 1.27 1.27)
							)
						)
					)
				)
				(pin passive line
					(at 0 -15.24 0)
					(length 2.54)
					(name "V_{DD}"
						(effects
							(font
								(size 1.27 1.27)
							)
						)
					)
					(number "15"
						(effects
							(font
								(size 1.27 1.27)
							)
						)
					)
				)
				(pin power_in line
					(at 21.59 -17.78 180)
					(length 2.54)
					(name "A_{GND}"
						(effects
							(font
								(size 1.27 1.27)
							)
						)
					)
					(number "16"
						(effects
							(font
								(size 1.27 1.27)
							)
						)
					)
				)
				(pin passive line
					(at 21.59 -12.7 180)
					(length 2.54)
					(name "FB"
						(effects
							(font
								(size 1.27 1.27)
							)
						)
					)
					(number "17"
						(effects
							(font
								(size 1.27 1.27)
							)
						)
					)
				)
				(pin passive line
					(at 21.59 -10.16 180)
					(length 2.54)
					(name "V_{OUT}"
						(effects
							(font
								(size 1.27 1.27)
							)
						)
					)
					(number "18"
						(effects
							(font
								(size 1.27 1.27)
							)
						)
					)
				)
				(pin input line
					(at 0 -7.62 0)
					(length 2.54)
					(name "EN"
						(effects
							(font
								(size 1.27 1.27)
							)
						)
					)
					(number "19"
						(effects
							(font
								(size 1.27 1.27)
							)
						)
					)
				)
				(pin passive line
					(at 0 0 0)
					(length 2.54) hide
					(name "V_{IN}"
						(effects
							(font
								(size 1.27 1.27)
							)
						)
					)
					(number "2"
						(effects
							(font
								(size 1.27 1.27)
							)
						)
					)
				)
				(pin input line
					(at 0 -12.7 0)
					(length 2.54)
					(name "MODE2"
						(effects
							(font
								(size 1.27 1.27)
							)
						)
					)
					(number "20"
						(effects
							(font
								(size 1.27 1.27)
							)
						)
					)
				)
				(pin input line
					(at 0 -10.16 0)
					(length 2.54)
					(name "MODE1"
						(effects
							(font
								(size 1.27 1.27)
							)
						)
					)
					(number "21"
						(effects
							(font
								(size 1.27 1.27)
							)
						)
					)
				)
				(pin passive line
					(at 0 0 0)
					(length 2.54) hide
					(name "V_{IN}"
						(effects
							(font
								(size 1.27 1.27)
							)
						)
					)
					(number "22"
						(effects
							(font
								(size 1.27 1.27)
							)
						)
					)
				)
				(pin passive line
					(at 21.59 0 180)
					(length 2.54)
					(name "BOOT"
						(effects
							(font
								(size 1.27 1.27)
							)
						)
					)
					(number "23"
						(effects
							(font
								(size 1.27 1.27)
							)
						)
					)
				)
				(pin passive line
					(at 21.59 -2.54 180)
					(length 2.54)
					(name "PHASE"
						(effects
							(font
								(size 1.27 1.27)
							)
						)
					)
					(number "24"
						(effects
							(font
								(size 1.27 1.27)
							)
						)
					)
				)
				(pin passive line
					(at 21.59 -17.78 180)
					(length 2.54) hide
					(name "A_{GND}"
						(effects
							(font
								(size 1.27 1.27)
							)
						)
					)
					(number "25"
						(effects
							(font
								(size 1.27 1.27)
							)
						)
					)
				)
				(pin passive line
					(at 0 0 0)
					(length 2.54) hide
					(name "V_{IN}"
						(effects
							(font
								(size 1.27 1.27)
							)
						)
					)
					(number "26"
						(effects
							(font
								(size 1.27 1.27)
							)
						)
					)
				)
				(pin passive line
					(at 21.59 -20.32 180)
					(length 2.54) hide
					(name "P_{GND}"
						(effects
							(font
								(size 1.27 1.27)
							)
						)
					)
					(number "27"
						(effects
							(font
								(size 1.27 1.27)
							)
						)
					)
				)
				(pin passive line
					(at 21.59 -7.62 180)
					(length 2.54) hide
					(name "GL"
						(effects
							(font
								(size 1.27 1.27)
							)
						)
					)
					(number "28"
						(effects
							(font
								(size 1.27 1.27)
							)
						)
					)
				)
				(pin passive line
					(at 21.59 -20.32 180)
					(length 2.54) hide
					(name "P_{GND}"
						(effects
							(font
								(size 1.27 1.27)
							)
						)
					)
					(number "3"
						(effects
							(font
								(size 1.27 1.27)
							)
						)
					)
				)
				(pin passive line
					(at 21.59 -20.32 180)
					(length 2.54) hide
					(name "P_{GND}"
						(effects
							(font
								(size 1.27 1.27)
							)
						)
					)
					(number "4"
						(effects
							(font
								(size 1.27 1.27)
							)
						)
					)
				)
				(pin passive line
					(at 21.59 -5.08 180)
					(length 2.54)
					(name "SW"
						(effects
							(font
								(size 1.27 1.27)
							)
						)
					)
					(number "5"
						(effects
							(font
								(size 1.27 1.27)
							)
						)
					)
				)
				(pin passive line
					(at 21.59 -5.08 180)
					(length 2.54) hide
					(name "SW"
						(effects
							(font
								(size 1.27 1.27)
							)
						)
					)
					(number "6"
						(effects
							(font
								(size 1.27 1.27)
							)
						)
					)
				)
				(pin passive line
					(at 21.59 -5.08 180)
					(length 2.54) hide
					(name "SW"
						(effects
							(font
								(size 1.27 1.27)
							)
						)
					)
					(number "7"
						(effects
							(font
								(size 1.27 1.27)
							)
						)
					)
				)
				(pin passive line
					(at 21.59 -5.08 180)
					(length 2.54) hide
					(name "SW"
						(effects
							(font
								(size 1.27 1.27)
							)
						)
					)
					(number "8"
						(effects
							(font
								(size 1.27 1.27)
							)
						)
					)
				)
				(pin passive line
					(at 21.59 -5.08 180)
					(length 2.54) hide
					(name "SW"
						(effects
							(font
								(size 1.27 1.27)
							)
						)
					)
					(number "9"
						(effects
							(font
								(size 1.27 1.27)
							)
						)
					)
				)
			)
		)
	(symbol "antmicroDCDCConverters:ULS-12_5-D48N-C"
			(exclude_from_sim no)
			(in_bom yes)
			(on_board yes)
			(property "Reference" "U"
				(at 33.02 -2.54 0)
				(effects
					(font
						(size 1.27 1.27)
						(thickness 0.15)
					)
					(justify left bottom)
				)
			)
			(property "Value" "ULS-12_5-D48N-C"
				(at 33.02 -7.62 0)
				(effects
					(font
						(size 1.27 1.27)
						(thickness 0.15)
					)
					(justify left bottom)
					(hide yes)
				)
			)
			(property "Footprint" "antmicro-footprints:Conv_Murata_ULS-60W"
				(at 33.02 -10.16 0)
				(effects
					(font
						(size 1.27 1.27)
						(thickness 0.15)
					)
					(justify left bottom)
					(hide yes)
				)
			)
			(property "Datasheet" "https://www.murata.com/products/productdata/8807040286750/uls.pdf?1649388617000"
				(at 33.02 -12.7 0)
				(effects
					(font
						(size 1.27 1.27)
						(thickness 0.15)
					)
					(justify left bottom)
					(hide yes)
				)
			)
			(property "Description" "Isolated Through Hole DC/DC Converter, ITE, 2:1, 60 W, 1 Output, 12 V, 5 A"
				(at 0 0 0)
				(effects
					(font
						(size 1.27 1.27)
					)
					(hide yes)
				)
			)
			(property "MPN" "ULS-12/5-D48N-C"
				(at 33.02 -5.08 0)
				(effects
					(font
						(size 1.27 1.27)
						(thickness 0.15)
					)
					(justify left bottom)
				)
			)
			(property "Manufacturer" "Murata"
				(at 33.02 -15.24 0)
				(effects
					(font
						(size 1.27 1.27)
						(thickness 0.15)
					)
					(justify left bottom)
					(hide yes)
				)
			)
			(property "Author" "Antmicro"
				(at 33.02 -17.78 0)
				(effects
					(font
						(size 1.27 1.27)
						(thickness 0.15)
					)
					(justify left bottom)
					(hide yes)
				)
			)
			(property "License" "Apache-2.0"
				(at 33.02 -20.32 0)
				(effects
					(font
						(size 1.27 1.27)
						(thickness 0.15)
					)
					(justify left bottom)
					(hide yes)
				)
			)
			(property "Alternatives 50W" " VCB4812SBO-50WR3, V36SE12004NRFA, PKU5513ESI, KHHD004A2B41Z"
				(at -10.16 -22.86 0)
				(show_name)
				(effects
					(font
						(size 1.27 1.27)
					)
					(justify left)
					(hide yes)
				)
			)
			(property "Alternatives 75W" " VCB4812SBO-75WR3"
				(at -10.16 -25.4 0)
				(show_name)
				(effects
					(font
						(size 1.27 1.27)
					)
					(justify left)
					(hide yes)
				)
			)
			(property "Alternatives 100W" "PKU4913DPIHS, VCB4812SBO-100WFR3"
				(at -10.16 -27.94 0)
				(show_name)
				(effects
					(font
						(size 1.27 1.27)
					)
					(justify left)
					(hide yes)
				)
			)
			(property "Alternatives 120W" "PQC50-48-S12-O"
				(at -10.16 -30.48 0)
				(show_name)
				(effects
					(font
						(size 1.27 1.27)
					)
					(justify left)
					(hide yes)
				)
			)
			(property "ki_keywords" "THT, PMIC, IC, DC-DC, CONVERTER, MODULE"
				(at 0 0 0)
				(effects
					(font
						(size 1.27 1.27)
					)
					(hide yes)
				)
			)
			(symbol "ULS-12_5-D48N-C_1_1"
				(rectangle
					(start 2.413 2.54)
					(end 17.653 -17.78)
					(stroke
						(width 0.254)
						(type default)
					)
					(fill
						(type background)
					)
				)
				(pin power_in line
					(at 0 0 0)
					(length 2.54)
					(name "VIN+"
						(effects
							(font
								(size 1.27 1.27)
							)
						)
					)
					(number "1"
						(effects
							(font
								(size 1.27 1.27)
							)
						)
					)
				)
				(pin input line
					(at 0 -7.62 0)
					(length 2.54)
					(name "CTRL"
						(effects
							(font
								(size 1.27 1.27)
							)
						)
					)
					(number "2"
						(effects
							(font
								(size 1.27 1.27)
							)
						)
					)
				)
				(pin power_in line
					(at 0 -15.24 0)
					(length 2.54)
					(name "VIN-"
						(effects
							(font
								(size 1.27 1.27)
							)
						)
					)
					(number "3"
						(effects
							(font
								(size 1.27 1.27)
							)
						)
					)
				)
				(pin power_out line
					(at 20.32 -15.24 180)
					(length 2.54)
					(name "VOUT-"
						(effects
							(font
								(size 1.27 1.27)
							)
						)
					)
					(number "4"
						(effects
							(font
								(size 1.27 1.27)
							)
						)
					)
				)
				(pin passive line
					(at 20.32 -12.7 180)
					(length 2.54)
					(name "SENSE-"
						(effects
							(font
								(size 1.27 1.27)
							)
						)
					)
					(number "5"
						(effects
							(font
								(size 1.27 1.27)
							)
						)
					)
				)
				(pin input line
					(at 20.32 -7.62 180)
					(length 2.54)
					(name "TRIM"
						(effects
							(font
								(size 1.27 1.27)
							)
						)
					)
					(number "6"
						(effects
							(font
								(size 1.27 1.27)
							)
						)
					)
				)
				(pin passive line
					(at 20.32 -2.54 180)
					(length 2.54)
					(name "SENSE+"
						(effects
							(font
								(size 1.27 1.27)
							)
						)
					)
					(number "7"
						(effects
							(font
								(size 1.27 1.27)
							)
						)
					)
				)
				(pin power_out line
					(at 20.32 0 180)
					(length 2.54)
					(name "VOUT+"
						(effects
							(font
								(size 1.27 1.27)
							)
						)
					)
					(number "8"
						(effects
							(font
								(size 1.27 1.27)
							)
						)
					)
				)
			)
		)
	(symbol "antmicroDiodesRectifiersSingle:CD-MMBL110S"
			(pin_names hide)
			(exclude_from_sim no)
			(in_bom yes)
			(on_board yes)
			(property "Reference" "D"
				(at 26.67 -2.54 0)
				(effects
					(font
						(size 1.27 1.27)
						(thickness 0.15)
					)
					(justify left bottom)
				)
			)
			(property "Value" "CD-MMBL110S"
				(at 26.67 -12.7 0)
				(effects
					(font
						(size 1.27 1.27)
						(thickness 0.15)
					)
					(justify left bottom)
					(hide yes)
				)
			)
			(property "Footprint" "antmicro-footprints:DFN3538"
				(at 26.67 -7.62 0)
				(effects
					(font
						(size 1.27 1.27)
						(thickness 0.15)
					)
					(justify left bottom)
					(hide yes)
				)
			)
			(property "Datasheet" "https://www.bourns.com/docs/product-datasheets/CD-MMBL110S.pdf"
				(at 26.67 -10.16 0)
				(effects
					(font
						(size 1.27 1.27)
						(thickness 0.15)
					)
					(justify left bottom)
					(hide yes)
				)
			)
			(property "Description" "Bridge Rectifier, 1000 V, 1 A, Single Phase , 4 Pins, 900mV"
				(at 0 0 0)
				(effects
					(font
						(size 1.27 1.27)
					)
					(hide yes)
				)
			)
			(property "MPN" "CD-MMBL110S"
				(at 26.67 -5.08 0)
				(effects
					(font
						(size 1.27 1.27)
						(thickness 0.15)
					)
					(justify left bottom)
				)
			)
			(property "Manufacturer" "Bourns"
				(at 26.67 -15.24 0)
				(effects
					(font
						(size 1.27 1.27)
						(thickness 0.15)
					)
					(justify left bottom)
					(hide yes)
				)
			)
			(property "Author" "Antmicro"
				(at 26.67 -17.78 0)
				(effects
					(font
						(size 1.27 1.27)
						(thickness 0.15)
					)
					(justify left bottom)
					(hide yes)
				)
			)
			(property "License" "Apache-2.0"
				(at 26.67 -20.32 0)
				(effects
					(font
						(size 1.27 1.27)
						(thickness 0.15)
					)
					(justify left bottom)
					(hide yes)
				)
			)
			(property "ki_keywords" "SMT, RECTIFIER, SEMICONDUCTOR, DIODE, BRIDGE"
				(at 0 0 0)
				(effects
					(font
						(size 1.27 1.27)
					)
					(hide yes)
				)
			)
			(symbol "CD-MMBL110S_1_1"
				(polyline
					(pts
						(xy 2.54 -5.08) (xy 3.81 -5.08)
					)
					(stroke
						(width 0.254)
						(type default)
					)
					(fill
						(type none)
					)
				)
				(polyline
					(pts
						(xy 3.81 -10.16) (xy 2.54 -10.16)
					)
					(stroke
						(width 0.254)
						(type default)
					)
					(fill
						(type none)
					)
				)
				(polyline
					(pts
						(xy 3.81 -3.81) (xy 3.81 -7.62)
					)
					(stroke
						(width 0.254)
						(type default)
					)
					(fill
						(type none)
					)
				)
				(polyline
					(pts
						(xy 3.81 -2.54) (xy 3.81 -3.81)
					)
					(stroke
						(width 0.254)
						(type default)
					)
					(fill
						(type none)
					)
				)
				(polyline
					(pts
						(xy 3.81 0) (xy 2.54 0)
					)
					(stroke
						(width 0.254)
						(type default)
					)
					(fill
						(type none)
					)
				)
				(polyline
					(pts
						(xy 5.08 -7.62) (xy 3.81 -7.62)
					)
					(stroke
						(width 0.254)
						(type default)
					)
					(fill
						(type none)
					)
				)
				(polyline
					(pts
						(xy 5.08 -2.54) (xy 3.81 -2.54)
					)
					(stroke
						(width 0.254)
						(type default)
					)
					(fill
						(type none)
					)
				)
				(polyline
					(pts
						(xy 7.62 -6.35) (xy 7.62 -8.89)
					)
					(stroke
						(width 0.254)
						(type default)
					)
					(fill
						(type none)
					)
				)
				(polyline
					(pts
						(xy 7.62 -1.27) (xy 7.62 -3.81)
					)
					(stroke
						(width 0.254)
						(type default)
					)
					(fill
						(type none)
					)
				)
				(polyline
					(pts
						(xy 8.89 -7.62) (xy 7.62 -7.62)
					)
					(stroke
						(width 0.254)
						(type default)
					)
					(fill
						(type none)
					)
				)
				(polyline
					(pts
						(xy 8.89 -2.54) (xy 7.62 -2.54)
					)
					(stroke
						(width 0.254)
						(type default)
					)
					(fill
						(type none)
					)
				)
				(polyline
					(pts
						(xy 10.16 -7.62) (xy 6.35 -7.62)
					)
					(stroke
						(width 0.254)
						(type default)
					)
					(fill
						(type none)
					)
				)
				(polyline
					(pts
						(xy 10.16 -2.54) (xy 6.35 -2.54)
					)
					(stroke
						(width 0.254)
						(type default)
					)
					(fill
						(type none)
					)
				)
				(polyline
					(pts
						(xy 12.7 -7.62) (xy 13.97 -7.62)
					)
					(stroke
						(width 0.254)
						(type default)
					)
					(fill
						(type none)
					)
				)
				(polyline
					(pts
						(xy 12.7 -6.35) (xy 12.7 -8.89)
					)
					(stroke
						(width 0.254)
						(type default)
					)
					(fill
						(type none)
					)
				)
				(polyline
					(pts
						(xy 12.7 -2.54) (xy 13.97 -2.54)
					)
					(stroke
						(width 0.254)
						(type default)
					)
					(fill
						(type none)
					)
				)
				(polyline
					(pts
						(xy 12.7 -1.27) (xy 12.7 -3.81)
					)
					(stroke
						(width 0.254)
						(type default)
					)
					(fill
						(type none)
					)
				)
				(polyline
					(pts
						(xy 13.97 -5.08) (xy 15.24 -5.08)
					)
					(stroke
						(width 0.254)
						(type default)
					)
					(fill
						(type none)
					)
				)
				(polyline
					(pts
						(xy 13.97 -3.81) (xy 13.97 -7.62)
					)
					(stroke
						(width 0.254)
						(type default)
					)
					(fill
						(type none)
					)
				)
				(polyline
					(pts
						(xy 13.97 -2.54) (xy 13.97 -3.81)
					)
					(stroke
						(width 0.254)
						(type default)
					)
					(fill
						(type none)
					)
				)
				(polyline
					(pts
						(xy 8.89 -7.62) (xy 8.89 -10.16) (xy 3.81 -10.16)
					)
					(stroke
						(width 0.254)
						(type default)
					)
					(fill
						(type none)
					)
				)
				(polyline
					(pts
						(xy 8.89 -2.54) (xy 8.89 0) (xy 3.81 0)
					)
					(stroke
						(width 0.254)
						(type default)
					)
					(fill
						(type none)
					)
				)
				(polyline
					(pts
						(xy 5.08 -6.35) (xy 5.08 -8.89) (xy 7.62 -7.62) (xy 5.08 -6.35)
					)
					(stroke
						(width 0.254)
						(type default)
					)
					(fill
						(type outline)
					)
				)
				(polyline
					(pts
						(xy 5.08 -1.27) (xy 5.08 -3.81) (xy 7.62 -2.54) (xy 5.08 -1.27)
					)
					(stroke
						(width 0.254)
						(type default)
					)
					(fill
						(type outline)
					)
				)
				(polyline
					(pts
						(xy 10.16 -6.35) (xy 10.16 -8.89) (xy 12.7 -7.62) (xy 10.16 -6.35)
					)
					(stroke
						(width 0.254)
						(type default)
					)
					(fill
						(type outline)
					)
				)
				(polyline
					(pts
						(xy 10.16 -1.27) (xy 10.16 -3.81) (xy 12.7 -2.54) (xy 10.16 -1.27)
					)
					(stroke
						(width 0.254)
						(type default)
					)
					(fill
						(type outline)
					)
				)
				(rectangle
					(start 2.54 1.27)
					(end 15.24 -11.43)
					(stroke
						(width 0.254)
						(type default)
					)
					(fill
						(type background)
					)
				)
				(pin passive line
					(at 0 -5.08 0)
					(length 2.54)
					(name "1"
						(effects
							(font
								(size 1.27 1.27)
							)
						)
					)
					(number "1"
						(effects
							(font
								(size 1.27 1.27)
							)
						)
					)
				)
				(pin passive line
					(at 17.78 -5.08 180)
					(length 2.54)
					(name "2"
						(effects
							(font
								(size 1.27 1.27)
							)
						)
					)
					(number "2"
						(effects
							(font
								(size 1.27 1.27)
							)
						)
					)
				)
				(pin passive line
					(at 0 0 0)
					(length 2.54)
					(name "3"
						(effects
							(font
								(size 1.27 1.27)
							)
						)
					)
					(number "3"
						(effects
							(font
								(size 1.27 1.27)
							)
						)
					)
				)
				(pin passive line
					(at 0 -10.16 0)
					(length 2.54)
					(name "4"
						(effects
							(font
								(size 1.27 1.27)
							)
						)
					)
					(number "4"
						(effects
							(font
								(size 1.27 1.27)
							)
						)
					)
				)
			)
		)
	(symbol "antmicroDiodesRectifiersSingle:RB521S30T1G"
			(pin_numbers hide)
			(pin_names hide)
			(exclude_from_sim no)
			(in_bom yes)
			(on_board yes)
			(property "Reference" "D"
				(at 22.86 -5.08 0)
				(effects
					(font
						(size 1.27 1.27)
						(thickness 0.15)
					)
					(justify left bottom)
				)
			)
			(property "Value" "RB521S30T1G"
				(at 22.86 -15.24 0)
				(effects
					(font
						(size 1.27 1.27)
						(thickness 0.15)
					)
					(justify left bottom)
					(hide yes)
				)
			)
			(property "Footprint" "antmicro-footprints:SOD-523"
				(at 22.86 -10.16 0)
				(effects
					(font
						(size 1.27 1.27)
						(thickness 0.15)
					)
					(justify left bottom)
					(hide yes)
				)
			)
			(property "Datasheet" "https://www.onsemi.com/pdf/datasheet/rb521s30t1-d.pdf"
				(at 22.86 -12.7 0)
				(effects
					(font
						(size 1.27 1.27)
						(thickness 0.15)
					)
					(justify left bottom)
					(hide yes)
				)
			)
			(property "Description" "Small Signal Schottky Diode, Single, 30 V, 200 mA, 500 mV, 1 A, 125 °C"
				(at 0 0 0)
				(effects
					(font
						(size 1.27 1.27)
					)
					(hide yes)
				)
			)
			(property "MPN" "RB521S30T1G"
				(at 22.86 -7.62 0)
				(effects
					(font
						(size 1.27 1.27)
						(thickness 0.15)
					)
					(justify left bottom)
				)
			)
			(property "Manufacturer" "ON Semiconductor"
				(at 22.86 -17.78 0)
				(effects
					(font
						(size 1.27 1.27)
						(thickness 0.15)
					)
					(justify left bottom)
					(hide yes)
				)
			)
			(property "Author" "Antmicro"
				(at 22.86 -20.32 0)
				(effects
					(font
						(size 1.27 1.27)
						(thickness 0.15)
					)
					(justify left bottom)
					(hide yes)
				)
			)
			(property "License" "Apache-2.0"
				(at 22.86 -22.86 0)
				(effects
					(font
						(size 1.27 1.27)
						(thickness 0.15)
					)
					(justify left bottom)
					(hide yes)
				)
			)
			(property "ki_keywords" "SMT, SEMICONDUCTOR, DIODE, SCHOTTKY"
				(at 0 0 0)
				(effects
					(font
						(size 1.27 1.27)
					)
					(hide yes)
				)
			)
			(symbol "RB521S30T1G_0_1"
				(polyline
					(pts
						(xy 1.905 0) (xy 0.635 0)
					)
					(stroke
						(width 0)
						(type default)
					)
					(fill
						(type none)
					)
				)
				(polyline
					(pts
						(xy 4.445 0) (xy 3.175 0)
					)
					(stroke
						(width 0)
						(type default)
					)
					(fill
						(type none)
					)
				)
			)
			(symbol "RB521S30T1G_1_1"
				(polyline
					(pts
						(xy 1.778 1.016) (xy 1.778 -1.016)
					)
					(stroke
						(width 0.254)
						(type default)
					)
					(fill
						(type none)
					)
				)
				(polyline
					(pts
						(xy 1.778 -1.016) (xy 2.159 -1.016) (xy 2.159 -0.762)
					)
					(stroke
						(width 0.254)
						(type default)
					)
					(fill
						(type none)
					)
				)
				(polyline
					(pts
						(xy 1.778 1.016) (xy 1.397 1.016) (xy 1.397 0.762)
					)
					(stroke
						(width 0.254)
						(type default)
					)
					(fill
						(type none)
					)
				)
				(polyline
					(pts
						(xy 3.302 1.016) (xy 3.302 -1.016) (xy 1.778 0) (xy 3.302 1.016)
					)
					(stroke
						(width 0.254)
						(type default)
					)
					(fill
						(type outline)
					)
				)
				(pin passive line
					(at 0 0 0)
					(length 0.635)
					(name "C"
						(effects
							(font
								(size 1.27 1.27)
							)
						)
					)
					(number "1"
						(effects
							(font
								(size 1.27 1.27)
							)
						)
					)
				)
				(pin passive line
					(at 5.08 0 180)
					(length 0.635)
					(name "A"
						(effects
							(font
								(size 1.27 1.27)
							)
						)
					)
					(number "2"
						(effects
							(font
								(size 1.27 1.27)
							)
						)
					)
				)
			)
		)
	(symbol "antmicroFCCConnectors:Conn_FFC_WE_68715014522"
			(exclude_from_sim no)
			(in_bom yes)
			(on_board yes)
			(property "Reference" "J"
				(at 19.05 -5.08 0)
				(effects
					(font
						(size 1.27 1.27)
						(thickness 0.15)
					)
					(justify left bottom)
				)
			)
			(property "Value" "Conn_FFC_WE_68715014522"
				(at 19.05 -7.62 0)
				(effects
					(font
						(size 1.27 1.27)
						(thickness 0.15)
					)
					(justify left bottom)
					(hide yes)
				)
			)
			(property "Footprint" "antmicro-footprints:Conn_FFC_WE_68715014x22"
				(at 19.05 -10.16 0)
				(effects
					(font
						(size 1.27 1.27)
						(thickness 0.15)
					)
					(justify left bottom)
					(hide yes)
				)
			)
			(property "Datasheet" "https://www.we-online.com/components/products/datasheet/68715014522.pdf"
				(at 19.05 -12.7 0)
				(effects
					(font
						(size 1.27 1.27)
						(thickness 0.15)
					)
					(justify left bottom)
					(hide yes)
				)
			)
			(property "Description" "FFC connector"
				(at 0 0 0)
				(effects
					(font
						(size 1.27 1.27)
					)
					(hide yes)
				)
			)
			(property "MPN" "68715014522"
				(at 19.05 -15.24 0)
				(effects
					(font
						(size 1.27 1.27)
						(thickness 0.15)
					)
					(justify left bottom)
				)
			)
			(property "Manufacturer" "Würth Elektronik"
				(at 19.05 -17.78 0)
				(effects
					(font
						(size 1.27 1.27)
						(thickness 0.15)
					)
					(justify left bottom)
					(hide yes)
				)
			)
			(property "Author" "Antmicro"
				(at 19.05 -20.32 0)
				(effects
					(font
						(size 1.27 1.27)
						(thickness 0.15)
					)
					(justify left bottom)
					(hide yes)
				)
			)
			(property "License" "Apache-2.0"
				(at 19.05 -22.86 0)
				(effects
					(font
						(size 1.27 1.27)
						(thickness 0.15)
					)
					(justify left bottom)
					(hide yes)
				)
			)
			(property "ki_keywords" "CONNECTOR"
				(at 0 0 0)
				(effects
					(font
						(size 1.27 1.27)
					)
					(hide yes)
				)
			)
			(symbol "Conn_FFC_WE_68715014522_1_1"
				(rectangle
					(start 3.81 -124.333)
					(end 5.08 -124.587)
					(stroke
						(width 0.254)
						(type default)
					)
					(fill
						(type background)
					)
				)
				(rectangle
					(start 3.81 -121.793)
					(end 5.08 -122.047)
					(stroke
						(width 0.254)
						(type default)
					)
					(fill
						(type background)
					)
				)
				(rectangle
					(start 3.81 -119.253)
					(end 5.08 -119.507)
					(stroke
						(width 0.254)
						(type default)
					)
					(fill
						(type background)
					)
				)
				(rectangle
					(start 3.81 -116.713)
					(end 5.08 -116.967)
					(stroke
						(width 0.254)
						(type default)
					)
					(fill
						(type background)
					)
				)
				(rectangle
					(start 3.81 -114.173)
					(end 5.08 -114.427)
					(stroke
						(width 0.254)
						(type default)
					)
					(fill
						(type background)
					)
				)
				(rectangle
					(start 3.81 -111.633)
					(end 5.08 -111.887)
					(stroke
						(width 0.254)
						(type default)
					)
					(fill
						(type background)
					)
				)
				(rectangle
					(start 3.81 -109.093)
					(end 5.08 -109.347)
					(stroke
						(width 0.254)
						(type default)
					)
					(fill
						(type background)
					)
				)
				(rectangle
					(start 3.81 -106.553)
					(end 5.08 -106.807)
					(stroke
						(width 0.254)
						(type default)
					)
					(fill
						(type background)
					)
				)
				(rectangle
					(start 3.81 -104.013)
					(end 5.08 -104.267)
					(stroke
						(width 0.254)
						(type default)
					)
					(fill
						(type background)
					)
				)
				(rectangle
					(start 3.81 -101.473)
					(end 5.08 -101.727)
					(stroke
						(width 0.254)
						(type default)
					)
					(fill
						(type background)
					)
				)
				(rectangle
					(start 3.81 -98.933)
					(end 5.08 -99.187)
					(stroke
						(width 0.254)
						(type default)
					)
					(fill
						(type background)
					)
				)
				(rectangle
					(start 3.81 -96.393)
					(end 5.08 -96.647)
					(stroke
						(width 0.254)
						(type default)
					)
					(fill
						(type background)
					)
				)
				(rectangle
					(start 3.81 -93.853)
					(end 5.08 -94.107)
					(stroke
						(width 0.254)
						(type default)
					)
					(fill
						(type background)
					)
				)
				(rectangle
					(start 3.81 -91.313)
					(end 5.08 -91.567)
					(stroke
						(width 0.254)
						(type default)
					)
					(fill
						(type background)
					)
				)
				(rectangle
					(start 3.81 -88.773)
					(end 5.08 -89.027)
					(stroke
						(width 0.254)
						(type default)
					)
					(fill
						(type background)
					)
				)
				(rectangle
					(start 3.81 -86.233)
					(end 5.08 -86.487)
					(stroke
						(width 0.254)
						(type default)
					)
					(fill
						(type background)
					)
				)
				(rectangle
					(start 3.81 -83.693)
					(end 5.08 -83.947)
					(stroke
						(width 0.254)
						(type default)
					)
					(fill
						(type background)
					)
				)
				(rectangle
					(start 3.81 -81.153)
					(end 5.08 -81.407)
					(stroke
						(width 0.254)
						(type default)
					)
					(fill
						(type background)
					)
				)
				(rectangle
					(start 3.81 -78.613)
					(end 5.08 -78.867)
					(stroke
						(width 0.254)
						(type default)
					)
					(fill
						(type background)
					)
				)
				(rectangle
					(start 3.81 -76.073)
					(end 5.08 -76.327)
					(stroke
						(width 0.254)
						(type default)
					)
					(fill
						(type background)
					)
				)
				(rectangle
					(start 3.81 -73.533)
					(end 5.08 -73.787)
					(stroke
						(width 0.254)
						(type default)
					)
					(fill
						(type background)
					)
				)
				(rectangle
					(start 3.81 -70.993)
					(end 5.08 -71.247)
					(stroke
						(width 0.254)
						(type default)
					)
					(fill
						(type background)
					)
				)
				(rectangle
					(start 3.81 -68.453)
					(end 5.08 -68.707)
					(stroke
						(width 0.254)
						(type default)
					)
					(fill
						(type background)
					)
				)
				(rectangle
					(start 3.81 -65.913)
					(end 5.08 -66.167)
					(stroke
						(width 0.254)
						(type default)
					)
					(fill
						(type background)
					)
				)
				(rectangle
					(start 3.81 -63.373)
					(end 5.08 -63.627)
					(stroke
						(width 0.254)
						(type default)
					)
					(fill
						(type background)
					)
				)
				(rectangle
					(start 3.81 -60.833)
					(end 5.08 -61.087)
					(stroke
						(width 0.254)
						(type default)
					)
					(fill
						(type background)
					)
				)
				(rectangle
					(start 3.81 -58.293)
					(end 5.08 -58.547)
					(stroke
						(width 0.254)
						(type default)
					)
					(fill
						(type background)
					)
				)
				(rectangle
					(start 3.81 -55.753)
					(end 5.08 -56.007)
					(stroke
						(width 0.254)
						(type default)
					)
					(fill
						(type background)
					)
				)
				(rectangle
					(start 3.81 -53.213)
					(end 5.08 -53.467)
					(stroke
						(width 0.254)
						(type default)
					)
					(fill
						(type background)
					)
				)
				(rectangle
					(start 3.81 -50.673)
					(end 5.08 -50.927)
					(stroke
						(width 0.254)
						(type default)
					)
					(fill
						(type background)
					)
				)
				(rectangle
					(start 3.81 -48.133)
					(end 5.08 -48.387)
					(stroke
						(width 0.254)
						(type default)
					)
					(fill
						(type background)
					)
				)
				(rectangle
					(start 3.81 -45.593)
					(end 5.08 -45.847)
					(stroke
						(width 0.254)
						(type default)
					)
					(fill
						(type background)
					)
				)
				(rectangle
					(start 3.81 -43.053)
					(end 5.08 -43.307)
					(stroke
						(width 0.254)
						(type default)
					)
					(fill
						(type background)
					)
				)
				(rectangle
					(start 3.81 -40.513)
					(end 5.08 -40.767)
					(stroke
						(width 0.254)
						(type default)
					)
					(fill
						(type background)
					)
				)
				(rectangle
					(start 3.81 -37.973)
					(end 5.08 -38.227)
					(stroke
						(width 0.254)
						(type default)
					)
					(fill
						(type background)
					)
				)
				(rectangle
					(start 3.81 -35.433)
					(end 5.08 -35.687)
					(stroke
						(width 0.254)
						(type default)
					)
					(fill
						(type background)
					)
				)
				(rectangle
					(start 3.81 -32.893)
					(end 5.08 -33.147)
					(stroke
						(width 0.254)
						(type default)
					)
					(fill
						(type background)
					)
				)
				(rectangle
					(start 3.81 -30.353)
					(end 5.08 -30.607)
					(stroke
						(width 0.254)
						(type default)
					)
					(fill
						(type background)
					)
				)
				(rectangle
					(start 3.81 -27.813)
					(end 5.08 -28.067)
					(stroke
						(width 0.254)
						(type default)
					)
					(fill
						(type background)
					)
				)
				(rectangle
					(start 3.81 -25.273)
					(end 5.08 -25.527)
					(stroke
						(width 0.254)
						(type default)
					)
					(fill
						(type background)
					)
				)
				(rectangle
					(start 3.81 -22.733)
					(end 5.08 -22.987)
					(stroke
						(width 0.254)
						(type default)
					)
					(fill
						(type background)
					)
				)
				(rectangle
					(start 3.81 -20.193)
					(end 5.08 -20.447)
					(stroke
						(width 0.254)
						(type default)
					)
					(fill
						(type background)
					)
				)
				(rectangle
					(start 3.81 -17.653)
					(end 5.08 -17.907)
					(stroke
						(width 0.254)
						(type default)
					)
					(fill
						(type background)
					)
				)
				(rectangle
					(start 3.81 -15.113)
					(end 5.08 -15.367)
					(stroke
						(width 0.254)
						(type default)
					)
					(fill
						(type background)
					)
				)
				(rectangle
					(start 3.81 -12.573)
					(end 5.08 -12.827)
					(stroke
						(width 0.254)
						(type default)
					)
					(fill
						(type background)
					)
				)
				(rectangle
					(start 3.81 -10.033)
					(end 5.08 -10.287)
					(stroke
						(width 0.254)
						(type default)
					)
					(fill
						(type background)
					)
				)
				(rectangle
					(start 3.81 -7.493)
					(end 5.08 -7.747)
					(stroke
						(width 0.254)
						(type default)
					)
					(fill
						(type background)
					)
				)
				(rectangle
					(start 3.81 -4.953)
					(end 5.08 -5.207)
					(stroke
						(width 0.254)
						(type default)
					)
					(fill
						(type background)
					)
				)
				(rectangle
					(start 3.81 -2.413)
					(end 5.08 -2.667)
					(stroke
						(width 0.254)
						(type default)
					)
					(fill
						(type background)
					)
				)
				(rectangle
					(start 3.81 0.127)
					(end 5.08 -0.127)
					(stroke
						(width 0.254)
						(type default)
					)
					(fill
						(type background)
					)
				)
				(rectangle
					(start 3.81 1.27)
					(end 7.62 -132.08)
					(stroke
						(width 0.254)
						(type default)
					)
					(fill
						(type background)
					)
				)
				(pin passive line
					(at 0 0 0)
					(length 3.81)
					(name "~"
						(effects
							(font
								(size 1.27 1.27)
							)
						)
					)
					(number "1"
						(effects
							(font
								(size 1.27 1.27)
							)
						)
					)
				)
				(pin passive line
					(at 0 -22.86 0)
					(length 3.81)
					(name "~"
						(effects
							(font
								(size 1.27 1.27)
							)
						)
					)
					(number "10"
						(effects
							(font
								(size 1.27 1.27)
							)
						)
					)
				)
				(pin passive line
					(at 0 -25.4 0)
					(length 3.81)
					(name "~"
						(effects
							(font
								(size 1.27 1.27)
							)
						)
					)
					(number "11"
						(effects
							(font
								(size 1.27 1.27)
							)
						)
					)
				)
				(pin passive line
					(at 0 -27.94 0)
					(length 3.81)
					(name "~"
						(effects
							(font
								(size 1.27 1.27)
							)
						)
					)
					(number "12"
						(effects
							(font
								(size 1.27 1.27)
							)
						)
					)
				)
				(pin passive line
					(at 0 -30.48 0)
					(length 3.81)
					(name "~"
						(effects
							(font
								(size 1.27 1.27)
							)
						)
					)
					(number "13"
						(effects
							(font
								(size 1.27 1.27)
							)
						)
					)
				)
				(pin passive line
					(at 0 -33.02 0)
					(length 3.81)
					(name "~"
						(effects
							(font
								(size 1.27 1.27)
							)
						)
					)
					(number "14"
						(effects
							(font
								(size 1.27 1.27)
							)
						)
					)
				)
				(pin passive line
					(at 0 -35.56 0)
					(length 3.81)
					(name "~"
						(effects
							(font
								(size 1.27 1.27)
							)
						)
					)
					(number "15"
						(effects
							(font
								(size 1.27 1.27)
							)
						)
					)
				)
				(pin passive line
					(at 0 -38.1 0)
					(length 3.81)
					(name "~"
						(effects
							(font
								(size 1.27 1.27)
							)
						)
					)
					(number "16"
						(effects
							(font
								(size 1.27 1.27)
							)
						)
					)
				)
				(pin passive line
					(at 0 -40.64 0)
					(length 3.81)
					(name "~"
						(effects
							(font
								(size 1.27 1.27)
							)
						)
					)
					(number "17"
						(effects
							(font
								(size 1.27 1.27)
							)
						)
					)
				)
				(pin passive line
					(at 0 -43.18 0)
					(length 3.81)
					(name "~"
						(effects
							(font
								(size 1.27 1.27)
							)
						)
					)
					(number "18"
						(effects
							(font
								(size 1.27 1.27)
							)
						)
					)
				)
				(pin passive line
					(at 0 -45.72 0)
					(length 3.81)
					(name "~"
						(effects
							(font
								(size 1.27 1.27)
							)
						)
					)
					(number "19"
						(effects
							(font
								(size 1.27 1.27)
							)
						)
					)
				)
				(pin passive line
					(at 0 -2.54 0)
					(length 3.81)
					(name "~"
						(effects
							(font
								(size 1.27 1.27)
							)
						)
					)
					(number "2"
						(effects
							(font
								(size 1.27 1.27)
							)
						)
					)
				)
				(pin passive line
					(at 0 -48.26 0)
					(length 3.81)
					(name "~"
						(effects
							(font
								(size 1.27 1.27)
							)
						)
					)
					(number "20"
						(effects
							(font
								(size 1.27 1.27)
							)
						)
					)
				)
				(pin passive line
					(at 0 -50.8 0)
					(length 3.81)
					(name "~"
						(effects
							(font
								(size 1.27 1.27)
							)
						)
					)
					(number "21"
						(effects
							(font
								(size 1.27 1.27)
							)
						)
					)
				)
				(pin passive line
					(at 0 -53.34 0)
					(length 3.81)
					(name "~"
						(effects
							(font
								(size 1.27 1.27)
							)
						)
					)
					(number "22"
						(effects
							(font
								(size 1.27 1.27)
							)
						)
					)
				)
				(pin passive line
					(at 0 -55.88 0)
					(length 3.81)
					(name "~"
						(effects
							(font
								(size 1.27 1.27)
							)
						)
					)
					(number "23"
						(effects
							(font
								(size 1.27 1.27)
							)
						)
					)
				)
				(pin passive line
					(at 0 -58.42 0)
					(length 3.81)
					(name "~"
						(effects
							(font
								(size 1.27 1.27)
							)
						)
					)
					(number "24"
						(effects
							(font
								(size 1.27 1.27)
							)
						)
					)
				)
				(pin passive line
					(at 0 -60.96 0)
					(length 3.81)
					(name "~"
						(effects
							(font
								(size 1.27 1.27)
							)
						)
					)
					(number "25"
						(effects
							(font
								(size 1.27 1.27)
							)
						)
					)
				)
				(pin passive line
					(at 0 -63.5 0)
					(length 3.81)
					(name "~"
						(effects
							(font
								(size 1.27 1.27)
							)
						)
					)
					(number "26"
						(effects
							(font
								(size 1.27 1.27)
							)
						)
					)
				)
				(pin passive line
					(at 0 -66.04 0)
					(length 3.81)
					(name "~"
						(effects
							(font
								(size 1.27 1.27)
							)
						)
					)
					(number "27"
						(effects
							(font
								(size 1.27 1.27)
							)
						)
					)
				)
				(pin passive line
					(at 0 -68.58 0)
					(length 3.81)
					(name "~"
						(effects
							(font
								(size 1.27 1.27)
							)
						)
					)
					(number "28"
						(effects
							(font
								(size 1.27 1.27)
							)
						)
					)
				)
				(pin passive line
					(at 0 -71.12 0)
					(length 3.81)
					(name "~"
						(effects
							(font
								(size 1.27 1.27)
							)
						)
					)
					(number "29"
						(effects
							(font
								(size 1.27 1.27)
							)
						)
					)
				)
				(pin passive line
					(at 0 -5.08 0)
					(length 3.81)
					(name "~"
						(effects
							(font
								(size 1.27 1.27)
							)
						)
					)
					(number "3"
						(effects
							(font
								(size 1.27 1.27)
							)
						)
					)
				)
				(pin passive line
					(at 0 -73.66 0)
					(length 3.81)
					(name "~"
						(effects
							(font
								(size 1.27 1.27)
							)
						)
					)
					(number "30"
						(effects
							(font
								(size 1.27 1.27)
							)
						)
					)
				)
				(pin passive line
					(at 0 -76.2 0)
					(length 3.81)
					(name "~"
						(effects
							(font
								(size 1.27 1.27)
							)
						)
					)
					(number "31"
						(effects
							(font
								(size 1.27 1.27)
							)
						)
					)
				)
				(pin passive line
					(at 0 -78.74 0)
					(length 3.81)
					(name "~"
						(effects
							(font
								(size 1.27 1.27)
							)
						)
					)
					(number "32"
						(effects
							(font
								(size 1.27 1.27)
							)
						)
					)
				)
				(pin passive line
					(at 0 -81.28 0)
					(length 3.81)
					(name "~"
						(effects
							(font
								(size 1.27 1.27)
							)
						)
					)
					(number "33"
						(effects
							(font
								(size 1.27 1.27)
							)
						)
					)
				)
				(pin passive line
					(at 0 -83.82 0)
					(length 3.81)
					(name "~"
						(effects
							(font
								(size 1.27 1.27)
							)
						)
					)
					(number "34"
						(effects
							(font
								(size 1.27 1.27)
							)
						)
					)
				)
				(pin passive line
					(at 0 -86.36 0)
					(length 3.81)
					(name "~"
						(effects
							(font
								(size 1.27 1.27)
							)
						)
					)
					(number "35"
						(effects
							(font
								(size 1.27 1.27)
							)
						)
					)
				)
				(pin passive line
					(at 0 -88.9 0)
					(length 3.81)
					(name "~"
						(effects
							(font
								(size 1.27 1.27)
							)
						)
					)
					(number "36"
						(effects
							(font
								(size 1.27 1.27)
							)
						)
					)
				)
				(pin passive line
					(at 0 -91.44 0)
					(length 3.81)
					(name "~"
						(effects
							(font
								(size 1.27 1.27)
							)
						)
					)
					(number "37"
						(effects
							(font
								(size 1.27 1.27)
							)
						)
					)
				)
				(pin passive line
					(at 0 -93.98 0)
					(length 3.81)
					(name "~"
						(effects
							(font
								(size 1.27 1.27)
							)
						)
					)
					(number "38"
						(effects
							(font
								(size 1.27 1.27)
							)
						)
					)
				)
				(pin passive line
					(at 0 -96.52 0)
					(length 3.81)
					(name "~"
						(effects
							(font
								(size 1.27 1.27)
							)
						)
					)
					(number "39"
						(effects
							(font
								(size 1.27 1.27)
							)
						)
					)
				)
				(pin passive line
					(at 0 -7.62 0)
					(length 3.81)
					(name "~"
						(effects
							(font
								(size 1.27 1.27)
							)
						)
					)
					(number "4"
						(effects
							(font
								(size 1.27 1.27)
							)
						)
					)
				)
				(pin passive line
					(at 0 -99.06 0)
					(length 3.81)
					(name "~"
						(effects
							(font
								(size 1.27 1.27)
							)
						)
					)
					(number "40"
						(effects
							(font
								(size 1.27 1.27)
							)
						)
					)
				)
				(pin passive line
					(at 0 -101.6 0)
					(length 3.81)
					(name "~"
						(effects
							(font
								(size 1.27 1.27)
							)
						)
					)
					(number "41"
						(effects
							(font
								(size 1.27 1.27)
							)
						)
					)
				)
				(pin passive line
					(at 0 -104.14 0)
					(length 3.81)
					(name "~"
						(effects
							(font
								(size 1.27 1.27)
							)
						)
					)
					(number "42"
						(effects
							(font
								(size 1.27 1.27)
							)
						)
					)
				)
				(pin passive line
					(at 0 -106.68 0)
					(length 3.81)
					(name "~"
						(effects
							(font
								(size 1.27 1.27)
							)
						)
					)
					(number "43"
						(effects
							(font
								(size 1.27 1.27)
							)
						)
					)
				)
				(pin passive line
					(at 0 -109.22 0)
					(length 3.81)
					(name "~"
						(effects
							(font
								(size 1.27 1.27)
							)
						)
					)
					(number "44"
						(effects
							(font
								(size 1.27 1.27)
							)
						)
					)
				)
				(pin passive line
					(at 0 -111.76 0)
					(length 3.81)
					(name "~"
						(effects
							(font
								(size 1.27 1.27)
							)
						)
					)
					(number "45"
						(effects
							(font
								(size 1.27 1.27)
							)
						)
					)
				)
				(pin passive line
					(at 0 -114.3 0)
					(length 3.81)
					(name "~"
						(effects
							(font
								(size 1.27 1.27)
							)
						)
					)
					(number "46"
						(effects
							(font
								(size 1.27 1.27)
							)
						)
					)
				)
				(pin passive line
					(at 0 -116.84 0)
					(length 3.81)
					(name "~"
						(effects
							(font
								(size 1.27 1.27)
							)
						)
					)
					(number "47"
						(effects
							(font
								(size 1.27 1.27)
							)
						)
					)
				)
				(pin passive line
					(at 0 -119.38 0)
					(length 3.81)
					(name "~"
						(effects
							(font
								(size 1.27 1.27)
							)
						)
					)
					(number "48"
						(effects
							(font
								(size 1.27 1.27)
							)
						)
					)
				)
				(pin passive line
					(at 0 -121.92 0)
					(length 3.81)
					(name "~"
						(effects
							(font
								(size 1.27 1.27)
							)
						)
					)
					(number "49"
						(effects
							(font
								(size 1.27 1.27)
							)
						)
					)
				)
				(pin passive line
					(at 0 -10.16 0)
					(length 3.81)
					(name "~"
						(effects
							(font
								(size 1.27 1.27)
							)
						)
					)
					(number "5"
						(effects
							(font
								(size 1.27 1.27)
							)
						)
					)
				)
				(pin passive line
					(at 0 -124.46 0)
					(length 3.81)
					(name "~"
						(effects
							(font
								(size 1.27 1.27)
							)
						)
					)
					(number "50"
						(effects
							(font
								(size 1.27 1.27)
							)
						)
					)
				)
				(pin passive line
					(at 0 -12.7 0)
					(length 3.81)
					(name "~"
						(effects
							(font
								(size 1.27 1.27)
							)
						)
					)
					(number "6"
						(effects
							(font
								(size 1.27 1.27)
							)
						)
					)
				)
				(pin passive line
					(at 0 -15.24 0)
					(length 3.81)
					(name "~"
						(effects
							(font
								(size 1.27 1.27)
							)
						)
					)
					(number "7"
						(effects
							(font
								(size 1.27 1.27)
							)
						)
					)
				)
				(pin passive line
					(at 0 -17.78 0)
					(length 3.81)
					(name "~"
						(effects
							(font
								(size 1.27 1.27)
							)
						)
					)
					(number "8"
						(effects
							(font
								(size 1.27 1.27)
							)
						)
					)
				)
				(pin passive line
					(at 0 -20.32 0)
					(length 3.81)
					(name "~"
						(effects
							(font
								(size 1.27 1.27)
							)
						)
					)
					(number "9"
						(effects
							(font
								(size 1.27 1.27)
							)
						)
					)
				)
				(pin passive line
					(at 0 -127 0)
					(length 3.81)
					(name "MP"
						(effects
							(font
								(size 1.27 1.27)
							)
						)
					)
					(number "MP1"
						(effects
							(font
								(size 1.27 1.27)
							)
						)
					)
				)
				(pin passive line
					(at 0 -129.54 0)
					(length 3.81)
					(name "MP"
						(effects
							(font
								(size 1.27 1.27)
							)
						)
					)
					(number "MP2"
						(effects
							(font
								(size 1.27 1.27)
							)
						)
					)
				)
			)
		)
	(symbol "antmicroFerriteBeadsandChips:FB_220Z_2A_Murata-BLM21PG_0805"
			(pin_numbers hide)
			(pin_names hide)
			(exclude_from_sim no)
			(in_bom yes)
			(on_board yes)
			(property "Reference" "FB"
				(at 13.97 0 0)
				(effects
					(font
						(size 1.27 1.27)
						(thickness 0.15)
					)
					(justify left bottom)
				)
			)
			(property "Value" "FB_220Z_2A_Murata-BLM21PG_0805"
				(at 13.97 -2.54 0)
				(effects
					(font
						(size 1.27 1.27)
						(thickness 0.15)
					)
					(justify left bottom)
					(hide yes)
				)
			)
			(property "Footprint" "antmicro-footprints:FB_0805_2012Metric"
				(at 13.97 -7.62 0)
				(effects
					(font
						(size 1.27 1.27)
						(thickness 0.15)
					)
					(justify left bottom)
					(hide yes)
				)
			)
			(property "Datasheet" "https://www.murata.com/products/productdata/8796738977822/ENFA0005.pdf?1653276712000"
				(at 13.97 -10.16 0)
				(effects
					(font
						(size 1.27 1.27)
						(thickness 0.15)
					)
					(justify left bottom)
					(hide yes)
				)
			)
			(property "Description" "Ferrite Bead, 0805 [2012 Metric], 220 ohm, 2 A, BLM21, 0.045 ohm, ± 25%, DC power line"
				(at 0 0 0)
				(effects
					(font
						(size 1.27 1.27)
					)
					(hide yes)
				)
			)
			(property "Val" "220Z/2A"
				(at 13.97 -5.08 0)
				(effects
					(font
						(size 1.27 1.27)
					)
					(justify left bottom)
				)
			)
			(property "MPN" "BLM21PG221SN1D"
				(at 13.97 -12.7 0)
				(effects
					(font
						(size 1.27 1.27)
						(thickness 0.15)
					)
					(justify left bottom)
					(hide yes)
				)
			)
			(property "Manufacturer" "Murata"
				(at 13.97 -15.24 0)
				(effects
					(font
						(size 1.27 1.27)
						(thickness 0.15)
					)
					(justify left bottom)
					(hide yes)
				)
			)
			(property "Current" ""
				(at 20.32 -22.86 0)
				(effects
					(font
						(size 1.27 1.27)
						(thickness 0.15)
					)
					(justify left bottom)
					(hide yes)
				)
			)
			(property "Author" "Antmicro"
				(at 13.97 -17.78 0)
				(effects
					(font
						(size 1.27 1.27)
						(thickness 0.15)
					)
					(justify left bottom)
					(hide yes)
				)
			)
			(property "License" "Apache-2.0"
				(at 13.97 -20.32 0)
				(effects
					(font
						(size 1.27 1.27)
						(thickness 0.15)
					)
					(justify left bottom)
					(hide yes)
				)
			)
			(property "ki_keywords" "FERRITE BEAD, PASSIVE"
				(at 0 0 0)
				(effects
					(font
						(size 1.27 1.27)
					)
					(hide yes)
				)
			)
			(symbol "FB_220Z_2A_Murata-BLM21PG_0805_0_1"
				(polyline
					(pts
						(xy 1.651 0) (xy 1.2446 0)
					)
					(stroke
						(width 0)
						(type default)
					)
					(fill
						(type none)
					)
				)
				(polyline
					(pts
						(xy 3.81 0) (xy 3.3274 0)
					)
					(stroke
						(width 0)
						(type default)
					)
					(fill
						(type none)
					)
				)
				(polyline
					(pts
						(xy 2.2606 -1.8288) (xy 1.0414 -1.1176) (xy 2.7432 1.8288) (xy 3.9624 1.1176) (xy 2.2606 -1.8288)
					)
					(stroke
						(width 0)
						(type default)
					)
					(fill
						(type none)
					)
				)
			)
			(symbol "FB_220Z_2A_Murata-BLM21PG_0805_1_1"
				(pin passive line
					(at 0 0 0)
					(length 1.27)
					(name "~"
						(effects
							(font
								(size 1.27 1.27)
							)
						)
					)
					(number "1"
						(effects
							(font
								(size 1.27 1.27)
							)
						)
					)
				)
				(pin passive line
					(at 5.08 0 180)
					(length 1.27)
					(name "~"
						(effects
							(font
								(size 1.27 1.27)
							)
						)
					)
					(number "2"
						(effects
							(font
								(size 1.27 1.27)
							)
						)
					)
				)
			)
		)
	(symbol "antmicroFixedInductors:L_1u_20A_Bourns-SRP6050CA"
			(pin_numbers hide)
			(pin_names hide)
			(exclude_from_sim no)
			(in_bom yes)
			(on_board yes)
			(property "Reference" "L"
				(at 13.97 0 0)
				(effects
					(font
						(size 1.27 1.27)
						(thickness 0.15)
					)
					(justify left bottom)
				)
			)
			(property "Value" "L_1u_20A_Bourns-SRP6050CA"
				(at 13.97 -2.54 0)
				(effects
					(font
						(size 1.27 1.27)
						(thickness 0.15)
					)
					(justify left bottom)
					(hide yes)
				)
			)
			(property "Footprint" "antmicro-footprints:L_Bourns-SRP6050CA"
				(at 13.97 -7.62 0)
				(effects
					(font
						(size 1.27 1.27)
						(thickness 0.15)
					)
					(justify left bottom)
					(hide yes)
				)
			)
			(property "Datasheet" "https://www.bourns.com/docs/Product-Datasheets/SRP6050CA.pdf"
				(at 13.97 -10.16 0)
				(effects
					(font
						(size 1.27 1.27)
						(thickness 0.15)
					)
					(justify left bottom)
					(hide yes)
				)
			)
			(property "Description" "Power Inductor (SMT), 1 µH, 20 A, Shielded, 23 A, SRP6050CA"
				(at 0 0 0)
				(effects
					(font
						(size 1.27 1.27)
					)
					(hide yes)
				)
			)
			(property "Val" "1u/20A"
				(at 13.97 -5.08 0)
				(effects
					(font
						(size 1.27 1.27)
						(thickness 0.15)
					)
					(justify left bottom)
				)
			)
			(property "Manufacturer" "Bourns"
				(at 13.97 -12.7 0)
				(effects
					(font
						(size 1.27 1.27)
						(thickness 0.15)
					)
					(justify left bottom)
					(hide yes)
				)
			)
			(property "MPN" "SRP6050CA-1R0M"
				(at 13.97 -15.24 0)
				(effects
					(font
						(size 1.27 1.27)
						(thickness 0.15)
					)
					(justify left bottom)
					(hide yes)
				)
			)
			(property "ISat" "23 A"
				(at 13.97 -16.51 0)
				(effects
					(font
						(size 1.27 1.27)
					)
					(justify left)
					(hide yes)
				)
			)
			(property "IMax" "20 A"
				(at 13.97 -20.32 0)
				(effects
					(font
						(size 1.27 1.27)
						(thickness 0.15)
					)
					(justify left bottom)
					(hide yes)
				)
			)
			(property "Size" "6.6x6.4"
				(at 13.97 -22.86 0)
				(effects
					(font
						(size 1.27 1.27)
						(thickness 0.15)
					)
					(justify left bottom)
					(hide yes)
				)
			)
			(property "Author" "Antmicro"
				(at 13.97 -25.4 0)
				(effects
					(font
						(size 1.27 1.27)
						(thickness 0.15)
					)
					(justify left bottom)
					(hide yes)
				)
			)
			(property "License" "Apache-2.0"
				(at 13.97 -27.94 0)
				(effects
					(font
						(size 1.27 1.27)
						(thickness 0.15)
					)
					(justify left bottom)
					(hide yes)
				)
			)
			(property "ki_keywords" "SMT, INDUCTOR, PASSIVE"
				(at 0 0 0)
				(effects
					(font
						(size 1.27 1.27)
					)
					(hide yes)
				)
			)
			(symbol "L_1u_20A_Bourns-SRP6050CA_0_1"
				(arc
					(start 1.524 0)
					(mid 1.016 0.5058)
					(end 0.508 0)
					(stroke
						(width 0)
						(type default)
					)
					(fill
						(type none)
					)
				)
				(arc
					(start 2.54 0)
					(mid 2.032 0.5058)
					(end 1.524 0)
					(stroke
						(width 0)
						(type default)
					)
					(fill
						(type none)
					)
				)
				(arc
					(start 3.556 0)
					(mid 3.048 0.5058)
					(end 2.54 0)
					(stroke
						(width 0)
						(type default)
					)
					(fill
						(type none)
					)
				)
				(arc
					(start 4.572 0)
					(mid 4.064 0.5058)
					(end 3.556 0)
					(stroke
						(width 0)
						(type default)
					)
					(fill
						(type none)
					)
				)
			)
			(symbol "L_1u_20A_Bourns-SRP6050CA_1_1"
				(pin passive line
					(at 0 0 0)
					(length 0.508)
					(name "~"
						(effects
							(font
								(size 1.27 1.27)
							)
						)
					)
					(number "1"
						(effects
							(font
								(size 1.27 1.27)
							)
						)
					)
				)
				(pin passive line
					(at 5.08 0 180)
					(length 0.508)
					(name "~"
						(effects
							(font
								(size 1.27 1.27)
							)
						)
					)
					(number "2"
						(effects
							(font
								(size 1.27 1.27)
							)
						)
					)
				)
			)
		)
	(symbol "antmicroFixedInductors:L_560n_17.7A_Bourns-SRP5030CA"
			(pin_numbers hide)
			(pin_names hide)
			(exclude_from_sim no)
			(in_bom yes)
			(on_board yes)
			(property "Reference" "L"
				(at 13.97 0 0)
				(effects
					(font
						(size 1.27 1.27)
						(thickness 0.15)
					)
					(justify left bottom)
				)
			)
			(property "Value" "L_560n_17.7A_Bourns-SRP5030CA"
				(at 13.97 -2.54 0)
				(effects
					(font
						(size 1.27 1.27)
						(thickness 0.15)
					)
					(justify left bottom)
					(hide yes)
				)
			)
			(property "Footprint" "antmicro-footprints:L_Bourns-SRP5030CA"
				(at 13.97 -7.62 0)
				(effects
					(font
						(size 1.27 1.27)
						(thickness 0.15)
					)
					(justify left bottom)
					(hide yes)
				)
			)
			(property "Datasheet" "https://www.bourns.com/docs/Product-Datasheets/SRP5030CA.pdf"
				(at 13.97 -10.16 0)
				(effects
					(font
						(size 1.27 1.27)
						(thickness 0.15)
					)
					(justify left bottom)
					(hide yes)
				)
			)
			(property "Description" "Power Inductor (SMT), 560 nH, 17.7 A, Shielded, 22.2 A, SRP5030CA"
				(at 0 0 0)
				(effects
					(font
						(size 1.27 1.27)
					)
					(hide yes)
				)
			)
			(property "Val" "560n/17.7A"
				(at 13.97 -5.08 0)
				(effects
					(font
						(size 1.27 1.27)
						(thickness 0.15)
					)
					(justify left bottom)
				)
			)
			(property "Manufacturer" "Bourns"
				(at 13.97 -12.7 0)
				(effects
					(font
						(size 1.27 1.27)
						(thickness 0.15)
					)
					(justify left bottom)
					(hide yes)
				)
			)
			(property "MPN" "SRP5030CA-R56M"
				(at 13.97 -15.24 0)
				(effects
					(font
						(size 1.27 1.27)
						(thickness 0.15)
					)
					(justify left bottom)
					(hide yes)
				)
			)
			(property "ISat" "22.2 A"
				(at 13.97 -16.51 0)
				(effects
					(font
						(size 1.27 1.27)
					)
					(justify left)
					(hide yes)
				)
			)
			(property "IMax" "17.7 A"
				(at 13.97 -20.32 0)
				(effects
					(font
						(size 1.27 1.27)
						(thickness 0.15)
					)
					(justify left bottom)
					(hide yes)
				)
			)
			(property "Size" "5.5x5.3"
				(at 13.97 -22.86 0)
				(effects
					(font
						(size 1.27 1.27)
						(thickness 0.15)
					)
					(justify left bottom)
					(hide yes)
				)
			)
			(property "Author" "Antmicro"
				(at 13.97 -25.4 0)
				(effects
					(font
						(size 1.27 1.27)
						(thickness 0.15)
					)
					(justify left bottom)
					(hide yes)
				)
			)
			(property "License" "Apache-2.0"
				(at 13.97 -27.94 0)
				(effects
					(font
						(size 1.27 1.27)
						(thickness 0.15)
					)
					(justify left bottom)
					(hide yes)
				)
			)
			(property "ki_keywords" "SMT, INDUCTOR, PASSIVE"
				(at 0 0 0)
				(effects
					(font
						(size 1.27 1.27)
					)
					(hide yes)
				)
			)
			(symbol "L_560n_17.7A_Bourns-SRP5030CA_0_1"
				(arc
					(start 1.524 0)
					(mid 1.016 0.5058)
					(end 0.508 0)
					(stroke
						(width 0)
						(type default)
					)
					(fill
						(type none)
					)
				)
				(arc
					(start 2.54 0)
					(mid 2.032 0.5058)
					(end 1.524 0)
					(stroke
						(width 0)
						(type default)
					)
					(fill
						(type none)
					)
				)
				(arc
					(start 3.556 0)
					(mid 3.048 0.5058)
					(end 2.54 0)
					(stroke
						(width 0)
						(type default)
					)
					(fill
						(type none)
					)
				)
				(arc
					(start 4.572 0)
					(mid 4.064 0.5058)
					(end 3.556 0)
					(stroke
						(width 0)
						(type default)
					)
					(fill
						(type none)
					)
				)
			)
			(symbol "L_560n_17.7A_Bourns-SRP5030CA_1_1"
				(pin passive line
					(at 0 0 0)
					(length 0.508)
					(name "~"
						(effects
							(font
								(size 1.27 1.27)
							)
						)
					)
					(number "1"
						(effects
							(font
								(size 1.27 1.27)
							)
						)
					)
				)
				(pin passive line
					(at 5.08 0 180)
					(length 0.508)
					(name "~"
						(effects
							(font
								(size 1.27 1.27)
							)
						)
					)
					(number "2"
						(effects
							(font
								(size 1.27 1.27)
							)
						)
					)
				)
			)
		)
	(symbol "antmicroFixedInductors:L_8u2_4A_2525"
			(pin_names
				(offset 1.016)
			)
			(exclude_from_sim no)
			(in_bom yes)
			(on_board yes)
			(property "Reference" "L"
				(at -5.715 1.27 0)
				(effects
					(font
						(size 1.524 1.524)
					)
					(justify left bottom)
				)
			)
			(property "Value" "IHLP2525CZER2R2M01_1"
				(at -11.43 -3.175 0)
				(effects
					(font
						(size 1.524 1.524)
					)
					(justify left bottom)
				)
			)
			(property "Footprint" "antmicro-footprints:L_2525_6363Metric"
				(at 20.32 10.16 0)
				(effects
					(font
						(size 1.524 1.524)
					)
					(hide yes)
				)
			)
			(property "Datasheet" "https://www.vishay.com/docs/34104/ihlp-2525cz-01.pdf"
				(at 34.29 7.62 0)
				(effects
					(font
						(size 1.524 1.524)
					)
					(hide yes)
				)
			)
			(property "Description" ""
				(at 0 0 0)
				(effects
					(font
						(size 1.27 1.27)
					)
					(hide yes)
				)
			)
			(property "Manufacturer" "Vishay"
				(at 2.54 17.78 0)
				(effects
					(font
						(size 1.27 1.27)
					)
					(hide yes)
				)
			)
			(property "MPN" "IHLP2525CZER8R2M01"
				(at 10.16 15.875 0)
				(effects
					(font
						(size 1.27 1.27)
					)
					(hide yes)
				)
			)
			(property "MaxCur" "8A"
				(at 1.27 13.97 0)
				(effects
					(font
						(size 1.27 1.27)
					)
					(hide yes)
				)
			)
			(property "Size" "6.47x6.47"
				(at 3.81 12.065 0)
				(effects
					(font
						(size 1.27 1.27)
					)
					(hide yes)
				)
			)
			(property "Val" "2.2u"
				(at 5.08 1.905 0)
				(effects
					(font
						(size 1.27 1.27)
					)
				)
			)
			(symbol "L_8u2_4A_2525_0_1"
				(pin passive line
					(at -5.08 0 0)
					(length 2.54)
					(name "P"
						(effects
							(font
								(size 0.0254 0.0254)
							)
						)
					)
					(number "1"
						(effects
							(font
								(size 0.0254 0.0254)
							)
						)
					)
				)
				(pin passive line
					(at 5.08 0 180)
					(length 2.54)
					(name "P"
						(effects
							(font
								(size 0.0254 0.0254)
							)
						)
					)
					(number "2"
						(effects
							(font
								(size 0.0254 0.0254)
							)
						)
					)
				)
			)
			(symbol "L_8u2_4A_2525_1_1"
				(arc
					(start -2.3368 0.5334)
					(mid -2.565 0.3058)
					(end -2.667 0)
					(stroke
						(width 0.254)
						(type default)
					)
					(fill
						(type none)
					)
				)
				(arc
					(start -1.7018 0.5334)
					(mid -2.0193 0.6272)
					(end -2.3368 0.5334)
					(stroke
						(width 0.254)
						(type default)
					)
					(fill
						(type none)
					)
				)
				(arc
					(start -1.397 0)
					(mid -1.4768 0.3082)
					(end -1.7018 0.5334)
					(stroke
						(width 0.254)
						(type default)
					)
					(fill
						(type none)
					)
				)
				(arc
					(start -1.3208 0.5334)
					(mid -1.549 0.3058)
					(end -1.651 0)
					(stroke
						(width 0.254)
						(type default)
					)
					(fill
						(type none)
					)
				)
				(arc
					(start -0.6858 0.5334)
					(mid -1.0033 0.6272)
					(end -1.3208 0.5334)
					(stroke
						(width 0.254)
						(type default)
					)
					(fill
						(type none)
					)
				)
				(arc
					(start -0.381 0)
					(mid -0.4608 0.3082)
					(end -0.6858 0.5334)
					(stroke
						(width 0.254)
						(type default)
					)
					(fill
						(type none)
					)
				)
				(arc
					(start -0.3048 0.5334)
					(mid -0.5311 0.3089)
					(end -0.6096 0)
					(stroke
						(width 0.254)
						(type default)
					)
					(fill
						(type none)
					)
				)
				(arc
					(start 0.3302 0.5334)
					(mid 0.0127 0.6272)
					(end -0.3048 0.5334)
					(stroke
						(width 0.254)
						(type default)
					)
					(fill
						(type none)
					)
				)
				(arc
					(start 0.6096 -0.0508)
					(mid 0.5453 0.2773)
					(end 0.3302 0.5334)
					(stroke
						(width 0.254)
						(type default)
					)
					(fill
						(type none)
					)
				)
				(arc
					(start 0.6858 0.5334)
					(mid 0.4675 0.3044)
					(end 0.381 0)
					(stroke
						(width 0.254)
						(type default)
					)
					(fill
						(type none)
					)
				)
				(arc
					(start 1.3208 0.5334)
					(mid 1.0033 0.6142)
					(end 0.6858 0.5334)
					(stroke
						(width 0.254)
						(type default)
					)
					(fill
						(type none)
					)
				)
				(arc
					(start 1.6256 0)
					(mid 1.5429 0.3065)
					(end 1.3208 0.5334)
					(stroke
						(width 0.254)
						(type default)
					)
					(fill
						(type none)
					)
				)
				(arc
					(start 1.7018 0.5334)
					(mid 1.4835 0.3044)
					(end 1.397 0)
					(stroke
						(width 0.254)
						(type default)
					)
					(fill
						(type none)
					)
				)
				(arc
					(start 2.3368 0.5334)
					(mid 2.0193 0.6142)
					(end 1.7018 0.5334)
					(stroke
						(width 0.254)
						(type default)
					)
					(fill
						(type none)
					)
				)
				(arc
					(start 2.667 0)
					(mid 2.5825 0.3166)
					(end 2.3368 0.5334)
					(stroke
						(width 0.254)
						(type default)
					)
					(fill
						(type none)
					)
				)
			)
		)
	(symbol "antmicroInterfaceAnalogSwitchesSpecialPurpose:TS3DV642RUARQ1"
			(exclude_from_sim no)
			(in_bom yes)
			(on_board yes)
			(property "Reference" "U"
				(at 38.1 -5.08 0)
				(effects
					(font
						(size 1.27 1.27)
						(thickness 0.15)
					)
					(justify left bottom)
				)
			)
			(property "Value" "TS3DV642RUARQ1"
				(at 38.1 -7.62 0)
				(effects
					(font
						(size 1.27 1.27)
						(thickness 0.15)
					)
					(justify left bottom)
					(hide yes)
				)
			)
			(property "Footprint" "antmicro-footprints:WQFN-42-1EP_3.5x9mm_P0.5mm"
				(at 38.1 -10.16 0)
				(effects
					(font
						(size 1.27 1.27)
						(thickness 0.15)
					)
					(justify left bottom)
					(hide yes)
				)
			)
			(property "Datasheet" "https://www.ti.com/lit/ds/symlink/ts3dv642-q1.pdf?ts=1676983005656&ref_url=https%253A%252F%252Fwww.ti.com%252Fproduct%252FTS3DV642-Q1"
				(at 38.1 -12.7 0)
				(effects
					(font
						(size 1.27 1.27)
						(thickness 0.15)
					)
					(justify left bottom)
					(hide yes)
				)
			)
			(property "Description" "Special purpose interface switch"
				(at 0 0 0)
				(effects
					(font
						(size 1.27 1.27)
					)
					(hide yes)
				)
			)
			(property "MPN" "TS3DV642RUARQ1"
				(at 38.1 -15.24 0)
				(effects
					(font
						(size 1.27 1.27)
						(thickness 0.15)
					)
					(justify left bottom)
				)
			)
			(property "Manufacturer" "Texas Instruments"
				(at 38.1 -17.78 0)
				(effects
					(font
						(size 1.27 1.27)
						(thickness 0.15)
					)
					(justify left bottom)
					(hide yes)
				)
			)
			(property "Author" "Antmicro"
				(at 38.1 -20.32 0)
				(effects
					(font
						(size 1.27 1.27)
						(thickness 0.15)
					)
					(justify left bottom)
					(hide yes)
				)
			)
			(property "License" "Apache-2.0"
				(at 38.1 -22.86 0)
				(effects
					(font
						(size 1.27 1.27)
						(thickness 0.15)
					)
					(justify left bottom)
					(hide yes)
				)
			)
			(property "ki_keywords" "IC"
				(at 0 0 0)
				(effects
					(font
						(size 1.27 1.27)
					)
					(hide yes)
				)
			)
			(symbol "TS3DV642RUARQ1_1_1"
				(rectangle
					(start 2.54 2.54)
					(end 22.86 -91.44)
					(stroke
						(width 0.254)
						(type default)
					)
					(fill
						(type background)
					)
				)
				(pin power_in line
					(at 0 0 0)
					(length 2.54)
					(name "VCC"
						(effects
							(font
								(size 1.27 1.27)
							)
						)
					)
					(number "1"
						(effects
							(font
								(size 1.27 1.27)
							)
						)
					)
				)
				(pin bidirectional line
					(at 0 -38.1 0)
					(length 2.54)
					(name "D2+"
						(effects
							(font
								(size 1.27 1.27)
							)
						)
					)
					(number "10"
						(effects
							(font
								(size 1.27 1.27)
							)
						)
					)
				)
				(pin bidirectional line
					(at 0 -40.64 0)
					(length 2.54)
					(name "D2-"
						(effects
							(font
								(size 1.27 1.27)
							)
						)
					)
					(number "11"
						(effects
							(font
								(size 1.27 1.27)
							)
						)
					)
				)
				(pin bidirectional line
					(at 0 -48.26 0)
					(length 2.54)
					(name "D3+"
						(effects
							(font
								(size 1.27 1.27)
							)
						)
					)
					(number "12"
						(effects
							(font
								(size 1.27 1.27)
							)
						)
					)
				)
				(pin bidirectional line
					(at 0 -50.8 0)
					(length 2.54)
					(name "D3-"
						(effects
							(font
								(size 1.27 1.27)
							)
						)
					)
					(number "13"
						(effects
							(font
								(size 1.27 1.27)
							)
						)
					)
				)
				(pin bidirectional line
					(at 0 -63.5 0)
					(length 2.54)
					(name "HPD"
						(effects
							(font
								(size 1.27 1.27)
							)
						)
					)
					(number "14"
						(effects
							(font
								(size 1.27 1.27)
							)
						)
					)
				)
				(pin bidirectional line
					(at 0 -66.04 0)
					(length 2.54)
					(name "CEC"
						(effects
							(font
								(size 1.27 1.27)
							)
						)
					)
					(number "15"
						(effects
							(font
								(size 1.27 1.27)
							)
						)
					)
				)
				(pin input line
					(at 0 -77.47 0)
					(length 2.54)
					(name "SEL1"
						(effects
							(font
								(size 1.27 1.27)
							)
						)
					)
					(number "16"
						(effects
							(font
								(size 1.27 1.27)
							)
						)
					)
				)
				(pin input line
					(at 0 -80.01 0)
					(length 2.54)
					(name "SEL2"
						(effects
							(font
								(size 1.27 1.27)
							)
						)
					)
					(number "17"
						(effects
							(font
								(size 1.27 1.27)
							)
						)
					)
				)
				(pin bidirectional line
					(at 25.4 -38.1 180)
					(length 2.54)
					(name "CEC_A"
						(effects
							(font
								(size 1.27 1.27)
							)
						)
					)
					(number "18"
						(effects
							(font
								(size 1.27 1.27)
							)
						)
					)
				)
				(pin bidirectional line
					(at 25.4 -40.64 180)
					(length 2.54)
					(name "HPD_A"
						(effects
							(font
								(size 1.27 1.27)
							)
						)
					)
					(number "19"
						(effects
							(font
								(size 1.27 1.27)
							)
						)
					)
				)
				(pin input line
					(at 0 -2.54 0)
					(length 2.54)
					(name "EN"
						(effects
							(font
								(size 1.27 1.27)
							)
						)
					)
					(number "2"
						(effects
							(font
								(size 1.27 1.27)
							)
						)
					)
				)
				(pin bidirectional line
					(at 25.4 -86.36 180)
					(length 2.54)
					(name "CEC_B"
						(effects
							(font
								(size 1.27 1.27)
							)
						)
					)
					(number "20"
						(effects
							(font
								(size 1.27 1.27)
							)
						)
					)
				)
				(pin bidirectional line
					(at 25.4 -88.9 180)
					(length 2.54)
					(name "HPD_B"
						(effects
							(font
								(size 1.27 1.27)
							)
						)
					)
					(number "21"
						(effects
							(font
								(size 1.27 1.27)
							)
						)
					)
				)
				(pin bidirectional line
					(at 25.4 -73.66 180)
					(length 2.54)
					(name "D3-B"
						(effects
							(font
								(size 1.27 1.27)
							)
						)
					)
					(number "22"
						(effects
							(font
								(size 1.27 1.27)
							)
						)
					)
				)
				(pin bidirectional line
					(at 25.4 -71.12 180)
					(length 2.54)
					(name "D3+B"
						(effects
							(font
								(size 1.27 1.27)
							)
						)
					)
					(number "23"
						(effects
							(font
								(size 1.27 1.27)
							)
						)
					)
				)
				(pin bidirectional line
					(at 25.4 -66.04 180)
					(length 2.54)
					(name "D2-B"
						(effects
							(font
								(size 1.27 1.27)
							)
						)
					)
					(number "24"
						(effects
							(font
								(size 1.27 1.27)
							)
						)
					)
				)
				(pin bidirectional line
					(at 25.4 -63.5 180)
					(length 2.54)
					(name "D2+B"
						(effects
							(font
								(size 1.27 1.27)
							)
						)
					)
					(number "25"
						(effects
							(font
								(size 1.27 1.27)
							)
						)
					)
				)
				(pin bidirectional line
					(at 25.4 -58.42 180)
					(length 2.54)
					(name "D1-B"
						(effects
							(font
								(size 1.27 1.27)
							)
						)
					)
					(number "26"
						(effects
							(font
								(size 1.27 1.27)
							)
						)
					)
				)
				(pin bidirectional line
					(at 25.4 -55.88 180)
					(length 2.54)
					(name "D1+B"
						(effects
							(font
								(size 1.27 1.27)
							)
						)
					)
					(number "27"
						(effects
							(font
								(size 1.27 1.27)
							)
						)
					)
				)
				(pin bidirectional line
					(at 25.4 -50.8 180)
					(length 2.54)
					(name "D0-B"
						(effects
							(font
								(size 1.27 1.27)
							)
						)
					)
					(number "28"
						(effects
							(font
								(size 1.27 1.27)
							)
						)
					)
				)
				(pin bidirectional line
					(at 25.4 -48.26 180)
					(length 2.54)
					(name "D0+B"
						(effects
							(font
								(size 1.27 1.27)
							)
						)
					)
					(number "29"
						(effects
							(font
								(size 1.27 1.27)
							)
						)
					)
				)
				(pin bidirectional line
					(at 0 -55.88 0)
					(length 2.54)
					(name "SCL/AUX+"
						(effects
							(font
								(size 1.27 1.27)
							)
						)
					)
					(number "3"
						(effects
							(font
								(size 1.27 1.27)
							)
						)
					)
				)
				(pin no_connect line
					(at 2.54 -17.78 0)
					(length 2.54) hide
					(name "NC"
						(effects
							(font
								(size 1.27 1.27)
							)
						)
					)
					(number "30"
						(effects
							(font
								(size 1.27 1.27)
							)
						)
					)
				)
				(pin bidirectional line
					(at 25.4 -25.4 180)
					(length 2.54)
					(name "D3-A"
						(effects
							(font
								(size 1.27 1.27)
							)
						)
					)
					(number "31"
						(effects
							(font
								(size 1.27 1.27)
							)
						)
					)
				)
				(pin bidirectional line
					(at 25.4 -22.86 180)
					(length 2.54)
					(name "D3+A"
						(effects
							(font
								(size 1.27 1.27)
							)
						)
					)
					(number "32"
						(effects
							(font
								(size 1.27 1.27)
							)
						)
					)
				)
				(pin bidirectional line
					(at 25.4 -17.78 180)
					(length 2.54)
					(name "D2-A"
						(effects
							(font
								(size 1.27 1.27)
							)
						)
					)
					(number "33"
						(effects
							(font
								(size 1.27 1.27)
							)
						)
					)
				)
				(pin bidirectional line
					(at 25.4 -15.24 180)
					(length 2.54)
					(name "D2+A"
						(effects
							(font
								(size 1.27 1.27)
							)
						)
					)
					(number "34"
						(effects
							(font
								(size 1.27 1.27)
							)
						)
					)
				)
				(pin bidirectional line
					(at 25.4 -10.16 180)
					(length 2.54)
					(name "D1-A"
						(effects
							(font
								(size 1.27 1.27)
							)
						)
					)
					(number "35"
						(effects
							(font
								(size 1.27 1.27)
							)
						)
					)
				)
				(pin bidirectional line
					(at 25.4 -7.62 180)
					(length 2.54)
					(name "D1+A"
						(effects
							(font
								(size 1.27 1.27)
							)
						)
					)
					(number "36"
						(effects
							(font
								(size 1.27 1.27)
							)
						)
					)
				)
				(pin bidirectional line
					(at 25.4 -2.54 180)
					(length 2.54)
					(name "D0-A"
						(effects
							(font
								(size 1.27 1.27)
							)
						)
					)
					(number "37"
						(effects
							(font
								(size 1.27 1.27)
							)
						)
					)
				)
				(pin bidirectional line
					(at 25.4 0 180)
					(length 2.54)
					(name "D0+A"
						(effects
							(font
								(size 1.27 1.27)
							)
						)
					)
					(number "38"
						(effects
							(font
								(size 1.27 1.27)
							)
						)
					)
				)
				(pin bidirectional line
					(at 25.4 -80.01 180)
					(length 2.54)
					(name "SDA/AUX-_B"
						(effects
							(font
								(size 1.27 1.27)
							)
						)
					)
					(number "39"
						(effects
							(font
								(size 1.27 1.27)
							)
						)
					)
				)
				(pin bidirectional line
					(at 0 -58.42 0)
					(length 2.54)
					(name "SDA/AUX-"
						(effects
							(font
								(size 1.27 1.27)
							)
						)
					)
					(number "4"
						(effects
							(font
								(size 1.27 1.27)
							)
						)
					)
				)
				(pin bidirectional line
					(at 25.4 -77.47 180)
					(length 2.54)
					(name "SCL/AUX+_B"
						(effects
							(font
								(size 1.27 1.27)
							)
						)
					)
					(number "40"
						(effects
							(font
								(size 1.27 1.27)
							)
						)
					)
				)
				(pin bidirectional line
					(at 25.4 -33.02 180)
					(length 2.54)
					(name "SDA/AUX-_A"
						(effects
							(font
								(size 1.27 1.27)
							)
						)
					)
					(number "41"
						(effects
							(font
								(size 1.27 1.27)
							)
						)
					)
				)
				(pin bidirectional line
					(at 25.4 -30.48 180)
					(length 2.54)
					(name "SCL/AUX+_A"
						(effects
							(font
								(size 1.27 1.27)
							)
						)
					)
					(number "42"
						(effects
							(font
								(size 1.27 1.27)
							)
						)
					)
				)
				(pin power_in line
					(at 0 -88.9 0)
					(length 2.54)
					(name "GND"
						(effects
							(font
								(size 1.27 1.27)
							)
						)
					)
					(number "43"
						(effects
							(font
								(size 1.27 1.27)
							)
						)
					)
				)
				(pin bidirectional line
					(at 0 -22.86 0)
					(length 2.54)
					(name "D0+"
						(effects
							(font
								(size 1.27 1.27)
							)
						)
					)
					(number "5"
						(effects
							(font
								(size 1.27 1.27)
							)
						)
					)
				)
				(pin bidirectional line
					(at 0 -25.4 0)
					(length 2.54)
					(name "D0-"
						(effects
							(font
								(size 1.27 1.27)
							)
						)
					)
					(number "6"
						(effects
							(font
								(size 1.27 1.27)
							)
						)
					)
				)
				(pin bidirectional line
					(at 0 -30.48 0)
					(length 2.54)
					(name "D1+"
						(effects
							(font
								(size 1.27 1.27)
							)
						)
					)
					(number "7"
						(effects
							(font
								(size 1.27 1.27)
							)
						)
					)
				)
				(pin bidirectional line
					(at 0 -33.02 0)
					(length 2.54)
					(name "D1-"
						(effects
							(font
								(size 1.27 1.27)
							)
						)
					)
					(number "8"
						(effects
							(font
								(size 1.27 1.27)
							)
						)
					)
				)
				(pin no_connect line
					(at 2.54 -15.24 0)
					(length 2.54) hide
					(name "NC"
						(effects
							(font
								(size 1.27 1.27)
							)
						)
					)
					(number "9"
						(effects
							(font
								(size 1.27 1.27)
							)
						)
					)
				)
			)
		)
	(symbol "antmicroInterfaceControllers:FT230X_QFN"
			(exclude_from_sim no)
			(in_bom yes)
			(on_board yes)
			(property "Reference" "U"
				(at 39.37 -7.62 0)
				(effects
					(font
						(size 1.27 1.27)
						(thickness 0.15)
					)
					(justify left bottom)
				)
			)
			(property "Value" "FT230X_QFN"
				(at 39.37 -10.16 0)
				(effects
					(font
						(size 1.27 1.27)
						(thickness 0.15)
					)
					(justify left bottom)
					(hide yes)
				)
			)
			(property "Footprint" "antmicro-footprints:QFN-16-1EP_4x4mm_P0.65mm"
				(at 39.37 -12.7 0)
				(effects
					(font
						(size 1.27 1.27)
						(thickness 0.15)
					)
					(justify left bottom)
					(hide yes)
				)
			)
			(property "Datasheet" "https://ftdichip.com/wp-content/uploads/2021/10/DS_FT230X.pdf"
				(at 39.37 -15.24 0)
				(effects
					(font
						(size 1.27 1.27)
						(thickness 0.15)
					)
					(justify left bottom)
					(hide yes)
				)
			)
			(property "Description" "USB Interface, USB-UART Converter, USB 2.0, 2.97 V, 5.5 V, QFN, 16 Pins"
				(at 0 0 0)
				(effects
					(font
						(size 1.27 1.27)
					)
					(hide yes)
				)
			)
			(property "MPN" "FT230XQ-R"
				(at 39.37 -20.32 0)
				(effects
					(font
						(size 1.27 1.27)
						(thickness 0.15)
					)
					(justify left bottom)
				)
			)
			(property "Manufacturer" "FTDI Chip"
				(at 39.37 -17.78 0)
				(effects
					(font
						(size 1.27 1.27)
						(thickness 0.15)
					)
					(justify left bottom)
					(hide yes)
				)
			)
			(property "Author" "Antmicro"
				(at 39.37 -22.86 0)
				(effects
					(font
						(size 1.27 1.27)
						(thickness 0.15)
					)
					(justify left bottom)
					(hide yes)
				)
			)
			(property "License" "Apache-2.0"
				(at 39.37 -25.4 0)
				(effects
					(font
						(size 1.27 1.27)
						(thickness 0.15)
					)
					(justify left bottom)
					(hide yes)
				)
			)
			(property "ki_keywords" "SMT, INTERFACE, IC, CONTROLLER, USB, UART"
				(at 0 0 0)
				(effects
					(font
						(size 1.27 1.27)
					)
					(hide yes)
				)
			)
			(symbol "FT230X_QFN_1_1"
				(rectangle
					(start 2.54 2.54)
					(end 20.32 -22.86)
					(stroke
						(width 0.254)
						(type default)
					)
					(fill
						(type background)
					)
				)
				(pin power_in line
					(at 0 -2.54 0)
					(length 2.54)
					(name "V_{CCIO}"
						(effects
							(font
								(size 1.27 1.27)
							)
						)
					)
					(number "1"
						(effects
							(font
								(size 1.27 1.27)
							)
						)
					)
				)
				(pin power_in line
					(at 0 0 0)
					(length 2.54)
					(name "V_{CC}"
						(effects
							(font
								(size 1.27 1.27)
							)
						)
					)
					(number "10"
						(effects
							(font
								(size 1.27 1.27)
							)
						)
					)
				)
				(pin bidirectional line
					(at 22.86 -15.24 180)
					(length 2.54)
					(name "CBUS1"
						(effects
							(font
								(size 1.27 1.27)
							)
						)
					)
					(number "11"
						(effects
							(font
								(size 1.27 1.27)
							)
						)
					)
				)
				(pin bidirectional line
					(at 22.86 -12.7 180)
					(length 2.54)
					(name "CBUS0"
						(effects
							(font
								(size 1.27 1.27)
							)
						)
					)
					(number "12"
						(effects
							(font
								(size 1.27 1.27)
							)
						)
					)
				)
				(pin power_in line
					(at 0 -20.32 0)
					(length 2.54)
					(name "GND"
						(effects
							(font
								(size 1.27 1.27)
							)
						)
					)
					(number "13"
						(effects
							(font
								(size 1.27 1.27)
							)
						)
					)
				)
				(pin bidirectional line
					(at 22.86 -20.32 180)
					(length 2.54)
					(name "CBUS3"
						(effects
							(font
								(size 1.27 1.27)
							)
						)
					)
					(number "14"
						(effects
							(font
								(size 1.27 1.27)
							)
						)
					)
				)
				(pin output line
					(at 22.86 0 180)
					(length 2.54)
					(name "TXD"
						(effects
							(font
								(size 1.27 1.27)
							)
						)
					)
					(number "15"
						(effects
							(font
								(size 1.27 1.27)
							)
						)
					)
				)
				(pin output line
					(at 22.86 -5.08 180)
					(length 2.54)
					(name "~{RTS}"
						(effects
							(font
								(size 1.27 1.27)
							)
						)
					)
					(number "16"
						(effects
							(font
								(size 1.27 1.27)
							)
						)
					)
				)
				(pin passive line
					(at 0 -20.32 0)
					(length 2.54) hide
					(name "GND"
						(effects
							(font
								(size 1.27 1.27)
							)
						)
					)
					(number "17"
						(effects
							(font
								(size 1.27 1.27)
							)
						)
					)
				)
				(pin input line
					(at 22.86 -2.54 180)
					(length 2.54)
					(name "RXD"
						(effects
							(font
								(size 1.27 1.27)
							)
						)
					)
					(number "2"
						(effects
							(font
								(size 1.27 1.27)
							)
						)
					)
				)
				(pin passive line
					(at 0 -20.32 0)
					(length 2.54) hide
					(name "GND"
						(effects
							(font
								(size 1.27 1.27)
							)
						)
					)
					(number "3"
						(effects
							(font
								(size 1.27 1.27)
							)
						)
					)
				)
				(pin input line
					(at 22.86 -7.62 180)
					(length 2.54)
					(name "~{CTS}"
						(effects
							(font
								(size 1.27 1.27)
							)
						)
					)
					(number "4"
						(effects
							(font
								(size 1.27 1.27)
							)
						)
					)
				)
				(pin bidirectional line
					(at 22.86 -17.78 180)
					(length 2.54)
					(name "CBUS2"
						(effects
							(font
								(size 1.27 1.27)
							)
						)
					)
					(number "5"
						(effects
							(font
								(size 1.27 1.27)
							)
						)
					)
				)
				(pin input line
					(at 0 -8.89 0)
					(length 2.54)
					(name "D+"
						(effects
							(font
								(size 1.27 1.27)
							)
						)
					)
					(number "6"
						(effects
							(font
								(size 1.27 1.27)
							)
						)
					)
				)
				(pin input line
					(at 0 -11.43 0)
					(length 2.54)
					(name "D-"
						(effects
							(font
								(size 1.27 1.27)
							)
						)
					)
					(number "7"
						(effects
							(font
								(size 1.27 1.27)
							)
						)
					)
				)
				(pin passive line
					(at 0 -5.08 0)
					(length 2.54)
					(name "3V3_{OUT}"
						(effects
							(font
								(size 1.27 1.27)
							)
						)
					)
					(number "8"
						(effects
							(font
								(size 1.27 1.27)
							)
						)
					)
				)
				(pin input line
					(at 0 -15.24 0)
					(length 2.54)
					(name "~{RESET}"
						(effects
							(font
								(size 1.27 1.27)
							)
						)
					)
					(number "9"
						(effects
							(font
								(size 1.27 1.27)
							)
						)
					)
				)
			)
		)
	(symbol "antmicroInterfaceControllers:HD3SS3220RNH"
			(exclude_from_sim no)
			(in_bom yes)
			(on_board yes)
			(property "Reference" "U"
				(at 41.91 -5.08 0)
				(effects
					(font
						(size 1.27 1.27)
						(thickness 0.15)
					)
					(justify left bottom)
				)
			)
			(property "Value" "HD3SS3220RNH"
				(at 41.91 -7.62 0)
				(effects
					(font
						(size 1.27 1.27)
						(thickness 0.15)
					)
					(justify left bottom)
					(hide yes)
				)
			)
			(property "Footprint" "antmicro-footprints:WQFN-30-1EP_4.6x2.6mm_P0.4mm"
				(at 41.91 -10.16 0)
				(effects
					(font
						(size 1.27 1.27)
						(thickness 0.15)
					)
					(justify left bottom)
					(hide yes)
				)
			)
			(property "Datasheet" "https://www.ti.com/lit/ds/symlink/hd3ss3220.pdf?ts=1663000043694&ref_url=https%253A%252F%252Fwww.google.com%252F"
				(at 41.91 -12.7 0)
				(effects
					(font
						(size 1.27 1.27)
						(thickness 0.15)
					)
					(justify left bottom)
					(hide yes)
				)
			)
			(property "Description" "USB Interface IC 10-Gbps USB 3.1 Type-C 2:1 mux with DRP Controller 30-WQFN -40°C to 85°C"
				(at 0 0 0)
				(effects
					(font
						(size 1.27 1.27)
					)
					(hide yes)
				)
			)
			(property "Manufacturer" "Texas Instruments"
				(at 41.91 -15.24 0)
				(effects
					(font
						(size 1.27 1.27)
						(thickness 0.15)
					)
					(justify left bottom)
					(hide yes)
				)
			)
			(property "MPN" "HD3SS3220RNHT"
				(at 41.91 -17.78 0)
				(effects
					(font
						(size 1.27 1.27)
						(thickness 0.15)
					)
					(justify left bottom)
				)
			)
			(property "Author" "Antmicro"
				(at 41.91 -20.32 0)
				(effects
					(font
						(size 1.27 1.27)
						(thickness 0.15)
					)
					(justify left bottom)
					(hide yes)
				)
			)
			(property "License" "Apache-2.0"
				(at 41.91 -22.86 0)
				(effects
					(font
						(size 1.27 1.27)
						(thickness 0.15)
					)
					(justify left bottom)
					(hide yes)
				)
			)
			(property "ki_keywords" "SMT, CONTROLLER, IC, INTERFACE"
				(at 0 0 0)
				(effects
					(font
						(size 1.27 1.27)
					)
					(hide yes)
				)
			)
			(symbol "HD3SS3220RNH_1_1"
				(rectangle
					(start 2.54 2.54)
					(end 25.4 -64.77)
					(stroke
						(width 0.254)
						(type default)
					)
					(fill
						(type background)
					)
				)
				(pin passive line
					(at 27.94 -17.78 180)
					(length 2.54)
					(name "CC2"
						(effects
							(font
								(size 1.27 1.27)
							)
						)
					)
					(number "1"
						(effects
							(font
								(size 1.27 1.27)
							)
						)
					)
				)
				(pin passive line
					(at 0 -35.56 0)
					(length 2.54)
					(name "RX-"
						(effects
							(font
								(size 1.27 1.27)
							)
						)
					)
					(number "10"
						(effects
							(font
								(size 1.27 1.27)
							)
						)
					)
				)
				(pin passive line
					(at 27.94 0 180)
					(length 2.54)
					(name "DIR"
						(effects
							(font
								(size 1.27 1.27)
							)
						)
					)
					(number "11"
						(effects
							(font
								(size 1.27 1.27)
							)
						)
					)
				)
				(pin passive line
					(at 0 -20.32 0)
					(length 2.54)
					(name "ENn_MUX"
						(effects
							(font
								(size 1.27 1.27)
							)
						)
					)
					(number "12"
						(effects
							(font
								(size 1.27 1.27)
							)
						)
					)
				)
				(pin passive line
					(at 0 -62.23 0)
					(length 2.54)
					(name "GND"
						(effects
							(font
								(size 1.27 1.27)
							)
						)
					)
					(number "13"
						(effects
							(font
								(size 1.27 1.27)
							)
						)
					)
				)
				(pin passive line
					(at 27.94 -35.56 180)
					(length 2.54)
					(name "RX1-"
						(effects
							(font
								(size 1.27 1.27)
							)
						)
					)
					(number "14"
						(effects
							(font
								(size 1.27 1.27)
							)
						)
					)
				)
				(pin passive line
					(at 27.94 -38.1 180)
					(length 2.54)
					(name "RX1+"
						(effects
							(font
								(size 1.27 1.27)
							)
						)
					)
					(number "15"
						(effects
							(font
								(size 1.27 1.27)
							)
						)
					)
				)
				(pin passive line
					(at 27.94 -43.18 180)
					(length 2.54)
					(name "TX1-"
						(effects
							(font
								(size 1.27 1.27)
							)
						)
					)
					(number "16"
						(effects
							(font
								(size 1.27 1.27)
							)
						)
					)
				)
				(pin passive line
					(at 27.94 -45.72 180)
					(length 2.54)
					(name "TX1+"
						(effects
							(font
								(size 1.27 1.27)
							)
						)
					)
					(number "17"
						(effects
							(font
								(size 1.27 1.27)
							)
						)
					)
				)
				(pin passive line
					(at 27.94 -50.8 180)
					(length 2.54)
					(name "RX2-"
						(effects
							(font
								(size 1.27 1.27)
							)
						)
					)
					(number "18"
						(effects
							(font
								(size 1.27 1.27)
							)
						)
					)
				)
				(pin passive line
					(at 27.94 -53.34 180)
					(length 2.54)
					(name "RX2+"
						(effects
							(font
								(size 1.27 1.27)
							)
						)
					)
					(number "19"
						(effects
							(font
								(size 1.27 1.27)
							)
						)
					)
				)
				(pin passive line
					(at 27.94 -15.24 180)
					(length 2.54)
					(name "CC1"
						(effects
							(font
								(size 1.27 1.27)
							)
						)
					)
					(number "2"
						(effects
							(font
								(size 1.27 1.27)
							)
						)
					)
				)
				(pin passive line
					(at 27.94 -58.42 180)
					(length 2.54)
					(name "TX2-"
						(effects
							(font
								(size 1.27 1.27)
							)
						)
					)
					(number "20"
						(effects
							(font
								(size 1.27 1.27)
							)
						)
					)
				)
				(pin passive line
					(at 27.94 -60.96 180)
					(length 2.54)
					(name "TX2+"
						(effects
							(font
								(size 1.27 1.27)
							)
						)
					)
					(number "21"
						(effects
							(font
								(size 1.27 1.27)
							)
						)
					)
				)
				(pin passive line
					(at 0 -50.8 0)
					(length 2.54)
					(name "ADDR"
						(effects
							(font
								(size 1.27 1.27)
							)
						)
					)
					(number "22"
						(effects
							(font
								(size 1.27 1.27)
							)
						)
					)
				)
				(pin passive line
					(at 0 -58.42 0)
					(length 2.54)
					(name "INT_N/OUT3"
						(effects
							(font
								(size 1.27 1.27)
							)
						)
					)
					(number "23"
						(effects
							(font
								(size 1.27 1.27)
							)
						)
					)
				)
				(pin passive line
					(at 27.94 -5.08 180)
					(length 2.54)
					(name "VCONN_FAULT_N"
						(effects
							(font
								(size 1.27 1.27)
							)
						)
					)
					(number "24"
						(effects
							(font
								(size 1.27 1.27)
							)
						)
					)
				)
				(pin passive line
					(at 0 -53.34 0)
					(length 2.54)
					(name "SDA/OUT1"
						(effects
							(font
								(size 1.27 1.27)
							)
						)
					)
					(number "25"
						(effects
							(font
								(size 1.27 1.27)
							)
						)
					)
				)
				(pin passive line
					(at 0 -55.88 0)
					(length 2.54)
					(name "SCL/OUT2"
						(effects
							(font
								(size 1.27 1.27)
							)
						)
					)
					(number "26"
						(effects
							(font
								(size 1.27 1.27)
							)
						)
					)
				)
				(pin passive line
					(at 27.94 -2.54 180)
					(length 2.54)
					(name "ID"
						(effects
							(font
								(size 1.27 1.27)
							)
						)
					)
					(number "27"
						(effects
							(font
								(size 1.27 1.27)
							)
						)
					)
				)
				(pin passive line
					(at 0 -62.23 0)
					(length 2.54) hide
					(name "GND"
						(effects
							(font
								(size 1.27 1.27)
							)
						)
					)
					(number "28"
						(effects
							(font
								(size 1.27 1.27)
							)
						)
					)
				)
				(pin passive line
					(at 0 -22.86 0)
					(length 2.54)
					(name "ENn_CC"
						(effects
							(font
								(size 1.27 1.27)
							)
						)
					)
					(number "29"
						(effects
							(font
								(size 1.27 1.27)
							)
						)
					)
				)
				(pin passive line
					(at 0 -15.24 0)
					(length 2.54)
					(name "CURRENT_MODE"
						(effects
							(font
								(size 1.27 1.27)
							)
						)
					)
					(number "3"
						(effects
							(font
								(size 1.27 1.27)
							)
						)
					)
				)
				(pin passive line
					(at 0 0 0)
					(length 2.54)
					(name "VDD5"
						(effects
							(font
								(size 1.27 1.27)
							)
						)
					)
					(number "30"
						(effects
							(font
								(size 1.27 1.27)
							)
						)
					)
				)
				(pin passive line
					(at 0 -62.23 0)
					(length 2.54) hide
					(name "GND"
						(effects
							(font
								(size 1.27 1.27)
							)
						)
					)
					(number "31"
						(effects
							(font
								(size 1.27 1.27)
							)
						)
					)
				)
				(pin passive line
					(at 0 -17.78 0)
					(length 2.54)
					(name "PORT"
						(effects
							(font
								(size 1.27 1.27)
							)
						)
					)
					(number "4"
						(effects
							(font
								(size 1.27 1.27)
							)
						)
					)
				)
				(pin passive line
					(at 27.94 -10.16 180)
					(length 2.54)
					(name "VBUS_DET"
						(effects
							(font
								(size 1.27 1.27)
							)
						)
					)
					(number "5"
						(effects
							(font
								(size 1.27 1.27)
							)
						)
					)
				)
				(pin passive line
					(at 0 -45.72 0)
					(length 2.54)
					(name "TX+"
						(effects
							(font
								(size 1.27 1.27)
							)
						)
					)
					(number "6"
						(effects
							(font
								(size 1.27 1.27)
							)
						)
					)
				)
				(pin passive line
					(at 0 -43.18 0)
					(length 2.54)
					(name "TX-"
						(effects
							(font
								(size 1.27 1.27)
							)
						)
					)
					(number "7"
						(effects
							(font
								(size 1.27 1.27)
							)
						)
					)
				)
				(pin passive line
					(at 0 -2.54 0)
					(length 2.54)
					(name "VCC33"
						(effects
							(font
								(size 1.27 1.27)
							)
						)
					)
					(number "8"
						(effects
							(font
								(size 1.27 1.27)
							)
						)
					)
				)
				(pin passive line
					(at 0 -38.1 0)
					(length 2.54)
					(name "RX+"
						(effects
							(font
								(size 1.27 1.27)
							)
						)
					)
					(number "9"
						(effects
							(font
								(size 1.27 1.27)
							)
						)
					)
				)
			)
		)
	(symbol "antmicroInterfaceControllers:TPS65988DHRSHR"
			(exclude_from_sim no)
			(in_bom yes)
			(on_board yes)
			(property "Reference" "U"
				(at 49.53 -2.54 0)
				(effects
					(font
						(size 1.27 1.27)
						(thickness 0.15)
					)
					(justify left bottom)
				)
			)
			(property "Value" "TPS65988DHRSHR"
				(at 49.53 -5.08 0)
				(effects
					(font
						(size 1.27 1.27)
						(thickness 0.15)
					)
					(justify left bottom)
					(hide yes)
				)
			)
			(property "Footprint" "antmicro-footprints:IC_TPS65987DDHRSHR"
				(at 49.53 -7.62 0)
				(effects
					(font
						(size 1.27 1.27)
						(thickness 0.15)
					)
					(justify left bottom)
					(hide yes)
				)
			)
			(property "Datasheet" "https://www.ti.com/lit/ds/symlink/tps65988.pdf?ts=1662726631004&ref_url=https%253A%252F%252Fwww.ti.com%252Fproduct%252FTPS65988"
				(at 49.53 -10.16 0)
				(effects
					(font
						(size 1.27 1.27)
						(thickness 0.15)
					)
					(justify left bottom)
					(hide yes)
				)
			)
			(property "Description" "USB, Type-C Controller PMIC 56-VQFN (7x7)"
				(at 0 0 0)
				(effects
					(font
						(size 1.27 1.27)
					)
					(hide yes)
				)
			)
			(property "MPN" "TPS65988DHRSHR "
				(at 49.53 -12.7 0)
				(effects
					(font
						(size 1.27 1.27)
						(thickness 0.15)
					)
					(justify left bottom)
				)
			)
			(property "Manufacturer" "Texas Instruments"
				(at 49.53 -15.24 0)
				(effects
					(font
						(size 1.27 1.27)
						(thickness 0.15)
					)
					(justify left bottom)
					(hide yes)
				)
			)
			(property "License" "Apache-2.0"
				(at 49.53 -17.78 0)
				(effects
					(font
						(size 1.27 1.27)
						(thickness 0.15)
					)
					(justify left bottom)
					(hide yes)
				)
			)
			(property "Author" "Antmicro"
				(at 49.53 -20.32 0)
				(effects
					(font
						(size 1.27 1.27)
						(thickness 0.15)
					)
					(justify left bottom)
					(hide yes)
				)
			)
			(property "ki_locked" ""
				(at 0 0 0)
				(effects
					(font
						(size 1.27 1.27)
					)
				)
			)
			(property "ki_keywords" "SMT, CONTROLLER, IC, USB"
				(at 0 0 0)
				(effects
					(font
						(size 1.27 1.27)
					)
					(hide yes)
				)
			)
			(symbol "TPS65988DHRSHR_1_1"
				(rectangle
					(start 2.54 2.54)
					(end 33.02 -69.85)
					(stroke
						(width 0.254)
						(type default)
					)
					(fill
						(type background)
					)
				)
				(pin input line
					(at 0 -34.29 0)
					(length 2.54)
					(name "ADCIN2"
						(effects
							(font
								(size 1.27 1.27)
							)
						)
					)
					(number "10"
						(effects
							(font
								(size 1.27 1.27)
							)
						)
					)
				)
				(pin bidirectional line
					(at 35.56 0 180)
					(length 2.54)
					(name "GPIO0"
						(effects
							(font
								(size 1.27 1.27)
							)
						)
					)
					(number "16"
						(effects
							(font
								(size 1.27 1.27)
							)
						)
					)
				)
				(pin bidirectional line
					(at 35.56 -2.54 180)
					(length 2.54)
					(name "GPIO1"
						(effects
							(font
								(size 1.27 1.27)
							)
						)
					)
					(number "17"
						(effects
							(font
								(size 1.27 1.27)
							)
						)
					)
				)
				(pin bidirectional line
					(at 35.56 -5.08 180)
					(length 2.54)
					(name "GPIO2"
						(effects
							(font
								(size 1.27 1.27)
							)
						)
					)
					(number "18"
						(effects
							(font
								(size 1.27 1.27)
							)
						)
					)
				)
				(pin power_in line
					(at 0 -64.77 0)
					(length 2.54)
					(name "GND"
						(effects
							(font
								(size 1.27 1.27)
							)
						)
					)
					(number "20"
						(effects
							(font
								(size 1.27 1.27)
							)
						)
					)
				)
				(pin bidirectional line
					(at 35.56 -13.97 180)
					(length 2.54)
					(name "I2C3_SCL/GPIO5"
						(effects
							(font
								(size 1.27 1.27)
							)
						)
					)
					(number "21"
						(effects
							(font
								(size 1.27 1.27)
							)
						)
					)
					(alternate "GPIO5" bidirectional line)
					(alternate "I2C3_SCL" bidirectional line)
				)
				(pin bidirectional line
					(at 35.56 -16.51 180)
					(length 2.54)
					(name "I2C3_SDA/GPIO6"
						(effects
							(font
								(size 1.27 1.27)
							)
						)
					)
					(number "22"
						(effects
							(font
								(size 1.27 1.27)
							)
						)
					)
					(alternate "GPIO6" bidirectional line)
					(alternate "I2C3_SDA" bidirectional line)
				)
				(pin bidirectional line
					(at 35.56 -19.05 180)
					(length 2.54)
					(name "~{I2C3_IRQ}/GPIO7"
						(effects
							(font
								(size 1.27 1.27)
							)
						)
					)
					(number "23"
						(effects
							(font
								(size 1.27 1.27)
							)
						)
					)
					(alternate "GPIO7" bidirectional line)
					(alternate "~{I2C3_IRQ}" bidirectional line)
				)
				(pin bidirectional line
					(at 35.56 -54.61 180)
					(length 2.54)
					(name "I2C1_SCL"
						(effects
							(font
								(size 1.27 1.27)
							)
						)
					)
					(number "27"
						(effects
							(font
								(size 1.27 1.27)
							)
						)
					)
				)
				(pin bidirectional line
					(at 35.56 -57.15 180)
					(length 2.54)
					(name "I2C1_SDA"
						(effects
							(font
								(size 1.27 1.27)
							)
						)
					)
					(number "28"
						(effects
							(font
								(size 1.27 1.27)
							)
						)
					)
				)
				(pin output line
					(at 35.56 -52.07 180)
					(length 2.54)
					(name "~{I2C1_IRQ}"
						(effects
							(font
								(size 1.27 1.27)
							)
						)
					)
					(number "29"
						(effects
							(font
								(size 1.27 1.27)
							)
						)
					)
				)
				(pin bidirectional line
					(at 35.56 -7.62 180)
					(length 2.54)
					(name "GPIO3/HPD1"
						(effects
							(font
								(size 1.27 1.27)
							)
						)
					)
					(number "30"
						(effects
							(font
								(size 1.27 1.27)
							)
						)
					)
					(alternate "GPIO3" bidirectional line)
					(alternate "HPD1" bidirectional line)
				)
				(pin bidirectional line
					(at 35.56 -10.16 180)
					(length 2.54)
					(name "GPIO4/HPD2"
						(effects
							(font
								(size 1.27 1.27)
							)
						)
					)
					(number "31"
						(effects
							(font
								(size 1.27 1.27)
							)
						)
					)
					(alternate "GPIO4" bidirectional line)
					(alternate "HPD2" bidirectional line)
				)
				(pin bidirectional line
					(at 35.56 -64.77 180)
					(length 2.54)
					(name "I2C2_SCL"
						(effects
							(font
								(size 1.27 1.27)
							)
						)
					)
					(number "32"
						(effects
							(font
								(size 1.27 1.27)
							)
						)
					)
				)
				(pin bidirectional line
					(at 35.56 -67.31 180)
					(length 2.54)
					(name "I2C2_SDA"
						(effects
							(font
								(size 1.27 1.27)
							)
						)
					)
					(number "33"
						(effects
							(font
								(size 1.27 1.27)
							)
						)
					)
				)
				(pin output line
					(at 35.56 -62.23 180)
					(length 2.54)
					(name "~{I2C2_IRQ}"
						(effects
							(font
								(size 1.27 1.27)
							)
						)
					)
					(number "34"
						(effects
							(font
								(size 1.27 1.27)
							)
						)
					)
				)
				(pin power_out line
					(at 0 -2.54 0)
					(length 2.54)
					(name "LDO_1V8"
						(effects
							(font
								(size 1.27 1.27)
							)
						)
					)
					(number "35"
						(effects
							(font
								(size 1.27 1.27)
							)
						)
					)
				)
				(pin bidirectional line
					(at 35.56 -22.86 180)
					(length 2.54)
					(name "SPI_POCI/GPIO8"
						(effects
							(font
								(size 1.27 1.27)
							)
						)
					)
					(number "36"
						(effects
							(font
								(size 1.27 1.27)
							)
						)
					)
					(alternate "GPIO8" bidirectional line)
					(alternate "SPI_POCI" bidirectional line)
				)
				(pin bidirectional line
					(at 35.56 -25.4 180)
					(length 2.54)
					(name "SPI_PICO/GPIO9"
						(effects
							(font
								(size 1.27 1.27)
							)
						)
					)
					(number "37"
						(effects
							(font
								(size 1.27 1.27)
							)
						)
					)
					(alternate "GPIO9" bidirectional line)
					(alternate "SPI_PICO" bidirectional line)
				)
				(pin bidirectional line
					(at 35.56 -27.94 180)
					(length 2.54)
					(name "SPI_CLK/GPIO10"
						(effects
							(font
								(size 1.27 1.27)
							)
						)
					)
					(number "38"
						(effects
							(font
								(size 1.27 1.27)
							)
						)
					)
					(alternate "GPIO10" bidirectional line)
					(alternate "SPI_CLK" bidirectional line)
				)
				(pin bidirectional line
					(at 35.56 -30.48 180)
					(length 2.54)
					(name "~{SPI_CS}/GPIO11"
						(effects
							(font
								(size 1.27 1.27)
							)
						)
					)
					(number "39"
						(effects
							(font
								(size 1.27 1.27)
							)
						)
					)
					(alternate "GPIO11" bidirectional line)
					(alternate "~{SPI_CS}" bidirectional line)
				)
				(pin bidirectional line
					(at 35.56 -34.29 180)
					(length 2.54)
					(name "GPIO12"
						(effects
							(font
								(size 1.27 1.27)
							)
						)
					)
					(number "40"
						(effects
							(font
								(size 1.27 1.27)
							)
						)
					)
				)
				(pin bidirectional line
					(at 35.56 -36.83 180)
					(length 2.54)
					(name "GPIO13"
						(effects
							(font
								(size 1.27 1.27)
							)
						)
					)
					(number "41"
						(effects
							(font
								(size 1.27 1.27)
							)
						)
					)
				)
				(pin bidirectional line
					(at 35.56 -39.37 180)
					(length 2.54)
					(name "GPIO14/PWM1"
						(effects
							(font
								(size 1.27 1.27)
							)
						)
					)
					(number "42"
						(effects
							(font
								(size 1.27 1.27)
							)
						)
					)
					(alternate "GPIO14" bidirectional line)
					(alternate "PWM1" output line)
				)
				(pin bidirectional line
					(at 35.56 -41.91 180)
					(length 2.54)
					(name "GPIO15/PWM2"
						(effects
							(font
								(size 1.27 1.27)
							)
						)
					)
					(number "43"
						(effects
							(font
								(size 1.27 1.27)
							)
						)
					)
					(alternate "GPIO15" bidirectional line)
					(alternate "PWM2" output line)
				)
				(pin input line
					(at 0 -13.97 0)
					(length 2.54)
					(name "HRESET"
						(effects
							(font
								(size 1.27 1.27)
							)
						)
					)
					(number "44"
						(effects
							(font
								(size 1.27 1.27)
							)
						)
					)
				)
				(pin bidirectional line
					(at 35.56 -44.45 180)
					(length 2.54)
					(name "GPIO16/PP_EXT1"
						(effects
							(font
								(size 1.27 1.27)
							)
						)
					)
					(number "48"
						(effects
							(font
								(size 1.27 1.27)
							)
						)
					)
					(alternate "GPIO16" bidirectional line)
					(alternate "PP_EXT1" output line)
				)
				(pin bidirectional line
					(at 35.56 -46.99 180)
					(length 2.54)
					(name "GPIO17/PP_EXT2"
						(effects
							(font
								(size 1.27 1.27)
							)
						)
					)
					(number "49"
						(effects
							(font
								(size 1.27 1.27)
							)
						)
					)
					(alternate "GPIO17" bidirectional line)
					(alternate "PP_EXT2" output line)
				)
				(pin power_in line
					(at 0 0 0)
					(length 2.54)
					(name "VIN_3V3"
						(effects
							(font
								(size 1.27 1.27)
							)
						)
					)
					(number "5"
						(effects
							(font
								(size 1.27 1.27)
							)
						)
					)
				)
				(pin passive line
					(at 0 -64.77 0)
					(length 2.54) hide
					(name "GND"
						(effects
							(font
								(size 1.27 1.27)
							)
						)
					)
					(number "51"
						(effects
							(font
								(size 1.27 1.27)
							)
						)
					)
				)
				(pin power_in line
					(at 0 -67.31 0)
					(length 2.54)
					(name "GND_EP"
						(effects
							(font
								(size 1.27 1.27)
							)
						)
					)
					(number "59"
						(effects
							(font
								(size 1.27 1.27)
							)
						)
					)
				)
				(pin input line
					(at 0 -22.86 0)
					(length 2.54)
					(name "ADCIN1"
						(effects
							(font
								(size 1.27 1.27)
							)
						)
					)
					(number "6"
						(effects
							(font
								(size 1.27 1.27)
							)
						)
					)
				)
				(pin power_out line
					(at 0 -5.08 0)
					(length 2.54)
					(name "LDO_3V3"
						(effects
							(font
								(size 1.27 1.27)
							)
						)
					)
					(number "9"
						(effects
							(font
								(size 1.27 1.27)
							)
						)
					)
				)
			)
			(symbol "TPS65988DHRSHR_2_1"
				(polyline
					(pts
						(xy 11.303 0) (xy 13.208 0)
					)
					(stroke
						(width 0.254)
						(type default)
					)
					(fill
						(type background)
					)
				)
				(polyline
					(pts
						(xy 13.208 0) (xy 16.002 1.651)
					)
					(stroke
						(width 0.254)
						(type default)
					)
					(fill
						(type background)
					)
				)
				(polyline
					(pts
						(xy 19.177 0) (xy 16.637 0)
					)
					(stroke
						(width 0.254)
						(type default)
					)
					(fill
						(type background)
					)
				)
				(rectangle
					(start 2.54 3.81)
					(end 29.21 -19.05)
					(stroke
						(width 0.254)
						(type default)
					)
					(fill
						(type background)
					)
				)
				(circle
					(center 13.208 0)
					(radius 0.1796)
					(stroke
						(width 0.254)
						(type default)
					)
					(fill
						(type background)
					)
				)
				(circle
					(center 16.637 0)
					(radius 0.1796)
					(stroke
						(width 0.254)
						(type default)
					)
					(fill
						(type background)
					)
				)
				(pin bidirectional line
					(at 31.75 0 180)
					(length 2.54)
					(name "PP_HV1"
						(effects
							(font
								(size 1.27 1.27)
							)
						)
					)
					(number "11"
						(effects
							(font
								(size 1.27 1.27)
							)
						)
					)
				)
				(pin bidirectional line
					(at 0 0 0)
					(length 2.54)
					(name "VBUS1"
						(effects
							(font
								(size 1.27 1.27)
							)
						)
					)
					(number "13"
						(effects
							(font
								(size 1.27 1.27)
							)
						)
					)
				)
				(pin passive line
					(at 31.75 -15.24 180)
					(length 2.54)
					(name "DRAIN1"
						(effects
							(font
								(size 1.27 1.27)
							)
						)
					)
					(number "15"
						(effects
							(font
								(size 1.27 1.27)
							)
						)
					)
				)
				(pin passive line
					(at 31.75 -15.24 180)
					(length 2.54) hide
					(name "DRAIN1"
						(effects
							(font
								(size 1.27 1.27)
							)
						)
					)
					(number "19"
						(effects
							(font
								(size 1.27 1.27)
							)
						)
					)
				)
				(pin bidirectional line
					(at 0 -5.08 0)
					(length 2.54)
					(name "C1_CC1"
						(effects
							(font
								(size 1.27 1.27)
							)
						)
					)
					(number "24"
						(effects
							(font
								(size 1.27 1.27)
							)
						)
					)
				)
				(pin power_in line
					(at 31.75 -3.81 180)
					(length 2.54)
					(name "PP1_CABLE"
						(effects
							(font
								(size 1.27 1.27)
							)
						)
					)
					(number "25"
						(effects
							(font
								(size 1.27 1.27)
							)
						)
					)
				)
				(pin bidirectional line
					(at 0 -7.62 0)
					(length 2.54)
					(name "C1_CC2"
						(effects
							(font
								(size 1.27 1.27)
							)
						)
					)
					(number "26"
						(effects
							(font
								(size 1.27 1.27)
							)
						)
					)
				)
				(pin bidirectional line
					(at 0 -15.24 0)
					(length 2.54)
					(name "C1_USB_P/GPIO18"
						(effects
							(font
								(size 1.27 1.27)
							)
						)
					)
					(number "50"
						(effects
							(font
								(size 1.27 1.27)
							)
						)
					)
					(alternate "C1_USB_P" bidirectional line)
					(alternate "GPIO18" bidirectional line)
				)
				(pin bidirectional line
					(at 0 -12.7 0)
					(length 2.54)
					(name "C1_USB_N/GPIO19"
						(effects
							(font
								(size 1.27 1.27)
							)
						)
					)
					(number "53"
						(effects
							(font
								(size 1.27 1.27)
							)
						)
					)
					(alternate "C1_USB_N" bidirectional line)
					(alternate "GPIO19" bidirectional line)
				)
				(pin passive line
					(at 31.75 -15.24 180)
					(length 2.54) hide
					(name "DRAIN1"
						(effects
							(font
								(size 1.27 1.27)
							)
						)
					)
					(number "58"
						(effects
							(font
								(size 1.27 1.27)
							)
						)
					)
				)
				(pin passive line
					(at 31.75 -15.24 180)
					(length 2.54) hide
					(name "DRAIN1"
						(effects
							(font
								(size 1.27 1.27)
							)
						)
					)
					(number "8"
						(effects
							(font
								(size 1.27 1.27)
							)
						)
					)
				)
			)
			(symbol "TPS65988DHRSHR_3_1"
				(polyline
					(pts
						(xy 11.557 0) (xy 13.462 0)
					)
					(stroke
						(width 0.254)
						(type default)
					)
					(fill
						(type background)
					)
				)
				(polyline
					(pts
						(xy 13.462 0) (xy 16.256 1.651)
					)
					(stroke
						(width 0.254)
						(type default)
					)
					(fill
						(type background)
					)
				)
				(polyline
					(pts
						(xy 19.431 0) (xy 16.891 0)
					)
					(stroke
						(width 0.254)
						(type default)
					)
					(fill
						(type background)
					)
				)
				(rectangle
					(start 2.54 3.81)
					(end 29.21 -19.05)
					(stroke
						(width 0.254)
						(type default)
					)
					(fill
						(type background)
					)
				)
				(circle
					(center 13.462 0)
					(radius 0.1796)
					(stroke
						(width 0.254)
						(type default)
					)
					(fill
						(type background)
					)
				)
				(circle
					(center 16.891 0)
					(radius 0.1796)
					(stroke
						(width 0.254)
						(type default)
					)
					(fill
						(type background)
					)
				)
				(pin bidirectional line
					(at 31.75 0 180)
					(length 2.54)
					(name "PP_HV2"
						(effects
							(font
								(size 1.27 1.27)
							)
						)
					)
					(number "1"
						(effects
							(font
								(size 1.27 1.27)
							)
						)
					)
				)
				(pin bidirectional line
					(at 0 0 0)
					(length 2.54)
					(name "VBUS2"
						(effects
							(font
								(size 1.27 1.27)
							)
						)
					)
					(number "3"
						(effects
							(font
								(size 1.27 1.27)
							)
						)
					)
				)
				(pin bidirectional line
					(at 0 -5.08 0)
					(length 2.54)
					(name "C2_CC1"
						(effects
							(font
								(size 1.27 1.27)
							)
						)
					)
					(number "45"
						(effects
							(font
								(size 1.27 1.27)
							)
						)
					)
				)
				(pin power_in line
					(at 31.75 -3.81 180)
					(length 2.54)
					(name "PP2_CABLE"
						(effects
							(font
								(size 1.27 1.27)
							)
						)
					)
					(number "46"
						(effects
							(font
								(size 1.27 1.27)
							)
						)
					)
				)
				(pin bidirectional line
					(at 0 -7.62 0)
					(length 2.54)
					(name "C2_CC2"
						(effects
							(font
								(size 1.27 1.27)
							)
						)
					)
					(number "47"
						(effects
							(font
								(size 1.27 1.27)
							)
						)
					)
				)
				(pin passive line
					(at 31.75 -15.24 180)
					(length 2.54)
					(name "DRAIN2"
						(effects
							(font
								(size 1.27 1.27)
							)
						)
					)
					(number "52"
						(effects
							(font
								(size 1.27 1.27)
							)
						)
					)
				)
				(pin bidirectional line
					(at 0 -15.24 0)
					(length 2.54)
					(name "C2_USB_P/GPIO20"
						(effects
							(font
								(size 1.27 1.27)
							)
						)
					)
					(number "54"
						(effects
							(font
								(size 1.27 1.27)
							)
						)
					)
					(alternate "C2_USB_P" bidirectional line)
					(alternate "GPIO20" bidirectional line)
				)
				(pin bidirectional line
					(at 0 -12.7 0)
					(length 2.54)
					(name "C2_USB_N/GPIO21"
						(effects
							(font
								(size 1.27 1.27)
							)
						)
					)
					(number "55"
						(effects
							(font
								(size 1.27 1.27)
							)
						)
					)
					(alternate "C2_USB_N" bidirectional line)
					(alternate "GPIO21" bidirectional line)
				)
				(pin passive line
					(at 31.75 -15.24 180)
					(length 2.54) hide
					(name "DRAIN2"
						(effects
							(font
								(size 1.27 1.27)
							)
						)
					)
					(number "56"
						(effects
							(font
								(size 1.27 1.27)
							)
						)
					)
				)
				(pin passive line
					(at 31.75 -15.24 180)
					(length 2.54) hide
					(name "DRAIN2"
						(effects
							(font
								(size 1.27 1.27)
							)
						)
					)
					(number "57"
						(effects
							(font
								(size 1.27 1.27)
							)
						)
					)
				)
				(pin passive line
					(at 31.75 -15.24 180)
					(length 2.54) hide
					(name "DRAIN2"
						(effects
							(font
								(size 1.27 1.27)
							)
						)
					)
					(number "7"
						(effects
							(font
								(size 1.27 1.27)
							)
						)
					)
				)
			)
		)
	(symbol "antmicroInterfaceControllers:TUSB1046-DCIRNQ"
			(exclude_from_sim no)
			(in_bom yes)
			(on_board yes)
			(property "Reference" "U"
				(at 38.1 -2.54 0)
				(effects
					(font
						(size 1.27 1.27)
						(thickness 0.15)
					)
					(justify left bottom)
				)
			)
			(property "Value" "TUSB1046-DCIRNQ"
				(at 38.1 -5.08 0)
				(effects
					(font
						(size 1.27 1.27)
						(thickness 0.15)
					)
					(justify left bottom)
					(hide yes)
				)
			)
			(property "Footprint" "antmicro-footprints:WQFN-40_1EP_6x3mm_Pitch0.4mm_EP4.7x2.7mm"
				(at 38.1 -7.62 0)
				(effects
					(font
						(size 1.27 1.27)
						(thickness 0.15)
					)
					(justify left bottom)
					(hide yes)
				)
			)
			(property "Datasheet" "https://www.ti.com/lit/ds/sllsew2d/sllsew2d.pdf?ts=1662107117482&ref_url=https%253A%252F%252Fwww.google.com%252F"
				(at 38.1 -10.16 0)
				(effects
					(font
						(size 1.27 1.27)
						(thickness 0.15)
					)
					(justify left bottom)
					(hide yes)
				)
			)
			(property "Description" "Analog & Digital Crosspoint ICs USB Type-C DP ALT Mode, 10-Gbps linear redriver crosspoint switch 40-WQFN 0°C to 70°C"
				(at 0 0 0)
				(effects
					(font
						(size 1.27 1.27)
					)
					(hide yes)
				)
			)
			(property "MPN" "TUSB1046-DCIRNQT"
				(at 38.1 -12.7 0)
				(effects
					(font
						(size 1.27 1.27)
						(thickness 0.15)
					)
					(justify left bottom)
				)
			)
			(property "Manufacturer" "Texas Instruments"
				(at 38.1 -15.24 0)
				(effects
					(font
						(size 1.27 1.27)
						(thickness 0.15)
					)
					(justify left bottom)
					(hide yes)
				)
			)
			(property "Author" "Antmicro"
				(at 38.1 -17.78 0)
				(effects
					(font
						(size 1.27 1.27)
						(thickness 0.15)
					)
					(justify left bottom)
					(hide yes)
				)
			)
			(property "License" "Apache-2.0"
				(at 38.1 -20.32 0)
				(effects
					(font
						(size 1.27 1.27)
						(thickness 0.15)
					)
					(justify left bottom)
					(hide yes)
				)
			)
			(property "ki_keywords" "IC"
				(at 0 0 0)
				(effects
					(font
						(size 1.27 1.27)
					)
					(hide yes)
				)
			)
			(symbol "TUSB1046-DCIRNQ_1_1"
				(rectangle
					(start 2.54 2.54)
					(end 22.86 -76.2)
					(stroke
						(width 0.254)
						(type default)
					)
					(fill
						(type background)
					)
				)
				(pin power_in line
					(at 0 0 0)
					(length 2.54)
					(name "VCC"
						(effects
							(font
								(size 1.27 1.27)
							)
						)
					)
					(number "1"
						(effects
							(font
								(size 1.27 1.27)
							)
						)
					)
				)
				(pin input line
					(at 0 -43.18 0)
					(length 2.54)
					(name "DP0_N"
						(effects
							(font
								(size 1.27 1.27)
							)
						)
					)
					(number "10"
						(effects
							(font
								(size 1.27 1.27)
							)
						)
					)
				)
				(pin input line
					(at 25.4 -50.8 180)
					(length 2.54)
					(name "SSEQ0/A0"
						(effects
							(font
								(size 1.27 1.27)
							)
						)
					)
					(number "11"
						(effects
							(font
								(size 1.27 1.27)
							)
						)
					)
				)
				(pin input line
					(at 0 -48.26 0)
					(length 2.54)
					(name "DP1_P"
						(effects
							(font
								(size 1.27 1.27)
							)
						)
					)
					(number "12"
						(effects
							(font
								(size 1.27 1.27)
							)
						)
					)
				)
				(pin input line
					(at 0 -50.8 0)
					(length 2.54)
					(name "DP1_N"
						(effects
							(font
								(size 1.27 1.27)
							)
						)
					)
					(number "13"
						(effects
							(font
								(size 1.27 1.27)
							)
						)
					)
				)
				(pin input line
					(at 25.4 -55.88 180)
					(length 2.54)
					(name "DPEQ0/A1"
						(effects
							(font
								(size 1.27 1.27)
							)
						)
					)
					(number "14"
						(effects
							(font
								(size 1.27 1.27)
							)
						)
					)
				)
				(pin input line
					(at 0 -55.88 0)
					(length 2.54)
					(name "DP2_P"
						(effects
							(font
								(size 1.27 1.27)
							)
						)
					)
					(number "15"
						(effects
							(font
								(size 1.27 1.27)
							)
						)
					)
				)
				(pin input line
					(at 0 -58.42 0)
					(length 2.54)
					(name "DP2_N"
						(effects
							(font
								(size 1.27 1.27)
							)
						)
					)
					(number "16"
						(effects
							(font
								(size 1.27 1.27)
							)
						)
					)
				)
				(pin input line
					(at 25.4 -48.26 180)
					(length 2.54)
					(name "I2C_EN"
						(effects
							(font
								(size 1.27 1.27)
							)
						)
					)
					(number "17"
						(effects
							(font
								(size 1.27 1.27)
							)
						)
					)
				)
				(pin input line
					(at 0 -63.5 0)
					(length 2.54)
					(name "DP3_P"
						(effects
							(font
								(size 1.27 1.27)
							)
						)
					)
					(number "18"
						(effects
							(font
								(size 1.27 1.27)
							)
						)
					)
				)
				(pin input line
					(at 0 -66.04 0)
					(length 2.54)
					(name "DP3_N"
						(effects
							(font
								(size 1.27 1.27)
							)
						)
					)
					(number "19"
						(effects
							(font
								(size 1.27 1.27)
							)
						)
					)
				)
				(pin input line
					(at 25.4 -58.42 180)
					(length 2.54)
					(name "DPEQ1"
						(effects
							(font
								(size 1.27 1.27)
							)
						)
					)
					(number "2"
						(effects
							(font
								(size 1.27 1.27)
							)
						)
					)
				)
				(pin passive line
					(at 0 0 0)
					(length 2.54) hide
					(name "VCC"
						(effects
							(font
								(size 1.27 1.27)
							)
						)
					)
					(number "20"
						(effects
							(font
								(size 1.27 1.27)
							)
						)
					)
				)
				(pin input line
					(at 0 -2.54 0)
					(length 2.54)
					(name "FLIP/SCL"
						(effects
							(font
								(size 1.27 1.27)
							)
						)
					)
					(number "21"
						(effects
							(font
								(size 1.27 1.27)
							)
						)
					)
				)
				(pin input line
					(at 0 -5.08 0)
					(length 2.54)
					(name "CTL0/SDA"
						(effects
							(font
								(size 1.27 1.27)
							)
						)
					)
					(number "22"
						(effects
							(font
								(size 1.27 1.27)
							)
						)
					)
				)
				(pin input line
					(at 0 -7.62 0)
					(length 2.54)
					(name "CTL1/HPDIN"
						(effects
							(font
								(size 1.27 1.27)
							)
						)
					)
					(number "23"
						(effects
							(font
								(size 1.27 1.27)
							)
						)
					)
				)
				(pin bidirectional line
					(at 0 -30.48 0)
					(length 2.54)
					(name "AUX_P"
						(effects
							(font
								(size 1.27 1.27)
							)
						)
					)
					(number "24"
						(effects
							(font
								(size 1.27 1.27)
							)
						)
					)
				)
				(pin bidirectional line
					(at 0 -33.02 0)
					(length 2.54)
					(name "AUX_N"
						(effects
							(font
								(size 1.27 1.27)
							)
						)
					)
					(number "25"
						(effects
							(font
								(size 1.27 1.27)
							)
						)
					)
				)
				(pin bidirectional line
					(at 25.4 -33.02 180)
					(length 2.54)
					(name "SBU2"
						(effects
							(font
								(size 1.27 1.27)
							)
						)
					)
					(number "26"
						(effects
							(font
								(size 1.27 1.27)
							)
						)
					)
				)
				(pin bidirectional line
					(at 25.4 -30.48 180)
					(length 2.54)
					(name "SBU1"
						(effects
							(font
								(size 1.27 1.27)
							)
						)
					)
					(number "27"
						(effects
							(font
								(size 1.27 1.27)
							)
						)
					)
				)
				(pin passive line
					(at 0 0 0)
					(length 2.54) hide
					(name "VCC"
						(effects
							(font
								(size 1.27 1.27)
							)
						)
					)
					(number "28"
						(effects
							(font
								(size 1.27 1.27)
							)
						)
					)
				)
				(pin bidirectional line
					(at 0 -71.12 0)
					(length 2.54)
					(name "CAD_SNK/RSVD1"
						(effects
							(font
								(size 1.27 1.27)
							)
						)
					)
					(number "29"
						(effects
							(font
								(size 1.27 1.27)
							)
						)
					)
					(alternate "CAD_SNK" bidirectional line)
					(alternate "RSVD1" no_connect line)
				)
				(pin input line
					(at 25.4 -53.34 180)
					(length 2.54)
					(name "SSEQ1"
						(effects
							(font
								(size 1.27 1.27)
							)
						)
					)
					(number "3"
						(effects
							(font
								(size 1.27 1.27)
							)
						)
					)
				)
				(pin input line
					(at 25.4 0 180)
					(length 2.54)
					(name "RX1_P"
						(effects
							(font
								(size 1.27 1.27)
							)
						)
					)
					(number "30"
						(effects
							(font
								(size 1.27 1.27)
							)
						)
					)
				)
				(pin input line
					(at 25.4 -2.54 180)
					(length 2.54)
					(name "RX1_N"
						(effects
							(font
								(size 1.27 1.27)
							)
						)
					)
					(number "31"
						(effects
							(font
								(size 1.27 1.27)
							)
						)
					)
				)
				(pin bidirectional line
					(at 0 -73.66 0)
					(length 2.54)
					(name "HPDIN/RSVD2"
						(effects
							(font
								(size 1.27 1.27)
							)
						)
					)
					(number "32"
						(effects
							(font
								(size 1.27 1.27)
							)
						)
					)
					(alternate "HPDIN" bidirectional line)
					(alternate "RSVD2" no_connect line)
				)
				(pin output line
					(at 25.4 -7.62 180)
					(length 2.54)
					(name "TX1_P"
						(effects
							(font
								(size 1.27 1.27)
							)
						)
					)
					(number "33"
						(effects
							(font
								(size 1.27 1.27)
							)
						)
					)
				)
				(pin output line
					(at 25.4 -10.16 180)
					(length 2.54)
					(name "TX1_N"
						(effects
							(font
								(size 1.27 1.27)
							)
						)
					)
					(number "34"
						(effects
							(font
								(size 1.27 1.27)
							)
						)
					)
				)
				(pin input line
					(at 25.4 -63.5 180)
					(length 2.54)
					(name "EQ1"
						(effects
							(font
								(size 1.27 1.27)
							)
						)
					)
					(number "35"
						(effects
							(font
								(size 1.27 1.27)
							)
						)
					)
				)
				(pin output line
					(at 25.4 -25.4 180)
					(length 2.54)
					(name "TX2_N"
						(effects
							(font
								(size 1.27 1.27)
							)
						)
					)
					(number "36"
						(effects
							(font
								(size 1.27 1.27)
							)
						)
					)
				)
				(pin output line
					(at 25.4 -22.86 180)
					(length 2.54)
					(name "TX2_P"
						(effects
							(font
								(size 1.27 1.27)
							)
						)
					)
					(number "37"
						(effects
							(font
								(size 1.27 1.27)
							)
						)
					)
				)
				(pin input line
					(at 25.4 -60.96 180)
					(length 2.54)
					(name "EQ0"
						(effects
							(font
								(size 1.27 1.27)
							)
						)
					)
					(number "38"
						(effects
							(font
								(size 1.27 1.27)
							)
						)
					)
				)
				(pin input line
					(at 25.4 -17.78 180)
					(length 2.54)
					(name "RX2_N"
						(effects
							(font
								(size 1.27 1.27)
							)
						)
					)
					(number "39"
						(effects
							(font
								(size 1.27 1.27)
							)
						)
					)
				)
				(pin output line
					(at 0 -17.78 0)
					(length 2.54)
					(name "SSRX_N"
						(effects
							(font
								(size 1.27 1.27)
							)
						)
					)
					(number "4"
						(effects
							(font
								(size 1.27 1.27)
							)
						)
					)
				)
				(pin input line
					(at 25.4 -15.24 180)
					(length 2.54)
					(name "RX2_P"
						(effects
							(font
								(size 1.27 1.27)
							)
						)
					)
					(number "40"
						(effects
							(font
								(size 1.27 1.27)
							)
						)
					)
				)
				(pin power_in line
					(at 25.4 -73.66 180)
					(length 2.54)
					(name "GND"
						(effects
							(font
								(size 1.27 1.27)
							)
						)
					)
					(number "41"
						(effects
							(font
								(size 1.27 1.27)
							)
						)
					)
				)
				(pin output line
					(at 0 -15.24 0)
					(length 2.54)
					(name "SSRX_P"
						(effects
							(font
								(size 1.27 1.27)
							)
						)
					)
					(number "5"
						(effects
							(font
								(size 1.27 1.27)
							)
						)
					)
				)
				(pin passive line
					(at 0 0 0)
					(length 2.54) hide
					(name "VCC"
						(effects
							(font
								(size 1.27 1.27)
							)
						)
					)
					(number "6"
						(effects
							(font
								(size 1.27 1.27)
							)
						)
					)
				)
				(pin input line
					(at 0 -25.4 0)
					(length 2.54)
					(name "SSTX_N"
						(effects
							(font
								(size 1.27 1.27)
							)
						)
					)
					(number "7"
						(effects
							(font
								(size 1.27 1.27)
							)
						)
					)
				)
				(pin input line
					(at 0 -22.86 0)
					(length 2.54)
					(name "SSTX_P"
						(effects
							(font
								(size 1.27 1.27)
							)
						)
					)
					(number "8"
						(effects
							(font
								(size 1.27 1.27)
							)
						)
					)
				)
				(pin input line
					(at 0 -40.64 0)
					(length 2.54)
					(name "DP0_P"
						(effects
							(font
								(size 1.27 1.27)
							)
						)
					)
					(number "9"
						(effects
							(font
								(size 1.27 1.27)
							)
						)
					)
				)
			)
		)
	(symbol "antmicroInterfaceIOExpanders:PCAL6408A_VQFN"
			(exclude_from_sim no)
			(in_bom yes)
			(on_board yes)
			(property "Reference" "U"
				(at 35.56 -2.54 0)
				(effects
					(font
						(size 1.27 1.27)
						(thickness 0.15)
					)
					(justify left bottom)
				)
			)
			(property "Value" "PCAL6408A_VQFN"
				(at 35.56 -7.62 0)
				(effects
					(font
						(size 1.27 1.27)
						(thickness 0.15)
					)
					(justify left bottom)
					(hide yes)
				)
			)
			(property "Footprint" "antmicro-footprints:VQFN-16-1EP_3x3mm_P0.5mm_EP1.68x1.68mm"
				(at 35.56 -10.16 0)
				(effects
					(font
						(size 1.27 1.27)
						(thickness 0.15)
					)
					(justify left bottom)
					(hide yes)
				)
			)
			(property "Datasheet" "https://eu.mouser.com/datasheet/2/302/PCAL6408A-3139197.pdf"
				(at 35.56 -12.7 0)
				(effects
					(font
						(size 1.27 1.27)
						(thickness 0.15)
					)
					(justify left bottom)
					(hide yes)
				)
			)
			(property "Description" "I/O Expander, 8 bit, I2C, 1.65-5.5 V, HVQFN, 16 Pins"
				(at 0 0 0)
				(effects
					(font
						(size 1.27 1.27)
					)
					(hide yes)
				)
			)
			(property "MPN" "PCAL6408ABSHP"
				(at 35.56 -5.08 0)
				(effects
					(font
						(size 1.27 1.27)
						(thickness 0.15)
					)
					(justify left bottom)
				)
			)
			(property "Manufacturer" "NXP"
				(at 35.56 -15.24 0)
				(effects
					(font
						(size 1.27 1.27)
						(thickness 0.15)
					)
					(justify left bottom)
					(hide yes)
				)
			)
			(property "Author" "Antmicro"
				(at 35.56 -17.78 0)
				(effects
					(font
						(size 1.27 1.27)
						(thickness 0.15)
					)
					(justify left bottom)
					(hide yes)
				)
			)
			(property "License" "Apache-2.0"
				(at 35.56 -20.32 0)
				(effects
					(font
						(size 1.27 1.27)
						(thickness 0.15)
					)
					(justify left bottom)
					(hide yes)
				)
			)
			(property "ki_keywords" "SMT, INTERFACE, IC, I2C"
				(at 0 0 0)
				(effects
					(font
						(size 1.27 1.27)
					)
					(hide yes)
				)
			)
			(symbol "PCAL6408A_VQFN_1_1"
				(rectangle
					(start 2.54 2.54)
					(end 17.78 -25.4)
					(stroke
						(width 0.254)
						(type default)
					)
					(fill
						(type background)
					)
				)
				(pin input line
					(at 0 -16.51 0)
					(length 2.54)
					(name "~{RESET}"
						(effects
							(font
								(size 1.27 1.27)
							)
						)
					)
					(number "1"
						(effects
							(font
								(size 1.27 1.27)
							)
						)
					)
				)
				(pin bidirectional line
					(at 20.32 -17.78 180)
					(length 2.54)
					(name "P7"
						(effects
							(font
								(size 1.27 1.27)
							)
						)
					)
					(number "10"
						(effects
							(font
								(size 1.27 1.27)
							)
						)
					)
				)
				(pin output line
					(at 0 -6.35 0)
					(length 2.54)
					(name "~{INT}"
						(effects
							(font
								(size 1.27 1.27)
							)
						)
					)
					(number "11"
						(effects
							(font
								(size 1.27 1.27)
							)
						)
					)
				)
				(pin input line
					(at 0 -12.7 0)
					(length 2.54)
					(name "SCL"
						(effects
							(font
								(size 1.27 1.27)
							)
						)
					)
					(number "12"
						(effects
							(font
								(size 1.27 1.27)
							)
						)
					)
				)
				(pin bidirectional line
					(at 0 -10.16 0)
					(length 2.54)
					(name "SDA"
						(effects
							(font
								(size 1.27 1.27)
							)
						)
					)
					(number "13"
						(effects
							(font
								(size 1.27 1.27)
							)
						)
					)
				)
				(pin power_in line
					(at 0 0 0)
					(length 2.54)
					(name "VDD_{(P)}"
						(effects
							(font
								(size 1.27 1.27)
							)
						)
					)
					(number "14"
						(effects
							(font
								(size 1.27 1.27)
							)
						)
					)
				)
				(pin power_in line
					(at 0 -2.54 0)
					(length 2.54)
					(name "VDD_{(I2C)}"
						(effects
							(font
								(size 1.27 1.27)
							)
						)
					)
					(number "15"
						(effects
							(font
								(size 1.27 1.27)
							)
						)
					)
				)
				(pin passive line
					(at 0 -20.32 0)
					(length 2.54)
					(name "ADDR"
						(effects
							(font
								(size 1.27 1.27)
							)
						)
					)
					(number "16"
						(effects
							(font
								(size 1.27 1.27)
							)
						)
					)
				)
				(pin power_in line
					(at 20.32 -20.32 180)
					(length 2.54)
					(name "EP"
						(effects
							(font
								(size 1.27 1.27)
							)
						)
					)
					(number "17"
						(effects
							(font
								(size 1.27 1.27)
							)
						)
					)
				)
				(pin bidirectional line
					(at 20.32 0 180)
					(length 2.54)
					(name "P0"
						(effects
							(font
								(size 1.27 1.27)
							)
						)
					)
					(number "2"
						(effects
							(font
								(size 1.27 1.27)
							)
						)
					)
				)
				(pin bidirectional line
					(at 20.32 -2.54 180)
					(length 2.54)
					(name "P1"
						(effects
							(font
								(size 1.27 1.27)
							)
						)
					)
					(number "3"
						(effects
							(font
								(size 1.27 1.27)
							)
						)
					)
				)
				(pin bidirectional line
					(at 20.32 -5.08 180)
					(length 2.54)
					(name "P2"
						(effects
							(font
								(size 1.27 1.27)
							)
						)
					)
					(number "4"
						(effects
							(font
								(size 1.27 1.27)
							)
						)
					)
				)
				(pin bidirectional line
					(at 20.32 -7.62 180)
					(length 2.54)
					(name "P3"
						(effects
							(font
								(size 1.27 1.27)
							)
						)
					)
					(number "5"
						(effects
							(font
								(size 1.27 1.27)
							)
						)
					)
				)
				(pin power_in line
					(at 20.32 -22.86 180)
					(length 2.54)
					(name "V_{ss}"
						(effects
							(font
								(size 1.27 1.27)
							)
						)
					)
					(number "6"
						(effects
							(font
								(size 1.27 1.27)
							)
						)
					)
				)
				(pin bidirectional line
					(at 20.32 -10.16 180)
					(length 2.54)
					(name "P4"
						(effects
							(font
								(size 1.27 1.27)
							)
						)
					)
					(number "7"
						(effects
							(font
								(size 1.27 1.27)
							)
						)
					)
				)
				(pin bidirectional line
					(at 20.32 -12.7 180)
					(length 2.54)
					(name "P5"
						(effects
							(font
								(size 1.27 1.27)
							)
						)
					)
					(number "8"
						(effects
							(font
								(size 1.27 1.27)
							)
						)
					)
				)
				(pin bidirectional line
					(at 20.32 -15.24 180)
					(length 2.54)
					(name "P6"
						(effects
							(font
								(size 1.27 1.27)
							)
						)
					)
					(number "9"
						(effects
							(font
								(size 1.27 1.27)
							)
						)
					)
				)
			)
		)
	(symbol "antmicroLEDIndicationDiscrete:LED_G_0603_LTST-C190GKT"
			(pin_numbers hide)
			(pin_names hide)
			(exclude_from_sim no)
			(in_bom yes)
			(on_board yes)
			(property "Reference" "D"
				(at 22.86 -2.54 0)
				(effects
					(font
						(size 1.27 1.27)
						(thickness 0.15)
					)
					(justify left bottom)
				)
			)
			(property "Value" "LED_G_0603_LTST-C190GKT"
				(at 22.86 -7.62 0)
				(effects
					(font
						(size 1.27 1.27)
						(thickness 0.15)
					)
					(justify left bottom)
					(hide yes)
				)
			)
			(property "Footprint" "antmicro-footprints:LED_0603_1608Metric_G"
				(at 22.86 -10.16 0)
				(effects
					(font
						(size 1.27 1.27)
						(thickness 0.15)
					)
					(justify left bottom)
					(hide yes)
				)
			)
			(property "Datasheet" "https://media.digikey.com/pdf/Data%20Sheets/Lite-On%20PDFs/LTST-C190GKT.pdf"
				(at 22.86 -12.7 0)
				(effects
					(font
						(size 1.27 1.27)
						(thickness 0.15)
					)
					(justify left bottom)
					(hide yes)
				)
			)
			(property "Description" "LED, Green, SMD, 0603, 20 mA, 2.1 V, 569 nm"
				(at 0 0 0)
				(effects
					(font
						(size 1.27 1.27)
					)
					(hide yes)
				)
			)
			(property "MPN" "LTST-C190GKT"
				(at 22.86 -15.24 0)
				(effects
					(font
						(size 1.27 1.27)
						(thickness 0.15)
					)
					(justify left bottom)
					(hide yes)
				)
			)
			(property "Manufacturer" "Lite-On"
				(at 22.86 -17.78 0)
				(effects
					(font
						(size 1.27 1.27)
						(thickness 0.15)
					)
					(justify left bottom)
					(hide yes)
				)
			)
			(property "Color" "Green"
				(at 22.86 -5.08 0)
				(effects
					(font
						(size 1.27 1.27)
					)
					(justify left bottom)
				)
			)
			(property "Author" "Antmicro"
				(at 22.86 -20.32 0)
				(effects
					(font
						(size 1.27 1.27)
						(thickness 0.15)
					)
					(justify left bottom)
					(hide yes)
				)
			)
			(property "License" "Apache-2.0"
				(at 22.86 -22.86 0)
				(effects
					(font
						(size 1.27 1.27)
						(thickness 0.15)
					)
					(justify left bottom)
					(hide yes)
				)
			)
			(property "ki_keywords" "SMT, DIODE, SEMICONDUCTOR, LED"
				(at 0 0 0)
				(effects
					(font
						(size 1.27 1.27)
					)
					(hide yes)
				)
			)
			(symbol "LED_G_0603_LTST-C190GKT_0_1"
				(polyline
					(pts
						(xy 1.905 0) (xy 0.635 0)
					)
					(stroke
						(width 0)
						(type default)
					)
					(fill
						(type none)
					)
				)
				(polyline
					(pts
						(xy 4.445 0) (xy 3.175 0)
					)
					(stroke
						(width 0)
						(type default)
					)
					(fill
						(type none)
					)
				)
			)
			(symbol "LED_G_0603_LTST-C190GKT_1_1"
				(polyline
					(pts
						(xy 1.778 1.016) (xy 1.778 -1.016)
					)
					(stroke
						(width 0.254)
						(type default)
					)
					(fill
						(type none)
					)
				)
				(polyline
					(pts
						(xy 3.302 1.016) (xy 3.302 -1.016) (xy 1.778 0) (xy 3.302 1.016)
					)
					(stroke
						(width 0.254)
						(type default)
					)
					(fill
						(type outline)
					)
				)
				(polyline
					(pts
						(xy 1.143 2.286) (xy 1.143 1.778) (xy 1.143 2.286) (xy 1.651 2.286) (xy 1.143 2.286) (xy 2.159 1.27)
					)
					(stroke
						(width 0.254)
						(type default)
					)
					(fill
						(type none)
					)
				)
				(polyline
					(pts
						(xy 2.159 2.54) (xy 2.159 2.032) (xy 2.159 2.54) (xy 2.667 2.54) (xy 2.159 2.54) (xy 3.048 1.651)
					)
					(stroke
						(width 0.254)
						(type default)
					)
					(fill
						(type none)
					)
				)
				(pin passive line
					(at 0 0 0)
					(length 0.635)
					(name "C"
						(effects
							(font
								(size 1.27 1.27)
							)
						)
					)
					(number "1"
						(effects
							(font
								(size 1.27 1.27)
							)
						)
					)
				)
				(pin passive line
					(at 5.08 0 180)
					(length 0.635)
					(name "A"
						(effects
							(font
								(size 1.27 1.27)
							)
						)
					)
					(number "2"
						(effects
							(font
								(size 1.27 1.27)
							)
						)
					)
				)
			)
		)
	(symbol "antmicroLogicBuffersDriversReceiversTransceivers:74LVC2G07_SOT457"
			(exclude_from_sim no)
			(in_bom yes)
			(on_board yes)
			(property "Reference" "U"
				(at 29.21 -3.81 0)
				(effects
					(font
						(size 1.27 1.27)
						(thickness 0.15)
					)
					(justify left bottom)
				)
			)
			(property "Value" "74LVC2G07_SOT457"
				(at 29.21 -6.35 0)
				(effects
					(font
						(size 1.27 1.27)
						(thickness 0.15)
					)
					(justify left bottom)
					(hide yes)
				)
			)
			(property "Footprint" "antmicro-footprints:SC-74-6_1.5x2.9mm_P0.95mm"
				(at 29.21 -8.89 0)
				(effects
					(font
						(size 1.27 1.27)
						(thickness 0.15)
					)
					(justify left bottom)
					(hide yes)
				)
			)
			(property "Datasheet" "https://www.tme.eu/Document/2ad9356043a4952b9021ef50162f8c34/74LVC2G07.pdf"
				(at 29.21 -11.43 0)
				(effects
					(font
						(size 1.27 1.27)
						(thickness 0.15)
					)
					(justify left bottom)
					(hide yes)
				)
			)
			(property "Description" "Buffer, Non-Inverting 2 Element 1 Bit per Element Open Drain Output 6-TSOP"
				(at 0 0 0)
				(effects
					(font
						(size 1.27 1.27)
					)
					(hide yes)
				)
			)
			(property "Manufacturer" "Nexperia"
				(at 29.21 -13.97 0)
				(effects
					(font
						(size 1.27 1.27)
						(thickness 0.15)
					)
					(justify left bottom)
					(hide yes)
				)
			)
			(property "MPN" "74LVC2G07GV,125"
				(at 29.21 -16.51 0)
				(effects
					(font
						(size 1.27 1.27)
						(thickness 0.15)
					)
					(justify left bottom)
				)
			)
			(property "Author" "Antmicro"
				(at 29.21 -19.05 0)
				(effects
					(font
						(size 1.27 1.27)
						(thickness 0.15)
					)
					(justify left bottom)
					(hide yes)
				)
			)
			(property "License" "Apache-2.0"
				(at 29.21 -21.59 0)
				(effects
					(font
						(size 1.27 1.27)
						(thickness 0.15)
					)
					(justify left bottom)
					(hide yes)
				)
			)
			(property "ki_keywords" "SMT, LOGIC, IC, BUFFER, TRANSCEIVER, DRIVER"
				(at 0 0 0)
				(effects
					(font
						(size 1.27 1.27)
					)
					(hide yes)
				)
			)
			(property "ki_fp_filters" "SG-74 SOT23-6 TSOP6 SOT457"
				(at 0 0 0)
				(effects
					(font
						(size 1.27 1.27)
					)
					(hide yes)
				)
			)
			(symbol "74LVC2G07_SOT457_1_1"
				(polyline
					(pts
						(xy 2.54 -2.54) (xy 3.81 -2.54)
					)
					(stroke
						(width 0.254)
						(type default)
					)
					(fill
						(type background)
					)
				)
				(polyline
					(pts
						(xy 3.81 -8.89) (xy 2.54 -8.89)
					)
					(stroke
						(width 0.254)
						(type default)
					)
					(fill
						(type background)
					)
				)
				(polyline
					(pts
						(xy 5.08 -9.525) (xy 6.35 -9.525)
					)
					(stroke
						(width 0.254)
						(type default)
					)
					(fill
						(type background)
					)
				)
				(polyline
					(pts
						(xy 5.08 -3.175) (xy 6.35 -3.175)
					)
					(stroke
						(width 0.254)
						(type default)
					)
					(fill
						(type background)
					)
				)
				(polyline
					(pts
						(xy 10.16 -8.89) (xy 8.89 -8.89)
					)
					(stroke
						(width 0.254)
						(type default)
					)
					(fill
						(type background)
					)
				)
				(polyline
					(pts
						(xy 10.16 -2.54) (xy 8.89 -2.54)
					)
					(stroke
						(width 0.254)
						(type default)
					)
					(fill
						(type background)
					)
				)
				(polyline
					(pts
						(xy 3.81 -6.35) (xy 8.89 -8.89) (xy 3.81 -11.43) (xy 3.81 -6.35)
					)
					(stroke
						(width 0.254)
						(type default)
					)
					(fill
						(type background)
					)
				)
				(polyline
					(pts
						(xy 3.81 0) (xy 8.89 -2.54) (xy 3.81 -5.08) (xy 3.81 0)
					)
					(stroke
						(width 0.254)
						(type default)
					)
					(fill
						(type background)
					)
				)
				(polyline
					(pts
						(xy 5.08 -8.89) (xy 5.715 -8.255) (xy 6.35 -8.89) (xy 5.715 -9.525) (xy 5.08 -8.89)
					)
					(stroke
						(width 0.254)
						(type default)
					)
					(fill
						(type background)
					)
				)
				(polyline
					(pts
						(xy 5.08 -2.54) (xy 5.715 -1.905) (xy 6.35 -2.54) (xy 5.715 -3.175) (xy 5.08 -2.54)
					)
					(stroke
						(width 0.254)
						(type default)
					)
					(fill
						(type background)
					)
				)
				(rectangle
					(start 2.54 3.81)
					(end 10.16 -15.24)
					(stroke
						(width 0.254)
						(type default)
					)
					(fill
						(type background)
					)
				)
				(pin input line
					(at 0 -2.54 0)
					(length 2.54)
					(name "~"
						(effects
							(font
								(size 1.27 1.27)
							)
						)
					)
					(number "1"
						(effects
							(font
								(size 1.27 1.27)
							)
						)
					)
				)
				(pin power_in line
					(at 0 -12.7 0)
					(length 2.54)
					(name "GND"
						(effects
							(font
								(size 1.27 1.27)
							)
						)
					)
					(number "2"
						(effects
							(font
								(size 1.27 1.27)
							)
						)
					)
				)
				(pin input line
					(at 0 -8.89 0)
					(length 2.54)
					(name "~"
						(effects
							(font
								(size 1.27 1.27)
							)
						)
					)
					(number "3"
						(effects
							(font
								(size 1.27 1.27)
							)
						)
					)
				)
				(pin output line
					(at 12.7 -8.89 180)
					(length 2.54)
					(name "~"
						(effects
							(font
								(size 1.27 1.27)
							)
						)
					)
					(number "4"
						(effects
							(font
								(size 1.27 1.27)
							)
						)
					)
				)
				(pin power_in line
					(at 0 1.27 0)
					(length 2.54)
					(name "V_{CC}"
						(effects
							(font
								(size 1.27 1.27)
							)
						)
					)
					(number "5"
						(effects
							(font
								(size 1.27 1.27)
							)
						)
					)
				)
				(pin output line
					(at 12.7 -2.54 180)
					(length 2.54)
					(name "~"
						(effects
							(font
								(size 1.27 1.27)
							)
						)
					)
					(number "6"
						(effects
							(font
								(size 1.27 1.27)
							)
						)
					)
				)
			)
		)
	(symbol "antmicroLogicBuffersDriversReceiversTransceivers:74LVC2G14_SOT457"
			(exclude_from_sim no)
			(in_bom yes)
			(on_board yes)
			(property "Reference" "U"
				(at 30.48 -6.35 0)
				(effects
					(font
						(size 1.27 1.27)
						(thickness 0.15)
					)
					(justify left bottom)
				)
			)
			(property "Value" "74LVC2G14_SOT457"
				(at 30.48 -8.89 0)
				(effects
					(font
						(size 1.27 1.27)
						(thickness 0.15)
					)
					(justify left bottom)
					(hide yes)
				)
			)
			(property "Footprint" "antmicro-footprints:SOT-23-6"
				(at 30.48 -11.43 0)
				(effects
					(font
						(size 1.27 1.27)
						(thickness 0.15)
					)
					(justify left bottom)
					(hide yes)
				)
			)
			(property "Datasheet" "https://assets.nexperia.com/documents/data-sheet/74LVC2G14.pdf"
				(at 30.48 -13.97 0)
				(effects
					(font
						(size 1.27 1.27)
						(thickness 0.15)
					)
					(justify left bottom)
					(hide yes)
				)
			)
			(property "Description" "Logic IC, Inverter, Dual, 1 Inputs, 6 Pins, TSOP, 74LVC2G14"
				(at 0 0 0)
				(effects
					(font
						(size 1.27 1.27)
					)
					(hide yes)
				)
			)
			(property "MPN" "74LVC2G14GV,125"
				(at 30.48 -16.51 0)
				(effects
					(font
						(size 1.27 1.27)
						(thickness 0.15)
					)
					(justify left bottom)
				)
			)
			(property "Manufacturer" "Nexperia"
				(at 30.48 -19.05 0)
				(effects
					(font
						(size 1.27 1.27)
						(thickness 0.15)
					)
					(justify left bottom)
					(hide yes)
				)
			)
			(property "Author" "Antmicro"
				(at 30.48 -21.59 0)
				(effects
					(font
						(size 1.27 1.27)
						(thickness 0.15)
					)
					(justify left bottom)
					(hide yes)
				)
			)
			(property "License" "Apache-2.0"
				(at 30.48 -24.13 0)
				(effects
					(font
						(size 1.27 1.27)
						(thickness 0.15)
					)
					(justify left bottom)
					(hide yes)
				)
			)
			(property "ki_keywords" "SMT, LOGIC, IC, BUFFER, TRANSCEIVER, DRIVER"
				(at 0 0 0)
				(effects
					(font
						(size 1.27 1.27)
					)
					(hide yes)
				)
			)
			(symbol "74LVC2G14_SOT457_1_1"
				(polyline
					(pts
						(xy 2.54 0) (xy 5.08 0)
					)
					(stroke
						(width 0.254)
						(type default)
					)
					(fill
						(type background)
					)
				)
				(polyline
					(pts
						(xy 5.08 -7.62) (xy 2.54 -7.62)
					)
					(stroke
						(width 0.254)
						(type default)
					)
					(fill
						(type background)
					)
				)
				(polyline
					(pts
						(xy 12.7 -7.62) (xy 11.176 -7.62)
					)
					(stroke
						(width 0.254)
						(type default)
					)
					(fill
						(type background)
					)
				)
				(polyline
					(pts
						(xy 12.7 0) (xy 11.176 0)
					)
					(stroke
						(width 0.254)
						(type default)
					)
					(fill
						(type background)
					)
				)
				(polyline
					(pts
						(xy 5.08 -5.08) (xy 5.08 -10.16) (xy 10.16 -7.62) (xy 5.08 -5.08)
					)
					(stroke
						(width 0.254)
						(type default)
					)
					(fill
						(type background)
					)
				)
				(polyline
					(pts
						(xy 5.08 2.54) (xy 5.08 -2.54) (xy 10.16 0) (xy 5.08 2.54)
					)
					(stroke
						(width 0.254)
						(type default)
					)
					(fill
						(type background)
					)
				)
				(polyline
					(pts
						(xy 6.858 -7.112) (xy 6.35 -7.112) (xy 6.35 -8.382) (xy 5.842 -8.382)
					)
					(stroke
						(width 0.254)
						(type default)
					)
					(fill
						(type background)
					)
				)
				(polyline
					(pts
						(xy 6.858 0.508) (xy 6.35 0.508) (xy 6.35 -0.762) (xy 5.842 -0.762)
					)
					(stroke
						(width 0.254)
						(type default)
					)
					(fill
						(type background)
					)
				)
				(polyline
					(pts
						(xy 7.366 -7.112) (xy 6.858 -7.112) (xy 6.858 -8.382) (xy 6.35 -8.382)
					)
					(stroke
						(width 0.254)
						(type default)
					)
					(fill
						(type background)
					)
				)
				(polyline
					(pts
						(xy 7.366 0.508) (xy 6.858 0.508) (xy 6.858 -0.762) (xy 6.35 -0.762)
					)
					(stroke
						(width 0.254)
						(type default)
					)
					(fill
						(type background)
					)
				)
				(rectangle
					(start 2.54 6.35)
					(end 12.7 -13.97)
					(stroke
						(width 0.254)
						(type default)
					)
					(fill
						(type background)
					)
				)
				(circle
					(center 10.668 -7.62)
					(radius 0.508)
					(stroke
						(width 0.254)
						(type default)
					)
					(fill
						(type background)
					)
				)
				(circle
					(center 10.668 0)
					(radius 0.508)
					(stroke
						(width 0.254)
						(type default)
					)
					(fill
						(type background)
					)
				)
				(pin input line
					(at 0 0 0)
					(length 2.54)
					(name "~"
						(effects
							(font
								(size 1.27 1.27)
							)
						)
					)
					(number "1"
						(effects
							(font
								(size 1.27 1.27)
							)
						)
					)
				)
				(pin power_in line
					(at 7.62 -16.51 90)
					(length 2.54)
					(name "GND"
						(effects
							(font
								(size 1.27 1.27)
							)
						)
					)
					(number "2"
						(effects
							(font
								(size 1.27 1.27)
							)
						)
					)
				)
				(pin input line
					(at 0 -7.62 0)
					(length 2.54)
					(name "~"
						(effects
							(font
								(size 1.27 1.27)
							)
						)
					)
					(number "3"
						(effects
							(font
								(size 1.27 1.27)
							)
						)
					)
				)
				(pin output line
					(at 15.24 -7.62 180)
					(length 2.54)
					(name "~"
						(effects
							(font
								(size 1.27 1.27)
							)
						)
					)
					(number "4"
						(effects
							(font
								(size 1.27 1.27)
							)
						)
					)
				)
				(pin power_in line
					(at 7.62 8.89 270)
					(length 2.54)
					(name "VCC"
						(effects
							(font
								(size 1.27 1.27)
							)
						)
					)
					(number "5"
						(effects
							(font
								(size 1.27 1.27)
							)
						)
					)
				)
				(pin output line
					(at 15.24 0 180)
					(length 2.54)
					(name "~"
						(effects
							(font
								(size 1.27 1.27)
							)
						)
					)
					(number "6"
						(effects
							(font
								(size 1.27 1.27)
							)
						)
					)
				)
			)
		)
	(symbol "antmicroLogicGatesandInverters:74LVC1G175_SOT457"
			(exclude_from_sim no)
			(in_bom yes)
			(on_board yes)
			(property "Reference" "U"
				(at 30.48 -5.08 0)
				(effects
					(font
						(size 1.27 1.27)
						(thickness 0.15)
					)
					(justify left bottom)
				)
			)
			(property "Value" "74LVC1G175_SOT457"
				(at 30.48 -7.62 0)
				(effects
					(font
						(size 1.27 1.27)
						(thickness 0.15)
					)
					(justify left bottom)
					(hide yes)
				)
			)
			(property "Footprint" "antmicro-footprints:SOT-23-6"
				(at 30.48 -10.16 0)
				(effects
					(font
						(size 1.27 1.27)
						(thickness 0.15)
					)
					(justify left bottom)
					(hide yes)
				)
			)
			(property "Datasheet" "https://www.mouser.com/datasheet/2/916/74LVC1G175-1480578.pdf"
				(at 30.48 -12.7 0)
				(effects
					(font
						(size 1.27 1.27)
						(thickness 0.15)
					)
					(justify left bottom)
					(hide yes)
				)
			)
			(property "Description" "Flip-Flop, Non Inverted, Positive Edge, 74LVC1G175, D, 300 MHz, 50 mA, SC-74"
				(at 0 0 0)
				(effects
					(font
						(size 1.27 1.27)
					)
					(hide yes)
				)
			)
			(property "MPN" "74LVC1G175GV,125"
				(at 30.48 -15.24 0)
				(effects
					(font
						(size 1.27 1.27)
						(thickness 0.15)
					)
					(justify left bottom)
				)
			)
			(property "Manufacturer" "Nexperia"
				(at 30.48 -17.78 0)
				(effects
					(font
						(size 1.27 1.27)
						(thickness 0.15)
					)
					(justify left bottom)
					(hide yes)
				)
			)
			(property "Author" "Antmicro"
				(at 30.48 -20.32 0)
				(effects
					(font
						(size 1.27 1.27)
						(thickness 0.15)
					)
					(justify left bottom)
					(hide yes)
				)
			)
			(property "License" "Apache-2.0"
				(at 30.48 -22.86 0)
				(effects
					(font
						(size 1.27 1.27)
						(thickness 0.15)
					)
					(justify left bottom)
					(hide yes)
				)
			)
			(property "ki_keywords" "SMT, LOGIC, IC, GATE"
				(at 0 0 0)
				(effects
					(font
						(size 1.27 1.27)
					)
					(hide yes)
				)
			)
			(symbol "74LVC1G175_SOT457_1_1"
				(rectangle
					(start 2.54 2.54)
					(end 12.7 -7.62)
					(stroke
						(width 0.254)
						(type default)
					)
					(fill
						(type background)
					)
				)
				(pin input clock
					(at 0 -2.54 0)
					(length 2.54)
					(name "CLK"
						(effects
							(font
								(size 1.27 1.27)
							)
						)
					)
					(number "1"
						(effects
							(font
								(size 1.27 1.27)
							)
						)
					)
				)
				(pin power_in line
					(at 7.62 -10.16 90)
					(length 2.54)
					(name "GND"
						(effects
							(font
								(size 1.27 1.27)
							)
						)
					)
					(number "2"
						(effects
							(font
								(size 1.27 1.27)
							)
						)
					)
				)
				(pin input line
					(at 0 0 0)
					(length 2.54)
					(name "D"
						(effects
							(font
								(size 1.27 1.27)
							)
						)
					)
					(number "3"
						(effects
							(font
								(size 1.27 1.27)
							)
						)
					)
				)
				(pin output line
					(at 15.24 0 180)
					(length 2.54)
					(name "Q"
						(effects
							(font
								(size 1.27 1.27)
							)
						)
					)
					(number "4"
						(effects
							(font
								(size 1.27 1.27)
							)
						)
					)
				)
				(pin power_in line
					(at 7.62 5.08 270)
					(length 2.54)
					(name "VCC"
						(effects
							(font
								(size 1.27 1.27)
							)
						)
					)
					(number "5"
						(effects
							(font
								(size 1.27 1.27)
							)
						)
					)
				)
				(pin input line
					(at 0 -5.08 0)
					(length 2.54)
					(name "~{CLR}"
						(effects
							(font
								(size 1.27 1.27)
							)
						)
					)
					(number "6"
						(effects
							(font
								(size 1.27 1.27)
							)
						)
					)
				)
			)
		)
	(symbol "antmicroLogicSignalSwitchesMultiplexersDecoders:PI4MSD5V9548AZDEX"
			(exclude_from_sim no)
			(in_bom yes)
			(on_board yes)
			(property "Reference" "U"
				(at 35.56 -2.54 0)
				(effects
					(font
						(size 1.27 1.27)
						(thickness 0.15)
					)
					(justify left bottom)
				)
			)
			(property "Value" "PI4MSD5V9548AZDEX"
				(at 35.56 -5.08 0)
				(effects
					(font
						(size 1.27 1.27)
						(thickness 0.15)
					)
					(justify left bottom)
					(hide yes)
				)
			)
			(property "Footprint" "antmicro-footprints:VQFN-24-1EP_3.8x3.8x1.0mm_P0.5mm"
				(at 35.56 -7.62 0)
				(effects
					(font
						(size 1.27 1.27)
						(thickness 0.15)
					)
					(justify left bottom)
					(hide yes)
				)
			)
			(property "Datasheet" "https://www.mouser.com/datasheet/2/115/DIOD_S_A0003139195_1-2542233.pdf"
				(at 35.56 -10.16 0)
				(effects
					(font
						(size 1.27 1.27)
						(thickness 0.15)
					)
					(justify left bottom)
					(hide yes)
				)
			)
			(property "Description" "Logic signal switch/multiplexer/decoder"
				(at 0 0 0)
				(effects
					(font
						(size 1.27 1.27)
					)
					(hide yes)
				)
			)
			(property "Manufacturer" "Diodes Incorporated"
				(at 35.56 -12.7 0)
				(effects
					(font
						(size 1.27 1.27)
						(thickness 0.15)
					)
					(justify left bottom)
					(hide yes)
				)
			)
			(property "MPN" "PI4MSD5V9548AZDEX"
				(at 35.56 -15.24 0)
				(effects
					(font
						(size 1.27 1.27)
						(thickness 0.15)
					)
					(justify left bottom)
				)
			)
			(property "Author" "Antmicro"
				(at 35.56 -17.78 0)
				(effects
					(font
						(size 1.27 1.27)
						(thickness 0.15)
					)
					(justify left bottom)
					(hide yes)
				)
			)
			(property "License" "Apache-2.0"
				(at 35.56 -20.32 0)
				(effects
					(font
						(size 1.27 1.27)
						(thickness 0.15)
					)
					(justify left bottom)
					(hide yes)
				)
			)
			(property "ki_keywords" "SMT, MUX, IC, I2C"
				(at 0 0 0)
				(effects
					(font
						(size 1.27 1.27)
					)
					(hide yes)
				)
			)
			(symbol "PI4MSD5V9548AZDEX_1_1"
				(rectangle
					(start 17.78 -58.42)
					(end 2.54 2.54)
					(stroke
						(width 0.254)
						(type default)
					)
					(fill
						(type background)
					)
				)
				(pin bidirectional line
					(at 20.32 0 180)
					(length 2.54)
					(name "SD0"
						(effects
							(font
								(size 1.27 1.27)
							)
						)
					)
					(number "1"
						(effects
							(font
								(size 1.27 1.27)
							)
						)
					)
				)
				(pin bidirectional line
					(at 20.32 -30.48 180)
					(length 2.54)
					(name "SD4"
						(effects
							(font
								(size 1.27 1.27)
							)
						)
					)
					(number "10"
						(effects
							(font
								(size 1.27 1.27)
							)
						)
					)
				)
				(pin bidirectional line
					(at 20.32 -33.02 180)
					(length 2.54)
					(name "SC4"
						(effects
							(font
								(size 1.27 1.27)
							)
						)
					)
					(number "11"
						(effects
							(font
								(size 1.27 1.27)
							)
						)
					)
				)
				(pin bidirectional line
					(at 20.32 -38.1 180)
					(length 2.54)
					(name "SD5"
						(effects
							(font
								(size 1.27 1.27)
							)
						)
					)
					(number "12"
						(effects
							(font
								(size 1.27 1.27)
							)
						)
					)
				)
				(pin bidirectional line
					(at 20.32 -40.64 180)
					(length 2.54)
					(name "SC5"
						(effects
							(font
								(size 1.27 1.27)
							)
						)
					)
					(number "13"
						(effects
							(font
								(size 1.27 1.27)
							)
						)
					)
				)
				(pin bidirectional line
					(at 20.32 -45.72 180)
					(length 2.54)
					(name "SD6"
						(effects
							(font
								(size 1.27 1.27)
							)
						)
					)
					(number "14"
						(effects
							(font
								(size 1.27 1.27)
							)
						)
					)
				)
				(pin bidirectional line
					(at 20.32 -48.26 180)
					(length 2.54)
					(name "SC6"
						(effects
							(font
								(size 1.27 1.27)
							)
						)
					)
					(number "15"
						(effects
							(font
								(size 1.27 1.27)
							)
						)
					)
				)
				(pin bidirectional line
					(at 20.32 -53.34 180)
					(length 2.54)
					(name "SD7"
						(effects
							(font
								(size 1.27 1.27)
							)
						)
					)
					(number "16"
						(effects
							(font
								(size 1.27 1.27)
							)
						)
					)
				)
				(pin bidirectional line
					(at 20.32 -55.88 180)
					(length 2.54)
					(name "SC7"
						(effects
							(font
								(size 1.27 1.27)
							)
						)
					)
					(number "17"
						(effects
							(font
								(size 1.27 1.27)
							)
						)
					)
				)
				(pin input line
					(at 0 -48.26 0)
					(length 2.54)
					(name "A2"
						(effects
							(font
								(size 1.27 1.27)
							)
						)
					)
					(number "18"
						(effects
							(font
								(size 1.27 1.27)
							)
						)
					)
				)
				(pin bidirectional line
					(at 0 -15.24 0)
					(length 2.54)
					(name "SCL"
						(effects
							(font
								(size 1.27 1.27)
							)
						)
					)
					(number "19"
						(effects
							(font
								(size 1.27 1.27)
							)
						)
					)
				)
				(pin bidirectional line
					(at 20.32 -2.54 180)
					(length 2.54)
					(name "SC0"
						(effects
							(font
								(size 1.27 1.27)
							)
						)
					)
					(number "2"
						(effects
							(font
								(size 1.27 1.27)
							)
						)
					)
				)
				(pin bidirectional line
					(at 0 -12.7 0)
					(length 2.54)
					(name "SDA"
						(effects
							(font
								(size 1.27 1.27)
							)
						)
					)
					(number "20"
						(effects
							(font
								(size 1.27 1.27)
							)
						)
					)
				)
				(pin power_in line
					(at 0 0 0)
					(length 2.54)
					(name "VCC"
						(effects
							(font
								(size 1.27 1.27)
							)
						)
					)
					(number "21"
						(effects
							(font
								(size 1.27 1.27)
							)
						)
					)
				)
				(pin input line
					(at 0 -43.18 0)
					(length 2.54)
					(name "A0"
						(effects
							(font
								(size 1.27 1.27)
							)
						)
					)
					(number "22"
						(effects
							(font
								(size 1.27 1.27)
							)
						)
					)
				)
				(pin input line
					(at 0 -45.72 0)
					(length 2.54)
					(name "A1"
						(effects
							(font
								(size 1.27 1.27)
							)
						)
					)
					(number "23"
						(effects
							(font
								(size 1.27 1.27)
							)
						)
					)
				)
				(pin input line
					(at 0 -38.1 0)
					(length 2.54)
					(name "~{RESET}"
						(effects
							(font
								(size 1.27 1.27)
							)
						)
					)
					(number "24"
						(effects
							(font
								(size 1.27 1.27)
							)
						)
					)
				)
				(pin power_in line
					(at 0 -53.34 0)
					(length 2.54)
					(name "EP"
						(effects
							(font
								(size 1.27 1.27)
							)
						)
					)
					(number "25"
						(effects
							(font
								(size 1.27 1.27)
							)
						)
					)
				)
				(pin bidirectional line
					(at 20.32 -7.62 180)
					(length 2.54)
					(name "SD1"
						(effects
							(font
								(size 1.27 1.27)
							)
						)
					)
					(number "3"
						(effects
							(font
								(size 1.27 1.27)
							)
						)
					)
				)
				(pin bidirectional line
					(at 20.32 -10.16 180)
					(length 2.54)
					(name "SC1"
						(effects
							(font
								(size 1.27 1.27)
							)
						)
					)
					(number "4"
						(effects
							(font
								(size 1.27 1.27)
							)
						)
					)
				)
				(pin bidirectional line
					(at 20.32 -15.24 180)
					(length 2.54)
					(name "SD2"
						(effects
							(font
								(size 1.27 1.27)
							)
						)
					)
					(number "5"
						(effects
							(font
								(size 1.27 1.27)
							)
						)
					)
				)
				(pin bidirectional line
					(at 20.32 -17.78 180)
					(length 2.54)
					(name "SC2"
						(effects
							(font
								(size 1.27 1.27)
							)
						)
					)
					(number "6"
						(effects
							(font
								(size 1.27 1.27)
							)
						)
					)
				)
				(pin bidirectional line
					(at 20.32 -22.86 180)
					(length 2.54)
					(name "SD3"
						(effects
							(font
								(size 1.27 1.27)
							)
						)
					)
					(number "7"
						(effects
							(font
								(size 1.27 1.27)
							)
						)
					)
				)
				(pin bidirectional line
					(at 20.32 -25.4 180)
					(length 2.54)
					(name "SC3"
						(effects
							(font
								(size 1.27 1.27)
							)
						)
					)
					(number "8"
						(effects
							(font
								(size 1.27 1.27)
							)
						)
					)
				)
				(pin power_in line
					(at 0 -55.88 0)
					(length 2.54)
					(name "GND"
						(effects
							(font
								(size 1.27 1.27)
							)
						)
					)
					(number "9"
						(effects
							(font
								(size 1.27 1.27)
							)
						)
					)
				)
			)
		)
	(symbol "antmicroLogicTranslatorsLevelShifters:NTS0102_XSON"
			(exclude_from_sim no)
			(in_bom yes)
			(on_board yes)
			(property "Reference" "U"
				(at 35.56 -2.54 0)
				(effects
					(font
						(size 1.27 1.27)
						(thickness 0.15)
					)
					(justify left bottom)
				)
			)
			(property "Value" "NTS0102_XSON"
				(at 35.56 -7.62 0)
				(effects
					(font
						(size 1.27 1.27)
						(thickness 0.15)
					)
					(justify left bottom)
					(hide yes)
				)
			)
			(property "Footprint" "antmicro-footprints:XSON-8_1x1.95mm_P0.5mm"
				(at 35.56 -10.16 0)
				(effects
					(font
						(size 1.27 1.27)
						(thickness 0.15)
					)
					(justify left bottom)
					(hide yes)
				)
			)
			(property "Datasheet" "http://www.farnell.com/datasheets/1760723.pdf"
				(at 35.56 -12.7 0)
				(effects
					(font
						(size 1.27 1.27)
						(thickness 0.15)
					)
					(justify left bottom)
					(hide yes)
				)
			)
			(property "Description" "Transceiver, 1.65 V to 3.6 V, XSON-8"
				(at 0 0 0)
				(effects
					(font
						(size 1.27 1.27)
					)
					(hide yes)
				)
			)
			(property "MPN" "NTS0102GT"
				(at 35.56 -5.08 0)
				(effects
					(font
						(size 1.27 1.27)
						(thickness 0.15)
					)
					(justify left bottom)
				)
			)
			(property "Manufacturer" "NXP"
				(at 35.56 -15.24 0)
				(effects
					(font
						(size 1.27 1.27)
						(thickness 0.15)
					)
					(justify left bottom)
					(hide yes)
				)
			)
			(property "Author" "Antmicro"
				(at 35.56 -17.78 0)
				(effects
					(font
						(size 1.27 1.27)
						(thickness 0.15)
					)
					(justify left bottom)
					(hide yes)
				)
			)
			(property "License" "Apache-2.0"
				(at 35.56 -20.32 0)
				(effects
					(font
						(size 1.27 1.27)
						(thickness 0.15)
					)
					(justify left bottom)
					(hide yes)
				)
			)
			(property "ki_keywords" "SMT, LEVEL-SHIFTER, IC, LOGIC"
				(at 0 0 0)
				(effects
					(font
						(size 1.27 1.27)
					)
					(hide yes)
				)
			)
			(symbol "NTS0102_XSON_1_1"
				(rectangle
					(start 2.54 2.54)
					(end 17.78 -10.16)
					(stroke
						(width 0.254)
						(type default)
					)
					(fill
						(type background)
					)
				)
				(pin bidirectional line
					(at 20.32 -5.08 180)
					(length 2.54)
					(name "B_{2}"
						(effects
							(font
								(size 1.27 1.27)
							)
						)
					)
					(number "1"
						(effects
							(font
								(size 1.27 1.27)
							)
						)
					)
				)
				(pin power_in line
					(at 20.32 -7.62 180)
					(length 2.54)
					(name "GND"
						(effects
							(font
								(size 1.27 1.27)
							)
						)
					)
					(number "2"
						(effects
							(font
								(size 1.27 1.27)
							)
						)
					)
				)
				(pin power_in line
					(at 0 0 0)
					(length 2.54)
					(name "VCC_{A}"
						(effects
							(font
								(size 1.27 1.27)
							)
						)
					)
					(number "3"
						(effects
							(font
								(size 1.27 1.27)
							)
						)
					)
				)
				(pin bidirectional line
					(at 0 -5.08 0)
					(length 2.54)
					(name "A_{2}"
						(effects
							(font
								(size 1.27 1.27)
							)
						)
					)
					(number "4"
						(effects
							(font
								(size 1.27 1.27)
							)
						)
					)
				)
				(pin bidirectional line
					(at 0 -2.54 0)
					(length 2.54)
					(name "A_{1}"
						(effects
							(font
								(size 1.27 1.27)
							)
						)
					)
					(number "5"
						(effects
							(font
								(size 1.27 1.27)
							)
						)
					)
				)
				(pin input line
					(at 0 -7.62 0)
					(length 2.54)
					(name "OE"
						(effects
							(font
								(size 1.27 1.27)
							)
						)
					)
					(number "6"
						(effects
							(font
								(size 1.27 1.27)
							)
						)
					)
				)
				(pin power_in line
					(at 20.32 0 180)
					(length 2.54)
					(name "VCC_{B}"
						(effects
							(font
								(size 1.27 1.27)
							)
						)
					)
					(number "7"
						(effects
							(font
								(size 1.27 1.27)
							)
						)
					)
				)
				(pin bidirectional line
					(at 20.32 -2.54 180)
					(length 2.54)
					(name "B_{1}"
						(effects
							(font
								(size 1.27 1.27)
							)
						)
					)
					(number "8"
						(effects
							(font
								(size 1.27 1.27)
							)
						)
					)
				)
			)
		)
	(symbol "antmicroMechanicalParts:Spacer_Drill3.7mm_H2.5mm_9774025151R"
			(exclude_from_sim no)
			(in_bom yes)
			(on_board yes)
			(property "Reference" "H"
				(at 22.86 -2.54 0)
				(effects
					(font
						(size 1.27 1.27)
						(thickness 0.15)
					)
					(justify left bottom)
				)
			)
			(property "Value" "Spacer_Drill3.7mm_H2.5mm_9774025151R"
				(at 22.86 -5.08 0)
				(effects
					(font
						(size 1.27 1.27)
						(thickness 0.15)
					)
					(justify left bottom)
				)
			)
			(property "Footprint" "antmicro-footprints:Spacer_Drill3.7mm_H2.5mm_9774025151R"
				(at 22.86 -7.62 0)
				(effects
					(font
						(size 1.27 1.27)
						(thickness 0.15)
					)
					(justify left bottom)
					(hide yes)
				)
			)
			(property "Datasheet" "https://www.we-online.com/components/products/datasheet/9774025151R.pdf"
				(at 22.86 -10.16 0)
				(effects
					(font
						(size 1.27 1.27)
						(thickness 0.15)
					)
					(justify left bottom)
					(hide yes)
				)
			)
			(property "Description" "Spacer, SMT, Non Stop, Steel, Swage Round, 5.1 mm x 2.5 mm, M2.5 Thread, WA-SMSI Series"
				(at 0 0 0)
				(effects
					(font
						(size 1.27 1.27)
					)
					(hide yes)
				)
			)
			(property "Manufacturer" "Würth Elektronik"
				(at 22.86 -12.7 0)
				(effects
					(font
						(size 1.27 1.27)
						(thickness 0.15)
					)
					(justify left bottom)
					(hide yes)
				)
			)
			(property "MPN" "9774025151R"
				(at 22.86 -15.24 0)
				(effects
					(font
						(size 1.27 1.27)
						(thickness 0.15)
					)
					(justify left bottom)
					(hide yes)
				)
			)
			(property "Author" "Antmicro"
				(at 22.86 -17.78 0)
				(effects
					(font
						(size 1.27 1.27)
						(thickness 0.15)
					)
					(justify left bottom)
					(hide yes)
				)
			)
			(property "License" "Apache-2.0"
				(at 22.86 -20.32 0)
				(effects
					(font
						(size 1.27 1.27)
						(thickness 0.15)
					)
					(justify left bottom)
					(hide yes)
				)
			)
			(property "ki_keywords" "MECHANICAL, SPACER"
				(at 0 0 0)
				(effects
					(font
						(size 1.27 1.27)
					)
					(hide yes)
				)
			)
			(symbol "Spacer_Drill3.7mm_H2.5mm_9774025151R_1_1"
				(rectangle
					(start 2.54 -2.54)
					(end 7.62 2.54)
					(stroke
						(width 0.254)
						(type default)
					)
					(fill
						(type background)
					)
				)
				(rectangle
					(start 3.81 -1.27)
					(end 6.35 1.27)
					(stroke
						(width 0.254)
						(type default)
					)
					(fill
						(type background)
					)
				)
				(pin passive line
					(at 0 0 0)
					(length 2.54)
					(name "~"
						(effects
							(font
								(size 1.27 1.27)
							)
						)
					)
					(number "1"
						(effects
							(font
								(size 1.27 1.27)
							)
						)
					)
				)
			)
		)
	(symbol "antmicroMechanicalParts:Spacer_Drill3.7mm_H6.5mm_9774065151R"
			(exclude_from_sim no)
			(in_bom yes)
			(on_board yes)
			(property "Reference" "H"
				(at 15.24 -5.08 0)
				(effects
					(font
						(size 1.27 1.27)
						(thickness 0.15)
					)
					(justify left bottom)
				)
			)
			(property "Value" "Spacer_Drill3.7mm_H6.5mm_9774065151R"
				(at 15.24 -10.16 0)
				(effects
					(font
						(size 1.27 1.27)
						(thickness 0.15)
					)
					(justify left bottom)
					(hide yes)
				)
			)
			(property "Footprint" "antmicro-footprints:Spacer_Drill3.7mm_H6.5mm_9774065151R"
				(at 15.24 -12.7 0)
				(effects
					(font
						(size 1.27 1.27)
						(thickness 0.15)
					)
					(justify left bottom)
					(hide yes)
				)
			)
			(property "Datasheet" "https://www.we-online.com/components/products/datasheet/9774065151R.pdf"
				(at 15.24 -15.24 0)
				(effects
					(font
						(size 1.27 1.27)
						(thickness 0.15)
					)
					(justify left bottom)
					(hide yes)
				)
			)
			(property "Description" "Standoff, Steel, M2.5, Hex Female-Female, 6.5 mm, 7.9 mm, WA-SMSI Series"
				(at 0 0 0)
				(effects
					(font
						(size 1.27 1.27)
					)
					(hide yes)
				)
			)
			(property "Manufacturer" "Würth Elektronik"
				(at 15.24 -17.78 0)
				(effects
					(font
						(size 1.27 1.27)
						(thickness 0.15)
					)
					(justify left bottom)
					(hide yes)
				)
			)
			(property "MPN" "9774065151R"
				(at 15.24 -7.62 0)
				(effects
					(font
						(size 1.27 1.27)
						(thickness 0.15)
					)
					(justify left bottom)
				)
			)
			(property "Author" "Antmicro"
				(at 15.24 -20.32 0)
				(effects
					(font
						(size 1.27 1.27)
						(thickness 0.15)
					)
					(justify left bottom)
					(hide yes)
				)
			)
			(property "License" "Apache-2.0"
				(at 15.24 -22.86 0)
				(effects
					(font
						(size 1.27 1.27)
						(thickness 0.15)
					)
					(justify left bottom)
					(hide yes)
				)
			)
			(property "ki_keywords" "SPACER"
				(at 0 0 0)
				(effects
					(font
						(size 1.27 1.27)
					)
					(hide yes)
				)
			)
			(symbol "Spacer_Drill3.7mm_H6.5mm_9774065151R_1_1"
				(rectangle
					(start 2.54 -2.54)
					(end 7.62 2.54)
					(stroke
						(width 0.254)
						(type default)
					)
					(fill
						(type background)
					)
				)
				(rectangle
					(start 3.81 -1.27)
					(end 6.35 1.27)
					(stroke
						(width 0.254)
						(type default)
					)
					(fill
						(type background)
					)
				)
				(pin passive line
					(at 0 0 0)
					(length 2.54)
					(name "~"
						(effects
							(font
								(size 1.27 1.27)
							)
						)
					)
					(number "1"
						(effects
							(font
								(size 1.27 1.27)
							)
						)
					)
				)
			)
		)
	(symbol "antmicroMemory:W25Q80DV_USON"
			(exclude_from_sim no)
			(in_bom yes)
			(on_board yes)
			(property "Reference" "U"
				(at 38.1 -6.35 0)
				(effects
					(font
						(size 1.27 1.27)
						(thickness 0.15)
					)
					(justify left bottom)
				)
			)
			(property "Value" "W25Q80DV_USON"
				(at 38.1 -8.89 0)
				(effects
					(font
						(size 1.27 1.27)
						(thickness 0.15)
					)
					(justify left bottom)
					(hide yes)
				)
			)
			(property "Footprint" "antmicro-footprints:USON-8_2x3mm_P0.5mm"
				(at 38.1 -11.43 0)
				(effects
					(font
						(size 1.27 1.27)
						(thickness 0.15)
					)
					(justify left bottom)
					(hide yes)
				)
			)
			(property "Datasheet" "https://www.mouser.com/datasheet/2/949/w25q80dv_dl_revh_10022015-1489677.pdf"
				(at 38.1 -13.97 0)
				(effects
					(font
						(size 1.27 1.27)
						(thickness 0.15)
					)
					(justify left bottom)
					(hide yes)
				)
			)
			(property "Description" "FLASH - NOR Memory IC 8Mbit SPI - Quad I/O 104 MHz 8-USON (2x3)"
				(at 0 0 0)
				(effects
					(font
						(size 1.27 1.27)
					)
					(hide yes)
				)
			)
			(property "MPN" "W25Q80DVUXIE TR"
				(at 38.1 -16.51 0)
				(effects
					(font
						(size 1.27 1.27)
						(thickness 0.15)
					)
					(justify left bottom)
				)
			)
			(property "Manufacturer" "Winbond"
				(at 38.1 -19.05 0)
				(effects
					(font
						(size 1.27 1.27)
						(thickness 0.15)
					)
					(justify left bottom)
					(hide yes)
				)
			)
			(property "Author" "Antmicro"
				(at 38.1 -21.59 0)
				(effects
					(font
						(size 1.27 1.27)
						(thickness 0.15)
					)
					(justify left bottom)
					(hide yes)
				)
			)
			(property "License" "Apache-2.0"
				(at 38.1 -24.13 0)
				(effects
					(font
						(size 1.27 1.27)
						(thickness 0.15)
					)
					(justify left bottom)
					(hide yes)
				)
			)
			(property "ki_keywords" "SMT, MEMORY, IC, FLASH"
				(at 0 0 0)
				(effects
					(font
						(size 1.27 1.27)
					)
					(hide yes)
				)
			)
			(symbol "W25Q80DV_USON_1_1"
				(rectangle
					(start 2.54 2.54)
					(end 16.51 -15.24)
					(stroke
						(width 0.254)
						(type default)
					)
					(fill
						(type background)
					)
				)
				(pin input line
					(at 0 -12.7 0)
					(length 2.54)
					(name "~{CS}"
						(effects
							(font
								(size 1.27 1.27)
							)
						)
					)
					(number "1"
						(effects
							(font
								(size 1.27 1.27)
							)
						)
					)
				)
				(pin input line
					(at 0 -2.54 0)
					(length 2.54)
					(name "SO/IO1"
						(effects
							(font
								(size 1.27 1.27)
							)
						)
					)
					(number "2"
						(effects
							(font
								(size 1.27 1.27)
							)
						)
					)
				)
				(pin input line
					(at 0 -5.08 0)
					(length 2.54)
					(name "~{WP}/IO2"
						(effects
							(font
								(size 1.27 1.27)
							)
						)
					)
					(number "3"
						(effects
							(font
								(size 1.27 1.27)
							)
						)
					)
				)
				(pin power_in line
					(at 19.05 -12.7 180)
					(length 2.54)
					(name "VSS"
						(effects
							(font
								(size 1.27 1.27)
							)
						)
					)
					(number "4"
						(effects
							(font
								(size 1.27 1.27)
							)
						)
					)
				)
				(pin input line
					(at 0 0 0)
					(length 2.54)
					(name "SI/IO0"
						(effects
							(font
								(size 1.27 1.27)
							)
						)
					)
					(number "5"
						(effects
							(font
								(size 1.27 1.27)
							)
						)
					)
				)
				(pin input line
					(at 0 -10.16 0)
					(length 2.54)
					(name "SCLK"
						(effects
							(font
								(size 1.27 1.27)
							)
						)
					)
					(number "6"
						(effects
							(font
								(size 1.27 1.27)
							)
						)
					)
				)
				(pin input line
					(at 0 -7.62 0)
					(length 2.54)
					(name "~{HOLD}/IO3"
						(effects
							(font
								(size 1.27 1.27)
							)
						)
					)
					(number "7"
						(effects
							(font
								(size 1.27 1.27)
							)
						)
					)
				)
				(pin power_in line
					(at 19.05 0 180)
					(length 2.54)
					(name "VCC"
						(effects
							(font
								(size 1.27 1.27)
							)
						)
					)
					(number "8"
						(effects
							(font
								(size 1.27 1.27)
							)
						)
					)
				)
				(pin power_in line
					(at 19.05 -10.16 180)
					(length 2.54)
					(name "EP"
						(effects
							(font
								(size 1.27 1.27)
							)
						)
					)
					(number "EP"
						(effects
							(font
								(size 1.27 1.27)
							)
						)
					)
				)
			)
		)
	(symbol "antmicroModularConnectorsJacksWithMagnetics:Bus_RJ45_5-2337992-8"
			(exclude_from_sim no)
			(in_bom yes)
			(on_board yes)
			(property "Reference" "J"
				(at 35.56 -2.54 0)
				(effects
					(font
						(size 1.27 1.27)
						(thickness 0.15)
					)
					(justify left bottom)
				)
			)
			(property "Value" "Bus_RJ45_5-2337992-8"
				(at 35.56 -5.08 0)
				(effects
					(font
						(size 1.27 1.27)
						(thickness 0.15)
					)
					(justify left bottom)
					(hide yes)
				)
			)
			(property "Footprint" "antmicro-footprints:RJ45_X-2337992-8_Horizontal"
				(at 35.56 -7.62 0)
				(effects
					(font
						(size 1.27 1.27)
						(thickness 0.15)
					)
					(justify left bottom)
					(hide yes)
				)
			)
			(property "Datasheet" "https://www.te.com/commerce/DocumentDelivery/DDEController?Action=showdoc&DocId=Customer+Drawing%7F5-2337992-8%7FA%7Fpdf%7FEnglish%7FENG_CD_5-2337992-8_A.pdf%7F5-2337992-8"
				(at 35.56 -10.16 0)
				(effects
					(font
						(size 1.27 1.27)
						(thickness 0.15)
					)
					(justify left bottom)
					(hide yes)
				)
			)
			(property "Description" "Modular Connector, RJ45 Jack, 1 x 1 (Port), 8P8C, Cat5e, Through Hole Mount"
				(at 0 0 0)
				(effects
					(font
						(size 1.27 1.27)
					)
					(hide yes)
				)
			)
			(property "MPN" "5-2337992-8"
				(at 35.56 -12.7 0)
				(effects
					(font
						(size 1.27 1.27)
						(thickness 0.15)
					)
					(justify left bottom)
				)
			)
			(property "Manufacturer" "TE Connectivity"
				(at 35.56 -15.24 0)
				(effects
					(font
						(size 1.27 1.27)
						(thickness 0.15)
					)
					(justify left bottom)
					(hide yes)
				)
			)
			(property "Author" "Antmicro"
				(at 35.56 -17.78 0)
				(effects
					(font
						(size 1.27 1.27)
						(thickness 0.15)
					)
					(justify left bottom)
					(hide yes)
				)
			)
			(property "License" "Apache-2.0"
				(at 35.56 -20.32 0)
				(effects
					(font
						(size 1.27 1.27)
						(thickness 0.15)
					)
					(justify left bottom)
					(hide yes)
				)
			)
			(property "ki_keywords" "RJ45, HORIZONTAL, THT, ETHERNET, CONNECTOR, FEMALE"
				(at 0 0 0)
				(effects
					(font
						(size 1.27 1.27)
					)
					(hide yes)
				)
			)
			(property "ki_fp_filters" "CONN18_5-2337992-8_TEC"
				(at 0 0 0)
				(effects
					(font
						(size 1.27 1.27)
					)
					(hide yes)
				)
			)
			(symbol "Bus_RJ45_5-2337992-8_1_1"
				(polyline
					(pts
						(xy 8.89 -13.97) (xy 13.97 -13.97)
					)
					(stroke
						(width 0.254)
						(type default)
					)
					(fill
						(type background)
					)
				)
				(polyline
					(pts
						(xy 8.89 -1.27) (xy 8.89 -13.97)
					)
					(stroke
						(width 0.254)
						(type default)
					)
					(fill
						(type background)
					)
				)
				(polyline
					(pts
						(xy 8.89 -1.27) (xy 13.97 -1.27)
					)
					(stroke
						(width 0.254)
						(type default)
					)
					(fill
						(type background)
					)
				)
				(polyline
					(pts
						(xy 13.97 -13.97) (xy 13.97 -12.7)
					)
					(stroke
						(width 0.254)
						(type default)
					)
					(fill
						(type background)
					)
				)
				(polyline
					(pts
						(xy 13.97 -12.7) (xy 15.24 -12.7)
					)
					(stroke
						(width 0.254)
						(type default)
					)
					(fill
						(type background)
					)
				)
				(polyline
					(pts
						(xy 13.97 -2.54) (xy 15.24 -2.54)
					)
					(stroke
						(width 0.254)
						(type default)
					)
					(fill
						(type background)
					)
				)
				(polyline
					(pts
						(xy 13.97 -1.27) (xy 13.97 -2.54)
					)
					(stroke
						(width 0.254)
						(type default)
					)
					(fill
						(type background)
					)
				)
				(polyline
					(pts
						(xy 15.24 -12.7) (xy 15.24 -11.43)
					)
					(stroke
						(width 0.254)
						(type default)
					)
					(fill
						(type background)
					)
				)
				(polyline
					(pts
						(xy 15.24 -11.43) (xy 16.51 -11.43)
					)
					(stroke
						(width 0.254)
						(type default)
					)
					(fill
						(type background)
					)
				)
				(polyline
					(pts
						(xy 15.24 -3.81) (xy 16.51 -3.81)
					)
					(stroke
						(width 0.254)
						(type default)
					)
					(fill
						(type background)
					)
				)
				(polyline
					(pts
						(xy 15.24 -2.54) (xy 15.24 -3.81)
					)
					(stroke
						(width 0.254)
						(type default)
					)
					(fill
						(type background)
					)
				)
				(polyline
					(pts
						(xy 16.51 -3.81) (xy 16.51 -11.43)
					)
					(stroke
						(width 0.254)
						(type default)
					)
					(fill
						(type background)
					)
				)
				(rectangle
					(start 2.54 2.54)
					(end 19.05 -38.1)
					(stroke
						(width 0.254)
						(type default)
					)
					(fill
						(type background)
					)
				)
				(pin bidirectional line
					(at 0 0 0)
					(length 2.54)
					(name "P1"
						(effects
							(font
								(size 1.27 1.27)
							)
						)
					)
					(number "1"
						(effects
							(font
								(size 1.27 1.27)
							)
						)
					)
				)
				(pin bidirectional line
					(at 0 -17.78 0)
					(length 2.54)
					(name "P10"
						(effects
							(font
								(size 1.27 1.27)
							)
						)
					)
					(number "10"
						(effects
							(font
								(size 1.27 1.27)
							)
						)
					)
				)
				(pin bidirectional line
					(at 0 -27.94 0)
					(length 2.54)
					(name "VC1"
						(effects
							(font
								(size 1.27 1.27)
							)
						)
					)
					(number "11"
						(effects
							(font
								(size 1.27 1.27)
							)
						)
					)
				)
				(pin bidirectional line
					(at 0 -30.48 0)
					(length 2.54)
					(name "VC2"
						(effects
							(font
								(size 1.27 1.27)
							)
						)
					)
					(number "12"
						(effects
							(font
								(size 1.27 1.27)
							)
						)
					)
				)
				(pin bidirectional line
					(at 0 -33.02 0)
					(length 2.54)
					(name "VC3"
						(effects
							(font
								(size 1.27 1.27)
							)
						)
					)
					(number "13"
						(effects
							(font
								(size 1.27 1.27)
							)
						)
					)
				)
				(pin bidirectional line
					(at 0 -35.56 0)
					(length 2.54)
					(name "VC4"
						(effects
							(font
								(size 1.27 1.27)
							)
						)
					)
					(number "14"
						(effects
							(font
								(size 1.27 1.27)
							)
						)
					)
				)
				(pin passive line
					(at 21.59 -27.94 180)
					(length 2.54)
					(name "LED_GRN+"
						(effects
							(font
								(size 1.27 1.27)
							)
						)
					)
					(number "15"
						(effects
							(font
								(size 1.27 1.27)
							)
						)
					)
				)
				(pin passive line
					(at 21.59 -30.48 180)
					(length 2.54)
					(name "LED_GRN-"
						(effects
							(font
								(size 1.27 1.27)
							)
						)
					)
					(number "16"
						(effects
							(font
								(size 1.27 1.27)
							)
						)
					)
				)
				(pin passive line
					(at 21.59 -22.86 180)
					(length 2.54)
					(name "LED_YEL+"
						(effects
							(font
								(size 1.27 1.27)
							)
						)
					)
					(number "17"
						(effects
							(font
								(size 1.27 1.27)
							)
						)
					)
				)
				(pin passive line
					(at 21.59 -25.4 180)
					(length 2.54)
					(name "LED_YEL-"
						(effects
							(font
								(size 1.27 1.27)
							)
						)
					)
					(number "18"
						(effects
							(font
								(size 1.27 1.27)
							)
						)
					)
				)
				(pin passive line
					(at 21.59 -35.56 180)
					(length 2.54)
					(name "SHIELD"
						(effects
							(font
								(size 1.27 1.27)
							)
						)
					)
					(number "19"
						(effects
							(font
								(size 1.27 1.27)
							)
						)
					)
				)
				(pin bidirectional line
					(at 0 -2.54 0)
					(length 2.54)
					(name "P2"
						(effects
							(font
								(size 1.27 1.27)
							)
						)
					)
					(number "2"
						(effects
							(font
								(size 1.27 1.27)
							)
						)
					)
				)
				(pin passive line
					(at 21.59 -35.56 180)
					(length 2.54) hide
					(name "SHIELD"
						(effects
							(font
								(size 1.27 1.27)
							)
						)
					)
					(number "20"
						(effects
							(font
								(size 1.27 1.27)
							)
						)
					)
				)
				(pin bidirectional line
					(at 0 -5.08 0)
					(length 2.54)
					(name "P3"
						(effects
							(font
								(size 1.27 1.27)
							)
						)
					)
					(number "3"
						(effects
							(font
								(size 1.27 1.27)
							)
						)
					)
				)
				(pin bidirectional line
					(at 0 -22.86 0)
					(length 2.54)
					(name "P4"
						(effects
							(font
								(size 1.27 1.27)
							)
						)
					)
					(number "4"
						(effects
							(font
								(size 1.27 1.27)
							)
						)
					)
				)
				(pin bidirectional line
					(at 0 -25.4 0)
					(length 2.54)
					(name "P5"
						(effects
							(font
								(size 1.27 1.27)
							)
						)
					)
					(number "5"
						(effects
							(font
								(size 1.27 1.27)
							)
						)
					)
				)
				(pin bidirectional line
					(at 0 -7.62 0)
					(length 2.54)
					(name "P6"
						(effects
							(font
								(size 1.27 1.27)
							)
						)
					)
					(number "6"
						(effects
							(font
								(size 1.27 1.27)
							)
						)
					)
				)
				(pin bidirectional line
					(at 0 -10.16 0)
					(length 2.54)
					(name "P7"
						(effects
							(font
								(size 1.27 1.27)
							)
						)
					)
					(number "7"
						(effects
							(font
								(size 1.27 1.27)
							)
						)
					)
				)
				(pin bidirectional line
					(at 0 -12.7 0)
					(length 2.54)
					(name "P8"
						(effects
							(font
								(size 1.27 1.27)
							)
						)
					)
					(number "8"
						(effects
							(font
								(size 1.27 1.27)
							)
						)
					)
				)
				(pin bidirectional line
					(at 0 -15.24 0)
					(length 2.54)
					(name "P9"
						(effects
							(font
								(size 1.27 1.27)
							)
						)
					)
					(number "9"
						(effects
							(font
								(size 1.27 1.27)
							)
						)
					)
				)
			)
		)
	(symbol "antmicroModules:Jetson-Orin-NX-Nano"
			(pin_names
				(offset 1.016)
			)
			(exclude_from_sim no)
			(in_bom no)
			(on_board yes)
			(property "Reference" "A"
				(at 25.4 -5.08 0)
				(effects
					(font
						(size 1.27 1.27)
						(thickness 0.15)
					)
					(justify left bottom)
				)
			)
			(property "Value" "Jetson-Orin-NX-Nano"
				(at 25.4 -7.62 0)
				(effects
					(font
						(size 1.27 1.27)
						(thickness 0.15)
					)
					(justify left bottom)
					(hide yes)
				)
			)
			(property "Footprint" "antmicro-footprints:Module_Jetson-Orin-NX-Nano"
				(at 25.4 -10.16 0)
				(effects
					(font
						(size 1.27 1.27)
						(thickness 0.15)
					)
					(justify left bottom)
					(hide yes)
				)
			)
			(property "Datasheet" "https://static6.arrow.com/aropdfconversion/c4902ff7fe8bae4b5d563d5e41c1cfab77501490/jetson-orin-nx-datasheet-nvidia-us-web-2605318-5.pdf"
				(at 25.4 -12.7 0)
				(effects
					(font
						(size 1.27 1.27)
						(thickness 0.15)
					)
					(justify left bottom)
					(hide yes)
				)
			)
			(property "Description" "Jetson Orin NX/Nano, System-on-Module 1024-Core Ampere GPU, 8-Core ARM 64 Bit CPU, 16 GB LPDDR5"
				(at 0 0 0)
				(effects
					(font
						(size 1.27 1.27)
					)
					(hide yes)
				)
			)
			(property "Manufacturer" "Nvidia"
				(at 25.4 -15.24 0)
				(effects
					(font
						(size 1.27 1.27)
						(thickness 0.15)
					)
					(justify left bottom)
					(hide yes)
				)
			)
			(property "MPN" "900-13767-0000-000"
				(at 25.4 -17.78 0)
				(effects
					(font
						(size 1.27 1.27)
						(thickness 0.15)
					)
					(justify left bottom)
				)
			)
			(property "Author" "Antmicro"
				(at 25.4 -20.32 0)
				(effects
					(font
						(size 1.27 1.27)
						(thickness 0.15)
					)
					(justify left bottom)
					(hide yes)
				)
			)
			(property "License" "Apache-2.0"
				(at 25.4 -22.86 0)
				(effects
					(font
						(size 1.27 1.27)
						(thickness 0.15)
					)
					(justify left bottom)
					(hide yes)
				)
			)
			(property "Displayed name" "Jetson Orin NX Nano"
				(at 25.4 -25.4 0)
				(effects
					(font
						(size 1.27 1.27)
					)
					(justify left bottom)
				)
			)
			(property "ki_keywords" "MODULE, SOM"
				(at 0 0 0)
				(effects
					(font
						(size 1.27 1.27)
					)
					(hide yes)
				)
			)
			(symbol "Jetson-Orin-NX-Nano_0_1"
				(rectangle
					(start 10.16 -6.35)
					(end 0 0)
					(stroke
						(width 0)
						(type default)
					)
					(fill
						(type background)
					)
				)
			)
		)
	(symbol "antmicroModules:Mech_M2_2242_H2.5mm"
			(exclude_from_sim no)
			(in_bom no)
			(on_board yes)
			(property "Reference" "A"
				(at 25.4 0 0)
				(effects
					(font
						(size 1.27 1.27)
						(thickness 0.15)
					)
					(justify left bottom)
				)
			)
			(property "Value" "Mech_M2_2242_H2.5mm"
				(at 25.4 -2.54 0)
				(effects
					(font
						(size 1.27 1.27)
						(thickness 0.15)
					)
					(justify left bottom)
				)
			)
			(property "Footprint" "antmicro-footprints:Mech_M2_2242_H2.5mm"
				(at 25.4 -5.08 0)
				(effects
					(font
						(size 1.27 1.27)
						(thickness 0.15)
					)
					(justify left bottom)
					(hide yes)
				)
			)
			(property "Datasheet" ""
				(at 25.4 -7.62 0)
				(effects
					(font
						(size 1.27 1.27)
						(thickness 0.15)
					)
					(justify left bottom)
					(hide yes)
				)
			)
			(property "Description" "Mechanical model for M2 2242 2.5mm module"
				(at 0 0 0)
				(effects
					(font
						(size 1.27 1.27)
					)
					(hide yes)
				)
			)
			(property "MPN" ""
				(at 0 0 0)
				(effects
					(font
						(size 1.27 1.27)
					)
				)
			)
			(property "Manufacturer" ""
				(at 0 0 0)
				(effects
					(font
						(size 1.27 1.27)
					)
					(hide yes)
				)
			)
			(property "Author" "Antmicro"
				(at 25.4 -10.16 0)
				(effects
					(font
						(size 1.27 1.27)
						(thickness 0.15)
					)
					(justify left bottom)
					(hide yes)
				)
			)
			(property "License" "Apache-2.0"
				(at 25.4 -12.7 0)
				(effects
					(font
						(size 1.27 1.27)
						(thickness 0.15)
					)
					(justify left bottom)
					(hide yes)
				)
			)
			(property "ki_keywords" "MODULE"
				(at 0 0 0)
				(effects
					(font
						(size 1.27 1.27)
					)
					(hide yes)
				)
			)
			(symbol "Mech_M2_2242_H2.5mm_1_1"
				(rectangle
					(start 10.16 -6.35)
					(end 0 0)
					(stroke
						(width 0.254)
						(type default)
					)
					(fill
						(type background)
					)
				)
			)
		)
	(symbol "antmicroModules:Mech_M2_2280_H2.5mm"
			(exclude_from_sim no)
			(in_bom no)
			(on_board yes)
			(property "Reference" "A"
				(at 25.4 0 0)
				(effects
					(font
						(size 1.27 1.27)
						(thickness 0.15)
					)
					(justify left bottom)
				)
			)
			(property "Value" "Mech_M2_2280_H2.5mm"
				(at 25.4 -2.54 0)
				(effects
					(font
						(size 1.27 1.27)
						(thickness 0.15)
					)
					(justify left bottom)
				)
			)
			(property "Footprint" "antmicro-footprints:Mech_M2_2280_H2.5mm"
				(at 25.4 -5.08 0)
				(effects
					(font
						(size 1.27 1.27)
						(thickness 0.15)
					)
					(justify left bottom)
					(hide yes)
				)
			)
			(property "Datasheet" ""
				(at 25.4 -7.62 0)
				(effects
					(font
						(size 1.27 1.27)
						(thickness 0.15)
					)
					(justify left bottom)
					(hide yes)
				)
			)
			(property "Description" "Mechanical model for M2 2280 2.5mm module"
				(at 0 0 0)
				(effects
					(font
						(size 1.27 1.27)
					)
					(hide yes)
				)
			)
			(property "Manufacturer" ""
				(at 0 0 0)
				(effects
					(font
						(size 1.27 1.27)
					)
					(hide yes)
				)
			)
			(property "MPN" ""
				(at 0 0 0)
				(effects
					(font
						(size 1.27 1.27)
					)
				)
			)
			(property "Author" "Antmicro"
				(at 25.4 -10.16 0)
				(effects
					(font
						(size 1.27 1.27)
						(thickness 0.15)
					)
					(justify left bottom)
					(hide yes)
				)
			)
			(property "License" "Apache-2.0"
				(at 25.4 -12.7 0)
				(effects
					(font
						(size 1.27 1.27)
						(thickness 0.15)
					)
					(justify left bottom)
					(hide yes)
				)
			)
			(property "ki_keywords" "MODULE"
				(at 0 0 0)
				(effects
					(font
						(size 1.27 1.27)
					)
					(hide yes)
				)
			)
			(symbol "Mech_M2_2280_H2.5mm_1_1"
				(rectangle
					(start 10.16 -6.35)
					(end 0 0)
					(stroke
						(width 0.254)
						(type default)
					)
					(fill
						(type background)
					)
				)
			)
		)
	(symbol "antmicroOptoisolatorsLogicOutput:ACPL-217-500E"
			(exclude_from_sim no)
			(in_bom yes)
			(on_board yes)
			(property "Reference" "U"
				(at 27.94 -5.08 0)
				(effects
					(font
						(size 1.27 1.27)
						(thickness 0.15)
					)
					(justify left bottom)
				)
			)
			(property "Value" "ACPL-217-500E"
				(at 27.94 -7.62 0)
				(effects
					(font
						(size 1.27 1.27)
						(thickness 0.15)
					)
					(justify left bottom)
					(hide yes)
				)
			)
			(property "Footprint" "antmicro-footprints:SOIC-4_4.55x2.6mm_P1.27mm"
				(at 27.94 -10.16 0)
				(effects
					(font
						(size 1.27 1.27)
						(thickness 0.15)
					)
					(justify left bottom)
					(hide yes)
				)
			)
			(property "Datasheet" "https://docs.broadcom.com/doc/AV02-0470EN"
				(at 27.94 -12.7 0)
				(effects
					(font
						(size 1.27 1.27)
						(thickness 0.15)
					)
					(justify left bottom)
					(hide yes)
				)
			)
			(property "Description" "Optocoupler, Transistor Output, 1 Channel, SOIC, 4 Pins, 50 mA, 3 kV, 50 %"
				(at 27.94 -15.24 0)
				(effects
					(font
						(size 1.27 1.27)
						(thickness 0.15)
					)
					(justify left bottom)
					(hide yes)
				)
			)
			(property "Manufacturer" "Broadcom"
				(at 27.94 -17.78 0)
				(effects
					(font
						(size 1.27 1.27)
						(thickness 0.15)
					)
					(justify left bottom)
					(hide yes)
				)
			)
			(property "MPN" "ACPL-217-500E"
				(at 27.94 -20.32 0)
				(effects
					(font
						(size 1.27 1.27)
						(thickness 0.15)
					)
					(justify left bottom)
				)
			)
			(property "Author" "Antmicro"
				(at 27.94 -22.86 0)
				(effects
					(font
						(size 1.27 1.27)
						(thickness 0.15)
					)
					(justify left bottom)
					(hide yes)
				)
			)
			(property "License" "Apache-2.0"
				(at 27.94 -25.4 0)
				(effects
					(font
						(size 1.27 1.27)
						(thickness 0.15)
					)
					(justify left bottom)
					(hide yes)
				)
			)
			(property "ki_keywords" "SMT, OPTOCOUPLER, IC"
				(at 0 0 0)
				(effects
					(font
						(size 1.27 1.27)
					)
					(hide yes)
				)
			)
			(symbol "ACPL-217-500E_1_1"
				(polyline
					(pts
						(xy 3.175 -2.413) (xy 4.445 -2.413)
					)
					(stroke
						(width 0.254)
						(type default)
					)
					(fill
						(type background)
					)
				)
				(polyline
					(pts
						(xy 5.207 -2.413) (xy 7.239 -2.413)
					)
					(stroke
						(width 0.254)
						(type default)
					)
					(fill
						(type background)
					)
				)
				(polyline
					(pts
						(xy 5.207 -1.397) (xy 7.239 -1.397)
					)
					(stroke
						(width 0.254)
						(type default)
					)
					(fill
						(type background)
					)
				)
				(polyline
					(pts
						(xy 7.747 -0.889) (xy 7.747 -2.921)
					)
					(stroke
						(width 0.254)
						(type default)
					)
					(fill
						(type background)
					)
				)
				(polyline
					(pts
						(xy 9.017 -3.683) (xy 7.747 -2.413)
					)
					(stroke
						(width 0.254)
						(type default)
					)
					(fill
						(type background)
					)
				)
				(polyline
					(pts
						(xy 9.017 -0.127) (xy 7.747 -1.397)
					)
					(stroke
						(width 0.254)
						(type default)
					)
					(fill
						(type background)
					)
				)
				(polyline
					(pts
						(xy 9.144 -3.81) (xy 8.89 -3.556)
					)
					(stroke
						(width 0.254)
						(type default)
					)
					(fill
						(type background)
					)
				)
				(polyline
					(pts
						(xy 9.144 -3.81) (xy 8.89 -3.556)
					)
					(stroke
						(width 0.254)
						(type default)
					)
					(fill
						(type background)
					)
				)
				(polyline
					(pts
						(xy 9.144 0) (xy 7.874 -1.27)
					)
					(stroke
						(width 0.254)
						(type default)
					)
					(fill
						(type background)
					)
				)
				(polyline
					(pts
						(xy 10.414 -3.81) (xy 9.144 -3.81)
					)
					(stroke
						(width 0.254)
						(type default)
					)
					(fill
						(type background)
					)
				)
				(polyline
					(pts
						(xy 10.414 0) (xy 9.144 0)
					)
					(stroke
						(width 0.254)
						(type default)
					)
					(fill
						(type background)
					)
				)
				(polyline
					(pts
						(xy 2.54 -3.81) (xy 3.81 -3.81) (xy 3.81 -2.54)
					)
					(stroke
						(width 0.254)
						(type default)
					)
					(fill
						(type background)
					)
				)
				(polyline
					(pts
						(xy 2.54 0) (xy 3.81 0) (xy 3.81 -1.27)
					)
					(stroke
						(width 0.254)
						(type default)
					)
					(fill
						(type background)
					)
				)
				(polyline
					(pts
						(xy 3.175 -1.27) (xy 4.445 -1.27) (xy 3.81 -2.413) (xy 3.175 -1.27)
					)
					(stroke
						(width 0.254)
						(type default)
					)
					(fill
						(type background)
					)
				)
				(polyline
					(pts
						(xy 6.477 -2.159) (xy 6.477 -2.159) (xy 6.477 -2.667) (xy 7.239 -2.413) (xy 6.477 -2.159) (xy 6.477 -2.159)
					)
					(stroke
						(width 0.254)
						(type default)
					)
					(fill
						(type background)
					)
				)
				(polyline
					(pts
						(xy 6.477 -1.143) (xy 6.477 -1.143) (xy 6.477 -1.651) (xy 7.239 -1.397) (xy 6.477 -1.143) (xy 6.477 -1.143)
					)
					(stroke
						(width 0.254)
						(type default)
					)
					(fill
						(type background)
					)
				)
				(polyline
					(pts
						(xy 9.017 -3.683) (xy 9.017 -3.683) (xy 8.89 -3.048) (xy 8.382 -3.556) (xy 9.017 -3.683) (xy 9.017 -3.683)
					)
					(stroke
						(width 0.254)
						(type default)
					)
					(fill
						(type background)
					)
				)
				(rectangle
					(start 2.54 0.635)
					(end 2.54 0.635)
					(stroke
						(width 0.254)
						(type default)
					)
					(fill
						(type background)
					)
				)
				(rectangle
					(start 2.54 1.27)
					(end 10.414 -5.08)
					(stroke
						(width 0.254)
						(type default)
					)
					(fill
						(type background)
					)
				)
				(pin passive line
					(at 0 0 0)
					(length 2.54)
					(name "~"
						(effects
							(font
								(size 1.27 1.27)
							)
						)
					)
					(number "1"
						(effects
							(font
								(size 1.27 1.27)
							)
						)
					)
				)
				(pin passive line
					(at 0 -3.81 0)
					(length 2.54)
					(name "~"
						(effects
							(font
								(size 1.27 1.27)
							)
						)
					)
					(number "2"
						(effects
							(font
								(size 1.27 1.27)
							)
						)
					)
				)
				(pin passive line
					(at 12.7 -3.81 180)
					(length 2.54)
					(name "~"
						(effects
							(font
								(size 1.27 1.27)
							)
						)
					)
					(number "3"
						(effects
							(font
								(size 1.27 1.27)
							)
						)
					)
				)
				(pin passive line
					(at 12.7 0 180)
					(length 2.54)
					(name "~"
						(effects
							(font
								(size 1.27 1.27)
							)
						)
					)
					(number "4"
						(effects
							(font
								(size 1.27 1.27)
							)
						)
					)
				)
			)
		)
	(symbol "antmicroOscillators:Oscillator_32.768kHz_ECS_2520MV"
			(exclude_from_sim no)
			(in_bom yes)
			(on_board yes)
			(property "Reference" "Y"
				(at 26.035 -2.54 0)
				(effects
					(font
						(size 1.27 1.27)
						(thickness 0.15)
					)
					(justify left bottom)
				)
			)
			(property "Value" "Oscillator_32.768kHz_ECS_2520MV"
				(at 26.035 -12.7 0)
				(effects
					(font
						(size 1.27 1.27)
						(thickness 0.15)
					)
					(justify left bottom)
					(hide yes)
				)
			)
			(property "Footprint" "antmicro-footprints:Oscillator_SMD_ECS_2520MV_2.5x2mm"
				(at 26.035 -15.24 0)
				(effects
					(font
						(size 1.27 1.27)
						(thickness 0.15)
					)
					(justify left bottom)
					(hide yes)
				)
			)
			(property "Datasheet" "https://ecsxtal.com/store/pdf/ECS-327MVATX.pdf"
				(at 26.035 -17.78 0)
				(effects
					(font
						(size 1.27 1.27)
						(thickness 0.15)
					)
					(justify left bottom)
					(hide yes)
				)
			)
			(property "Description" "32.768 kHz XO (Standard) CMOS Oscillator 1.6V ~ 3.6V Enable/Disable 4-SMD, No Lead"
				(at 0 0 0)
				(effects
					(font
						(size 1.27 1.27)
					)
					(hide yes)
				)
			)
			(property "Manufacturer" "ECS Inc. International"
				(at 26.035 -7.62 0)
				(effects
					(font
						(size 1.27 1.27)
						(thickness 0.15)
					)
					(justify left bottom)
					(hide yes)
				)
			)
			(property "MPN" "ECS-327MVATX-2-CN-TR3"
				(at 26.035 -5.08 0)
				(effects
					(font
						(size 1.27 1.27)
						(thickness 0.15)
					)
					(justify left bottom)
				)
			)
			(property "Val" "32.768 kHz"
				(at 26.035 -10.16 0)
				(effects
					(font
						(size 1.27 1.27)
						(thickness 0.15)
					)
					(justify left bottom)
				)
			)
			(property "Author" "Antmicro"
				(at 26.035 -20.32 0)
				(effects
					(font
						(size 1.27 1.27)
						(thickness 0.15)
					)
					(justify left bottom)
					(hide yes)
				)
			)
			(property "License" "Apache-2.0"
				(at 26.035 -22.86 0)
				(effects
					(font
						(size 1.27 1.27)
						(thickness 0.15)
					)
					(justify left bottom)
					(hide yes)
				)
			)
			(property "ki_keywords" "OSCILLATOR"
				(at 0 0 0)
				(effects
					(font
						(size 1.27 1.27)
					)
					(hide yes)
				)
			)
			(symbol "Oscillator_32.768kHz_ECS_2520MV_1_1"
				(polyline
					(pts
						(xy 7.62 -1.27) (xy 8.255 -1.27) (xy 8.255 0) (xy 8.89 0) (xy 8.89 -1.27) (xy 9.525 -1.27) (xy 9.525 0)
						(xy 10.16 0) (xy 10.16 -1.27)
					)
					(stroke
						(width 0.254)
						(type default)
					)
					(fill
						(type background)
					)
				)
				(rectangle
					(start 2.54 2.54)
					(end 16.51 -7.62)
					(stroke
						(width 0.254)
						(type default)
					)
					(fill
						(type background)
					)
				)
				(pin input line
					(at 0 -2.54 0)
					(length 2.54)
					(name "EN"
						(effects
							(font
								(size 1.27 1.27)
							)
						)
					)
					(number "1"
						(effects
							(font
								(size 1.27 1.27)
							)
						)
					)
				)
				(pin power_in line
					(at 0 -5.08 0)
					(length 2.54)
					(name "GND"
						(effects
							(font
								(size 1.27 1.27)
							)
						)
					)
					(number "2"
						(effects
							(font
								(size 1.27 1.27)
							)
						)
					)
				)
				(pin output line
					(at 19.05 0 180)
					(length 2.54)
					(name "OUT"
						(effects
							(font
								(size 1.27 1.27)
							)
						)
					)
					(number "3"
						(effects
							(font
								(size 1.27 1.27)
							)
						)
					)
				)
				(pin power_in line
					(at 0 0 0)
					(length 2.54)
					(name "VDD"
						(effects
							(font
								(size 1.27 1.27)
							)
						)
					)
					(number "4"
						(effects
							(font
								(size 1.27 1.27)
							)
						)
					)
				)
			)
		)
	(symbol "antmicroPMICORControllersIdealDiodes:TPS259474ARPWR"
			(exclude_from_sim no)
			(in_bom yes)
			(on_board yes)
			(property "Reference" "U"
				(at 35.56 -2.54 0)
				(effects
					(font
						(size 1.27 1.27)
						(thickness 0.15)
					)
					(justify left bottom)
				)
			)
			(property "Value" "TPS259474"
				(at 35.56 -7.62 0)
				(effects
					(font
						(size 1.27 1.27)
						(thickness 0.15)
					)
					(justify left bottom)
					(hide yes)
				)
			)
			(property "Footprint" "antmicro-footprints:VQFN-HR-10_2x2mm"
				(at 35.56 -10.16 0)
				(effects
					(font
						(size 1.27 1.27)
						(thickness 0.15)
					)
					(justify left bottom)
					(hide yes)
				)
			)
			(property "Datasheet" "https://www.ti.com/lit/ds/symlink/tps25947.pdf"
				(at 35.56 -12.7 0)
				(effects
					(font
						(size 1.27 1.27)
						(thickness 0.15)
					)
					(justify left bottom)
					(hide yes)
				)
			)
			(property "Description" "Reverse Current Blocking eFuse with Input Reverse Polarity Protection, 5.5A, 23V, -40 to 125 Deg C, VQFN-HR-10 "
				(at 35.56 -15.24 0)
				(effects
					(font
						(size 1.27 1.27)
						(thickness 0.15)
					)
					(justify left bottom)
					(hide yes)
				)
			)
			(property "MPN" "TPS259474ARPWR"
				(at 35.56 -5.08 0)
				(effects
					(font
						(size 1.27 1.27)
						(thickness 0.15)
					)
					(justify left bottom)
				)
			)
			(property "Manufacturer" "Texas Instruments"
				(at 35.56 -17.78 0)
				(effects
					(font
						(size 1.27 1.27)
						(thickness 0.15)
					)
					(justify left bottom)
					(hide yes)
				)
			)
			(property "Author" "Antmicro"
				(at 35.56 -20.32 0)
				(effects
					(font
						(size 1.27 1.27)
						(thickness 0.15)
					)
					(justify left bottom)
					(hide yes)
				)
			)
			(property "License" "Apache-2.0"
				(at 35.56 -22.86 0)
				(effects
					(font
						(size 1.27 1.27)
						(thickness 0.15)
					)
					(justify left bottom)
					(hide yes)
				)
			)
			(property "ki_keywords" "SMT, CONTROLLER, IC, DIODE"
				(at 0 0 0)
				(effects
					(font
						(size 1.27 1.27)
					)
					(hide yes)
				)
			)
			(symbol "TPS259474ARPWR_1_1"
				(rectangle
					(start 2.54 2.54)
					(end 20.32 -13.97)
					(stroke
						(width 0.254)
						(type default)
					)
					(fill
						(type background)
					)
				)
				(pin input line
					(at 0 -3.81 0)
					(length 2.54)
					(name "EN/UVLO"
						(effects
							(font
								(size 1.27 1.27)
							)
						)
					)
					(number "1"
						(effects
							(font
								(size 1.27 1.27)
							)
						)
					)
					(alternate "UVLO" passive line)
				)
				(pin output line
					(at 22.86 -11.43 180)
					(length 2.54)
					(name "ITIMER"
						(effects
							(font
								(size 1.27 1.27)
							)
						)
					)
					(number "10"
						(effects
							(font
								(size 1.27 1.27)
							)
						)
					)
				)
				(pin input line
					(at 0 -6.35 0)
					(length 2.54)
					(name "OVLO"
						(effects
							(font
								(size 1.27 1.27)
							)
						)
					)
					(number "2"
						(effects
							(font
								(size 1.27 1.27)
							)
						)
					)
				)
				(pin output line
					(at 22.86 -8.89 180)
					(length 2.54)
					(name "PG"
						(effects
							(font
								(size 1.27 1.27)
							)
						)
					)
					(number "3"
						(effects
							(font
								(size 1.27 1.27)
							)
						)
					)
				)
				(pin input line
					(at 0 -8.89 0)
					(length 2.54)
					(name "PGTH"
						(effects
							(font
								(size 1.27 1.27)
							)
						)
					)
					(number "4"
						(effects
							(font
								(size 1.27 1.27)
							)
						)
					)
				)
				(pin power_in line
					(at 0 0 0)
					(length 2.54)
					(name "IN"
						(effects
							(font
								(size 1.27 1.27)
							)
						)
					)
					(number "5"
						(effects
							(font
								(size 1.27 1.27)
							)
						)
					)
				)
				(pin power_out line
					(at 22.86 0 180)
					(length 2.54)
					(name "OUT"
						(effects
							(font
								(size 1.27 1.27)
							)
						)
					)
					(number "6"
						(effects
							(font
								(size 1.27 1.27)
							)
						)
					)
				)
				(pin output line
					(at 22.86 -3.81 180)
					(length 2.54)
					(name "DVDT"
						(effects
							(font
								(size 1.27 1.27)
							)
						)
					)
					(number "7"
						(effects
							(font
								(size 1.27 1.27)
							)
						)
					)
				)
				(pin power_in line
					(at 0 -11.43 0)
					(length 2.54)
					(name "GND"
						(effects
							(font
								(size 1.27 1.27)
							)
						)
					)
					(number "8"
						(effects
							(font
								(size 1.27 1.27)
							)
						)
					)
				)
				(pin output line
					(at 22.86 -6.35 180)
					(length 2.54)
					(name "ILIM"
						(effects
							(font
								(size 1.27 1.27)
							)
						)
					)
					(number "9"
						(effects
							(font
								(size 1.27 1.27)
							)
						)
					)
				)
			)
		)
	(symbol "antmicroPMICPowerDistributionSwitchesLoadDrivers:AP22615A_TSOT26"
			(exclude_from_sim no)
			(in_bom yes)
			(on_board yes)
			(property "Reference" "U"
				(at 30.48 -2.54 0)
				(effects
					(font
						(size 1.27 1.27)
						(thickness 0.15)
					)
					(justify left bottom)
				)
			)
			(property "Value" "AP22615A_TSOT26"
				(at 30.48 -5.08 0)
				(effects
					(font
						(size 1.27 1.27)
						(thickness 0.15)
					)
					(justify left bottom)
					(hide yes)
				)
			)
			(property "Footprint" "antmicro-footprints:TSOT23-6"
				(at 30.48 -7.62 0)
				(effects
					(font
						(size 1.27 1.27)
						(thickness 0.15)
					)
					(justify left bottom)
					(hide yes)
				)
			)
			(property "Datasheet" "https://www.mouser.com/datasheet/2/115/DIOD_S_A0008958405_1-2543193.pdf"
				(at 30.48 -10.16 0)
				(effects
					(font
						(size 1.27 1.27)
						(thickness 0.15)
					)
					(justify left bottom)
					(hide yes)
				)
			)
			(property "Description" "Power Load Distribution Switch, High Side, Active High, 1 Output, 5.5 V, 3.6 A, 0.04 ohm, TSOT-26-6"
				(at 0 0 0)
				(effects
					(font
						(size 1.27 1.27)
					)
					(hide yes)
				)
			)
			(property "MPN" "AP22615AWU-7"
				(at 30.48 -12.7 0)
				(effects
					(font
						(size 1.27 1.27)
						(thickness 0.15)
					)
					(justify left bottom)
				)
			)
			(property "Manufacturer" "Diodes Incorporated"
				(at 30.48 -15.24 0)
				(effects
					(font
						(size 1.27 1.27)
						(thickness 0.15)
					)
					(justify left bottom)
					(hide yes)
				)
			)
			(property "Author" "Antmicro"
				(at 30.48 -17.78 0)
				(effects
					(font
						(size 1.27 1.27)
						(thickness 0.15)
					)
					(justify left bottom)
					(hide yes)
				)
			)
			(property "License" "Apache-2.0"
				(at 30.48 -20.32 0)
				(effects
					(font
						(size 1.27 1.27)
						(thickness 0.15)
					)
					(justify left bottom)
					(hide yes)
				)
			)
			(property "ki_keywords" "SMT, PMIC, IC, VOLTAGE"
				(at 0 0 0)
				(effects
					(font
						(size 1.27 1.27)
					)
					(hide yes)
				)
			)
			(symbol "AP22615A_TSOT26_1_1"
				(rectangle
					(start 2.54 2.54)
					(end 12.7 -7.62)
					(stroke
						(width 0.254)
						(type default)
					)
					(fill
						(type background)
					)
				)
				(pin power_out line
					(at 15.24 0 180)
					(length 2.54)
					(name "OUT"
						(effects
							(font
								(size 1.27 1.27)
							)
						)
					)
					(number "1"
						(effects
							(font
								(size 1.27 1.27)
							)
						)
					)
				)
				(pin power_in line
					(at 15.24 -5.08 180)
					(length 2.54)
					(name "GND"
						(effects
							(font
								(size 1.27 1.27)
							)
						)
					)
					(number "2"
						(effects
							(font
								(size 1.27 1.27)
							)
						)
					)
				)
				(pin output line
					(at 0 -2.54 0)
					(length 2.54)
					(name "FLG"
						(effects
							(font
								(size 1.27 1.27)
							)
						)
					)
					(number "3"
						(effects
							(font
								(size 1.27 1.27)
							)
						)
					)
				)
				(pin input line
					(at 0 -5.08 0)
					(length 2.54)
					(name "EN"
						(effects
							(font
								(size 1.27 1.27)
							)
						)
					)
					(number "4"
						(effects
							(font
								(size 1.27 1.27)
							)
						)
					)
				)
				(pin passive line
					(at 15.24 -2.54 180)
					(length 2.54)
					(name "ISET"
						(effects
							(font
								(size 1.27 1.27)
							)
						)
					)
					(number "5"
						(effects
							(font
								(size 1.27 1.27)
							)
						)
					)
				)
				(pin power_in line
					(at 0 0 0)
					(length 2.54)
					(name "IN"
						(effects
							(font
								(size 1.27 1.27)
							)
						)
					)
					(number "6"
						(effects
							(font
								(size 1.27 1.27)
							)
						)
					)
				)
			)
		)
	(symbol "antmicroPMICPowerDistributionSwitchesLoadDrivers:AP22653_DFN"
			(exclude_from_sim no)
			(in_bom yes)
			(on_board yes)
			(property "Reference" "U"
				(at 30.48 -2.54 0)
				(effects
					(font
						(size 1.27 1.27)
						(thickness 0.15)
					)
					(justify left bottom)
				)
			)
			(property "Value" "AP22653_DFN"
				(at 30.48 -5.08 0)
				(effects
					(font
						(size 1.27 1.27)
						(thickness 0.15)
					)
					(justify left bottom)
					(hide yes)
				)
			)
			(property "Footprint" "antmicro-footprints:DFN-6-1EP_2x2mm_P0.65mm_EP1x1.6mm"
				(at 30.48 -7.62 0)
				(effects
					(font
						(size 1.27 1.27)
						(thickness 0.15)
					)
					(justify left bottom)
					(hide yes)
				)
			)
			(property "Datasheet" "https://www.mouser.com/datasheet/2/115/DIOD_S_A0010880137_1-2543666.pdf"
				(at 30.48 -10.16 0)
				(effects
					(font
						(size 1.27 1.27)
						(thickness 0.15)
					)
					(justify left bottom)
					(hide yes)
				)
			)
			(property "Description" "Power Load Distribution Switch, High Side, Active High, 1 Output, 5.5 V, 2.665 A, W-DFN2020-EP-6"
				(at 0 0 0)
				(effects
					(font
						(size 1.27 1.27)
					)
					(hide yes)
				)
			)
			(property "MPN" "AP22653FDZ-7"
				(at 30.48 -12.7 0)
				(effects
					(font
						(size 1.27 1.27)
						(thickness 0.15)
					)
					(justify left bottom)
				)
			)
			(property "Manufacturer" "Diodes Incorporated"
				(at 30.48 -15.24 0)
				(effects
					(font
						(size 1.27 1.27)
						(thickness 0.15)
					)
					(justify left bottom)
					(hide yes)
				)
			)
			(property "Author" "Antmicro"
				(at 30.48 -17.78 0)
				(effects
					(font
						(size 1.27 1.27)
						(thickness 0.15)
					)
					(justify left bottom)
					(hide yes)
				)
			)
			(property "License" "Apache-2.0"
				(at 30.48 -20.32 0)
				(effects
					(font
						(size 1.27 1.27)
						(thickness 0.15)
					)
					(justify left bottom)
					(hide yes)
				)
			)
			(property "ki_keywords" "SMT, PMIC, IC, VOLTAGE"
				(at 0 0 0)
				(effects
					(font
						(size 1.27 1.27)
					)
					(hide yes)
				)
			)
			(symbol "AP22653_DFN_1_1"
				(rectangle
					(start 2.54 2.54)
					(end 12.7 -10.16)
					(stroke
						(width 0.254)
						(type default)
					)
					(fill
						(type background)
					)
				)
				(pin power_out line
					(at 15.24 0 180)
					(length 2.54)
					(name "OUT"
						(effects
							(font
								(size 1.27 1.27)
							)
						)
					)
					(number "1"
						(effects
							(font
								(size 1.27 1.27)
							)
						)
					)
				)
				(pin passive line
					(at 15.24 -2.54 180)
					(length 2.54)
					(name "ISET"
						(effects
							(font
								(size 1.27 1.27)
							)
						)
					)
					(number "2"
						(effects
							(font
								(size 1.27 1.27)
							)
						)
					)
				)
				(pin output line
					(at 0 -2.54 0)
					(length 2.54)
					(name "FLG"
						(effects
							(font
								(size 1.27 1.27)
							)
						)
					)
					(number "3"
						(effects
							(font
								(size 1.27 1.27)
							)
						)
					)
				)
				(pin input line
					(at 0 -5.08 0)
					(length 2.54)
					(name "EN"
						(effects
							(font
								(size 1.27 1.27)
							)
						)
					)
					(number "4"
						(effects
							(font
								(size 1.27 1.27)
							)
						)
					)
				)
				(pin power_in line
					(at 15.24 -7.62 180)
					(length 2.54)
					(name "GND"
						(effects
							(font
								(size 1.27 1.27)
							)
						)
					)
					(number "5"
						(effects
							(font
								(size 1.27 1.27)
							)
						)
					)
				)
				(pin power_in line
					(at 0 0 0)
					(length 2.54)
					(name "IN"
						(effects
							(font
								(size 1.27 1.27)
							)
						)
					)
					(number "6"
						(effects
							(font
								(size 1.27 1.27)
							)
						)
					)
				)
				(pin power_in line
					(at 15.24 -5.08 180)
					(length 2.54)
					(name "EP"
						(effects
							(font
								(size 1.27 1.27)
							)
						)
					)
					(number "7"
						(effects
							(font
								(size 1.27 1.27)
							)
						)
					)
				)
			)
		)
	(symbol "antmicroPMICPowerDistributionSwitchesLoadDrivers:TPS2372-3RGWR"
			(exclude_from_sim no)
			(in_bom yes)
			(on_board yes)
			(property "Reference" "U"
				(at 35.56 0 0)
				(effects
					(font
						(size 1.27 1.27)
						(thickness 0.15)
					)
					(justify left bottom)
				)
			)
			(property "Value" "TPS2372-3RGWR"
				(at 35.56 -2.54 0)
				(effects
					(font
						(size 1.27 1.27)
						(thickness 0.15)
					)
					(justify left bottom)
					(hide yes)
				)
			)
			(property "Footprint" "antmicro-footprints:VQFN-20_5x5x1mm_P0.65mm"
				(at 35.56 -5.08 0)
				(effects
					(font
						(size 1.27 1.27)
						(thickness 0.15)
					)
					(justify left bottom)
					(hide yes)
				)
			)
			(property "Datasheet" "https://www.ti.com/lit/ds/symlink/tps2372.pdf?ts=1679042478513&ref_url=https%253A%252F%252Fwww.google.com%252F"
				(at 35.56 -7.62 0)
				(effects
					(font
						(size 1.27 1.27)
						(thickness 0.15)
					)
					(justify left bottom)
					(hide yes)
				)
			)
			(property "Description" "PoE interface"
				(at 0 0 0)
				(effects
					(font
						(size 1.27 1.27)
					)
					(hide yes)
				)
			)
			(property "MPN" "TPS2372-3RGWR"
				(at 35.56 -10.16 0)
				(effects
					(font
						(size 1.27 1.27)
						(thickness 0.15)
					)
					(justify left bottom)
				)
			)
			(property "Manufacturer" "Texas Instruments"
				(at 35.56 -12.7 0)
				(effects
					(font
						(size 1.27 1.27)
						(thickness 0.15)
					)
					(justify left bottom)
					(hide yes)
				)
			)
			(property "Author" "Antmicro"
				(at 35.56 -15.24 0)
				(effects
					(font
						(size 1.27 1.27)
						(thickness 0.15)
					)
					(justify left bottom)
					(hide yes)
				)
			)
			(property "License" "Apache-2.0"
				(at 35.56 -17.78 0)
				(effects
					(font
						(size 1.27 1.27)
						(thickness 0.15)
					)
					(justify left bottom)
					(hide yes)
				)
			)
			(property "ki_keywords" "SMT, POE, IC, INTERFACE"
				(at 0 0 0)
				(effects
					(font
						(size 1.27 1.27)
					)
					(hide yes)
				)
			)
			(symbol "TPS2372-3RGWR_1_1"
				(rectangle
					(start 2.54 2.54)
					(end 19.05 -35.56)
					(stroke
						(width 0.254)
						(type default)
					)
					(fill
						(type background)
					)
				)
				(pin power_in line
					(at 0 0 0)
					(length 2.54)
					(name "VDD"
						(effects
							(font
								(size 1.27 1.27)
							)
						)
					)
					(number "1"
						(effects
							(font
								(size 1.27 1.27)
							)
						)
					)
				)
				(pin input line
					(at 0 -33.02 0)
					(length 2.54)
					(name "~{AUTCLS}"
						(effects
							(font
								(size 1.27 1.27)
							)
						)
					)
					(number "10"
						(effects
							(font
								(size 1.27 1.27)
							)
						)
					)
				)
				(pin power_out line
					(at 21.59 -30.48 180)
					(length 2.54)
					(name "RTNA"
						(effects
							(font
								(size 1.27 1.27)
							)
						)
					)
					(number "11"
						(effects
							(font
								(size 1.27 1.27)
							)
						)
					)
				)
				(pin power_out line
					(at 21.59 -33.02 180)
					(length 2.54)
					(name "RTNB"
						(effects
							(font
								(size 1.27 1.27)
							)
						)
					)
					(number "12"
						(effects
							(font
								(size 1.27 1.27)
							)
						)
					)
				)
				(pin output line
					(at 21.59 -20.32 180)
					(length 2.54)
					(name "PG"
						(effects
							(font
								(size 1.27 1.27)
							)
						)
					)
					(number "13"
						(effects
							(font
								(size 1.27 1.27)
							)
						)
					)
				)
				(pin no_connect line
					(at 19.05 -15.24 180)
					(length 2.54) hide
					(name "NC"
						(effects
							(font
								(size 1.27 1.27)
							)
						)
					)
					(number "14"
						(effects
							(font
								(size 1.27 1.27)
							)
						)
					)
				)
				(pin no_connect line
					(at 19.05 -12.7 180)
					(length 2.54) hide
					(name "NC"
						(effects
							(font
								(size 1.27 1.27)
							)
						)
					)
					(number "15"
						(effects
							(font
								(size 1.27 1.27)
							)
						)
					)
				)
				(pin output line
					(at 21.59 -25.4 180)
					(length 2.54)
					(name "IRSHDL_EN"
						(effects
							(font
								(size 1.27 1.27)
							)
						)
					)
					(number "16"
						(effects
							(font
								(size 1.27 1.27)
							)
						)
					)
				)
				(pin output line
					(at 21.59 -2.54 180)
					(length 2.54)
					(name "TPL"
						(effects
							(font
								(size 1.27 1.27)
							)
						)
					)
					(number "17"
						(effects
							(font
								(size 1.27 1.27)
							)
						)
					)
				)
				(pin output line
					(at 21.59 0 180)
					(length 2.54)
					(name "TPH"
						(effects
							(font
								(size 1.27 1.27)
							)
						)
					)
					(number "18"
						(effects
							(font
								(size 1.27 1.27)
							)
						)
					)
				)
				(pin output line
					(at 21.59 -5.08 180)
					(length 2.54)
					(name "~{BT}"
						(effects
							(font
								(size 1.27 1.27)
							)
						)
					)
					(number "19"
						(effects
							(font
								(size 1.27 1.27)
							)
						)
					)
				)
				(pin input line
					(at 0 -2.54 0)
					(length 2.54)
					(name "DEN"
						(effects
							(font
								(size 1.27 1.27)
							)
						)
					)
					(number "2"
						(effects
							(font
								(size 1.27 1.27)
							)
						)
					)
				)
				(pin no_connect line
					(at 19.05 -10.16 180)
					(length 2.54) hide
					(name "NC"
						(effects
							(font
								(size 1.27 1.27)
							)
						)
					)
					(number "20"
						(effects
							(font
								(size 1.27 1.27)
							)
						)
					)
				)
				(pin power_in line
					(at 0 -20.32 0)
					(length 2.54)
					(name "PAD_VSSC"
						(effects
							(font
								(size 1.27 1.27)
							)
						)
					)
					(number "21"
						(effects
							(font
								(size 1.27 1.27)
							)
						)
					)
				)
				(pin input line
					(at 0 -7.62 0)
					(length 2.54)
					(name "CLSA"
						(effects
							(font
								(size 1.27 1.27)
							)
						)
					)
					(number "3"
						(effects
							(font
								(size 1.27 1.27)
							)
						)
					)
				)
				(pin power_in line
					(at 0 -15.24 0)
					(length 2.54)
					(name "VSSA"
						(effects
							(font
								(size 1.27 1.27)
							)
						)
					)
					(number "4"
						(effects
							(font
								(size 1.27 1.27)
							)
						)
					)
				)
				(pin power_in line
					(at 0 -17.78 0)
					(length 2.54)
					(name "VSSB"
						(effects
							(font
								(size 1.27 1.27)
							)
						)
					)
					(number "5"
						(effects
							(font
								(size 1.27 1.27)
							)
						)
					)
				)
				(pin input line
					(at 0 -10.16 0)
					(length 2.54)
					(name "CLSB"
						(effects
							(font
								(size 1.27 1.27)
							)
						)
					)
					(number "6"
						(effects
							(font
								(size 1.27 1.27)
							)
						)
					)
				)
				(pin input line
					(at 0 -25.4 0)
					(length 2.54)
					(name "REF"
						(effects
							(font
								(size 1.27 1.27)
							)
						)
					)
					(number "7"
						(effects
							(font
								(size 1.27 1.27)
							)
						)
					)
				)
				(pin input line
					(at 0 -22.86 0)
					(length 2.54)
					(name "AMPS_CTL"
						(effects
							(font
								(size 1.27 1.27)
							)
						)
					)
					(number "8"
						(effects
							(font
								(size 1.27 1.27)
							)
						)
					)
				)
				(pin input line
					(at 0 -27.94 0)
					(length 2.54)
					(name "MPS_DUTY"
						(effects
							(font
								(size 1.27 1.27)
							)
						)
					)
					(number "9"
						(effects
							(font
								(size 1.27 1.27)
							)
						)
					)
				)
			)
		)
	(symbol "antmicroPMICVoltageRegulatorsLinear:NCP730BMT330_WSON"
			(exclude_from_sim no)
			(in_bom yes)
			(on_board yes)
			(property "Reference" "U"
				(at 30.48 -2.54 0)
				(effects
					(font
						(size 1.27 1.27)
						(thickness 0.15)
					)
					(justify left bottom)
				)
			)
			(property "Value" "NCP730BMT330_WSON"
				(at 30.48 -5.08 0)
				(effects
					(font
						(size 1.27 1.27)
						(thickness 0.15)
					)
					(justify left bottom)
					(hide yes)
				)
			)
			(property "Footprint" "antmicro-footprints:WSON-6-1EP_2x2mm_P0.65mm"
				(at 30.48 -7.62 0)
				(effects
					(font
						(size 1.27 1.27)
						(thickness 0.15)
					)
					(justify left bottom)
					(hide yes)
				)
			)
			(property "Datasheet" "https://www.onsemi.com/download/data-sheet/pdf/ncp730-d.pdf"
				(at 30.48 -10.16 0)
				(effects
					(font
						(size 1.27 1.27)
						(thickness 0.15)
					)
					(justify left bottom)
					(hide yes)
				)
			)
			(property "Description" "Linear Voltage Regulator IC Positive Fixed 1 Output 150mA 6-WDFN (2x2)"
				(at 0 0 0)
				(effects
					(font
						(size 1.27 1.27)
					)
					(hide yes)
				)
			)
			(property "MPN" "NCP730BMT330TBG"
				(at 30.48 -12.7 0)
				(effects
					(font
						(size 1.27 1.27)
						(thickness 0.15)
					)
					(justify left bottom)
				)
			)
			(property "Manufacturer" "ON Semiconductor"
				(at 30.48 -15.24 0)
				(effects
					(font
						(size 1.27 1.27)
						(thickness 0.15)
					)
					(justify left bottom)
					(hide yes)
				)
			)
			(property "Author" "Antmicro"
				(at 30.48 -17.78 0)
				(effects
					(font
						(size 1.27 1.27)
						(thickness 0.15)
					)
					(justify left bottom)
					(hide yes)
				)
			)
			(property "License" "Apache-2.0"
				(at 30.48 -20.32 0)
				(effects
					(font
						(size 1.27 1.27)
						(thickness 0.15)
					)
					(justify left bottom)
					(hide yes)
				)
			)
			(property "ki_keywords" "SMT, PMIC, IC, LDO, VOLTAGE, REGULATOR"
				(at 0 0 0)
				(effects
					(font
						(size 1.27 1.27)
					)
					(hide yes)
				)
			)
			(symbol "NCP730BMT330_WSON_1_1"
				(rectangle
					(start 2.54 2.54)
					(end 12.7 -7.62)
					(stroke
						(width 0.254)
						(type default)
					)
					(fill
						(type background)
					)
				)
				(pin power_out line
					(at 15.24 0 180)
					(length 2.54)
					(name "V_{OUT}"
						(effects
							(font
								(size 1.27 1.27)
							)
						)
					)
					(number "1"
						(effects
							(font
								(size 1.27 1.27)
							)
						)
					)
				)
				(pin no_connect line
					(at 12.7 -5.08 180)
					(length 2.54) hide
					(name "NC"
						(effects
							(font
								(size 1.27 1.27)
							)
						)
					)
					(number "2"
						(effects
							(font
								(size 1.27 1.27)
							)
						)
					)
				)
				(pin power_in line
					(at 0 -5.08 0)
					(length 2.54)
					(name "GND"
						(effects
							(font
								(size 1.27 1.27)
							)
						)
					)
					(number "3"
						(effects
							(font
								(size 1.27 1.27)
							)
						)
					)
				)
				(pin input line
					(at 0 -2.54 0)
					(length 2.54)
					(name "EN"
						(effects
							(font
								(size 1.27 1.27)
							)
						)
					)
					(number "4"
						(effects
							(font
								(size 1.27 1.27)
							)
						)
					)
				)
				(pin open_collector line
					(at 15.24 -2.54 180)
					(length 2.54)
					(name "PG"
						(effects
							(font
								(size 1.27 1.27)
							)
						)
					)
					(number "5"
						(effects
							(font
								(size 1.27 1.27)
							)
						)
					)
				)
				(pin power_in line
					(at 0 0 0)
					(length 2.54)
					(name "V_{IN}"
						(effects
							(font
								(size 1.27 1.27)
							)
						)
					)
					(number "6"
						(effects
							(font
								(size 1.27 1.27)
							)
						)
					)
				)
				(pin passive line
					(at 0 -5.08 0)
					(length 2.54) hide
					(name "GND"
						(effects
							(font
								(size 1.27 1.27)
							)
						)
					)
					(number "7"
						(effects
							(font
								(size 1.27 1.27)
							)
						)
					)
				)
			)
		)
	(symbol "antmicroPMICVoltageRegulatorsLinear:TPS7A0518P_SOT23-5"
			(exclude_from_sim no)
			(in_bom yes)
			(on_board yes)
			(property "Reference" "U"
				(at 26.67 -1.27 0)
				(effects
					(font
						(size 1.27 1.27)
						(thickness 0.15)
					)
					(justify left bottom)
				)
			)
			(property "Value" "TPS7A0518P_SOT23-5"
				(at 26.67 -3.81 0)
				(effects
					(font
						(size 1.27 1.27)
						(thickness 0.15)
					)
					(justify left bottom)
					(hide yes)
				)
			)
			(property "Footprint" "antmicro-footprints:SOT-23-5"
				(at 26.67 -6.35 0)
				(effects
					(font
						(size 1.27 1.27)
						(thickness 0.15)
					)
					(justify left bottom)
					(hide yes)
				)
			)
			(property "Datasheet" "https://www.ti.com/lit/ds/symlink/tps7a05.pdf?ts=1678973651768&ref_url=https%253A%252F%252Fwww.google.com%252F"
				(at 26.67 -8.89 0)
				(effects
					(font
						(size 1.27 1.27)
						(thickness 0.15)
					)
					(justify left bottom)
					(hide yes)
				)
			)
			(property "Description" "Linear voltage regulator"
				(at 0 0 0)
				(effects
					(font
						(size 1.27 1.27)
					)
					(hide yes)
				)
			)
			(property "MPN" "TPS7A0518PDBVT"
				(at 26.67 -11.43 0)
				(effects
					(font
						(size 1.27 1.27)
						(thickness 0.15)
					)
					(justify left bottom)
				)
			)
			(property "Manufacturer" "Texas Instruments"
				(at 26.67 -13.97 0)
				(effects
					(font
						(size 1.27 1.27)
						(thickness 0.15)
					)
					(justify left bottom)
					(hide yes)
				)
			)
			(property "Author" "Antmicro"
				(at 26.67 -16.51 0)
				(effects
					(font
						(size 1.27 1.27)
						(thickness 0.15)
					)
					(justify left bottom)
					(hide yes)
				)
			)
			(property "License" "Apache-2.0"
				(at 26.67 -19.05 0)
				(effects
					(font
						(size 1.27 1.27)
						(thickness 0.15)
					)
					(justify left bottom)
					(hide yes)
				)
			)
			(property "ki_keywords" "SMT, PMIC, IC, LDO, LINEAR, VOLTAGE, REGULATOR"
				(at 0 0 0)
				(effects
					(font
						(size 1.27 1.27)
					)
					(hide yes)
				)
			)
			(symbol "TPS7A0518P_SOT23-5_1_1"
				(rectangle
					(start 2.54 2.54)
					(end 12.7 -5.08)
					(stroke
						(width 0.254)
						(type default)
					)
					(fill
						(type background)
					)
				)
				(pin power_in line
					(at 0 0 0)
					(length 2.54)
					(name "VIN"
						(effects
							(font
								(size 1.27 1.27)
							)
						)
					)
					(number "1"
						(effects
							(font
								(size 1.27 1.27)
							)
						)
					)
				)
				(pin power_in line
					(at 15.24 -2.54 180)
					(length 2.54)
					(name "GND"
						(effects
							(font
								(size 1.27 1.27)
							)
						)
					)
					(number "2"
						(effects
							(font
								(size 1.27 1.27)
							)
						)
					)
				)
				(pin input line
					(at 0 -2.54 0)
					(length 2.54)
					(name "EN"
						(effects
							(font
								(size 1.27 1.27)
							)
						)
					)
					(number "3"
						(effects
							(font
								(size 1.27 1.27)
							)
						)
					)
				)
				(pin no_connect line
					(at 2.54 -3.81 0)
					(length 2.54) hide
					(name "NC"
						(effects
							(font
								(size 1.27 1.27)
							)
						)
					)
					(number "4"
						(effects
							(font
								(size 1.27 1.27)
							)
						)
					)
				)
				(pin power_out line
					(at 15.24 0 180)
					(length 2.54)
					(name "VOUT"
						(effects
							(font
								(size 1.27 1.27)
							)
						)
					)
					(number "5"
						(effects
							(font
								(size 1.27 1.27)
							)
						)
					)
				)
			)
		)
	(symbol "antmicroPciConnectors:Bus_M.2_1-2199230-6"
			(exclude_from_sim no)
			(in_bom yes)
			(on_board yes)
			(property "Reference" "J"
				(at 45.72 -2.54 0)
				(effects
					(font
						(size 1.27 1.27)
						(thickness 0.15)
					)
					(justify left bottom)
				)
			)
			(property "Value" "Bus_M.2_1-2199230-6"
				(at 45.72 -7.62 0)
				(effects
					(font
						(size 1.27 1.27)
						(thickness 0.15)
					)
					(justify left bottom)
					(hide yes)
				)
			)
			(property "Footprint" "antmicro-footprints:Bus_M.2_Socket_Key_M_TE_1-2199230-6"
				(at 45.72 -10.16 0)
				(effects
					(font
						(size 1.27 1.27)
						(thickness 0.15)
					)
					(justify left bottom)
					(hide yes)
				)
			)
			(property "Datasheet" "https://www.te.com/commerce/DocumentDelivery/DDEController?Action=srchrtrv&DocNm=2199230&DocType=Customer+Drawing&DocLang=English"
				(at 45.72 -12.7 0)
				(effects
					(font
						(size 1.27 1.27)
						(thickness 0.15)
					)
					(justify left bottom)
					(hide yes)
				)
			)
			(property "Description" "Key M Card Edge Connector, 0, Dual Side, 67 Contacts, Surface Mount, Right Angle, Solder"
				(at 0 0 0)
				(effects
					(font
						(size 1.27 1.27)
					)
					(hide yes)
				)
			)
			(property "Manufacturer" "TE Connectivity"
				(at 45.72 -15.24 0)
				(effects
					(font
						(size 1.27 1.27)
						(thickness 0.15)
					)
					(justify left bottom)
					(hide yes)
				)
			)
			(property "MPN" "1-2199230-6"
				(at 45.72 -5.08 0)
				(effects
					(font
						(size 1.27 1.27)
						(thickness 0.15)
					)
					(justify left bottom)
				)
			)
			(property "Author" "Antmicro"
				(at 45.72 -17.78 0)
				(effects
					(font
						(size 1.27 1.27)
						(thickness 0.15)
					)
					(justify left bottom)
					(hide yes)
				)
			)
			(property "License" "Apache-2.0"
				(at 45.72 -20.32 0)
				(effects
					(font
						(size 1.27 1.27)
						(thickness 0.15)
					)
					(justify left bottom)
					(hide yes)
				)
			)
			(property "ki_keywords" "HORIZONTAL, SMT, PCIE, CONNECTOR"
				(at 0 0 0)
				(effects
					(font
						(size 1.27 1.27)
					)
					(hide yes)
				)
			)
			(symbol "Bus_M.2_1-2199230-6_0_0"
				(text "KEY M"
					(at 15.24 0 0)
					(effects
						(font
							(size 1.27 1.27)
							(bold yes)
						)
					)
				)
			)
			(symbol "Bus_M.2_1-2199230-6_1_1"
				(rectangle
					(start 3.81 2.54)
					(end 26.67 -80.01)
					(stroke
						(width 0.254)
						(type default)
					)
					(fill
						(type background)
					)
				)
				(pin power_in line
					(at 30.48 -77.47 180)
					(length 3.81)
					(name "GND"
						(effects
							(font
								(size 1.27 1.27)
							)
						)
					)
					(number "1"
						(effects
							(font
								(size 1.27 1.27)
							)
						)
					)
				)
				(pin passive line
					(at 30.48 -54.61 180)
					(length 3.81)
					(name "LED"
						(effects
							(font
								(size 1.27 1.27)
							)
						)
					)
					(number "10"
						(effects
							(font
								(size 1.27 1.27)
							)
						)
					)
				)
				(pin input line
					(at 0 -69.85 0)
					(length 3.81)
					(name "PET3_N"
						(effects
							(font
								(size 1.27 1.27)
							)
						)
					)
					(number "11"
						(effects
							(font
								(size 1.27 1.27)
							)
						)
					)
				)
				(pin passive line
					(at 30.48 0 180)
					(length 3.81)
					(name "3V3"
						(effects
							(font
								(size 1.27 1.27)
							)
						)
					)
					(number "12"
						(effects
							(font
								(size 1.27 1.27)
							)
						)
					)
				)
				(pin input line
					(at 0 -67.31 0)
					(length 3.81)
					(name "PET3_P"
						(effects
							(font
								(size 1.27 1.27)
							)
						)
					)
					(number "13"
						(effects
							(font
								(size 1.27 1.27)
							)
						)
					)
				)
				(pin passive line
					(at 30.48 0 180)
					(length 3.81) hide
					(name "3V3"
						(effects
							(font
								(size 1.27 1.27)
							)
						)
					)
					(number "14"
						(effects
							(font
								(size 1.27 1.27)
							)
						)
					)
				)
				(pin passive line
					(at 30.48 -77.47 180)
					(length 3.81) hide
					(name "GND"
						(effects
							(font
								(size 1.27 1.27)
							)
						)
					)
					(number "15"
						(effects
							(font
								(size 1.27 1.27)
							)
						)
					)
				)
				(pin passive line
					(at 30.48 0 180)
					(length 3.81) hide
					(name "3V3"
						(effects
							(font
								(size 1.27 1.27)
							)
						)
					)
					(number "16"
						(effects
							(font
								(size 1.27 1.27)
							)
						)
					)
				)
				(pin output line
					(at 0 -62.23 0)
					(length 3.81)
					(name "PER2_N"
						(effects
							(font
								(size 1.27 1.27)
							)
						)
					)
					(number "17"
						(effects
							(font
								(size 1.27 1.27)
							)
						)
					)
				)
				(pin passive line
					(at 30.48 0 180)
					(length 3.81) hide
					(name "3V3"
						(effects
							(font
								(size 1.27 1.27)
							)
						)
					)
					(number "18"
						(effects
							(font
								(size 1.27 1.27)
							)
						)
					)
				)
				(pin output line
					(at 0 -59.69 0)
					(length 3.81)
					(name "PER2_P"
						(effects
							(font
								(size 1.27 1.27)
							)
						)
					)
					(number "19"
						(effects
							(font
								(size 1.27 1.27)
							)
						)
					)
				)
				(pin passive line
					(at 30.48 0 180)
					(length 3.81) hide
					(name "3V3"
						(effects
							(font
								(size 1.27 1.27)
							)
						)
					)
					(number "2"
						(effects
							(font
								(size 1.27 1.27)
							)
						)
					)
				)
				(pin no_connect line
					(at 26.67 -44.45 180)
					(length 3.81) hide
					(name "NC"
						(effects
							(font
								(size 1.27 1.27)
							)
						)
					)
					(number "20"
						(effects
							(font
								(size 1.27 1.27)
							)
						)
					)
				)
				(pin passive line
					(at 30.48 -77.47 180)
					(length 3.81) hide
					(name "GND"
						(effects
							(font
								(size 1.27 1.27)
							)
						)
					)
					(number "21"
						(effects
							(font
								(size 1.27 1.27)
							)
						)
					)
				)
				(pin no_connect line
					(at 26.67 -45.72 180)
					(length 3.81) hide
					(name "NC"
						(effects
							(font
								(size 1.27 1.27)
							)
						)
					)
					(number "22"
						(effects
							(font
								(size 1.27 1.27)
							)
						)
					)
				)
				(pin input line
					(at 0 -54.61 0)
					(length 3.81)
					(name "PET2_N"
						(effects
							(font
								(size 1.27 1.27)
							)
						)
					)
					(number "23"
						(effects
							(font
								(size 1.27 1.27)
							)
						)
					)
				)
				(pin no_connect line
					(at 26.67 -46.99 180)
					(length 3.81) hide
					(name "NC"
						(effects
							(font
								(size 1.27 1.27)
							)
						)
					)
					(number "24"
						(effects
							(font
								(size 1.27 1.27)
							)
						)
					)
				)
				(pin input line
					(at 0 -52.07 0)
					(length 3.81)
					(name "PET2_P"
						(effects
							(font
								(size 1.27 1.27)
							)
						)
					)
					(number "25"
						(effects
							(font
								(size 1.27 1.27)
							)
						)
					)
				)
				(pin no_connect line
					(at 26.67 -59.69 180)
					(length 3.81) hide
					(name "NC"
						(effects
							(font
								(size 1.27 1.27)
							)
						)
					)
					(number "26"
						(effects
							(font
								(size 1.27 1.27)
							)
						)
					)
				)
				(pin passive line
					(at 30.48 -77.47 180)
					(length 3.81) hide
					(name "GND"
						(effects
							(font
								(size 1.27 1.27)
							)
						)
					)
					(number "27"
						(effects
							(font
								(size 1.27 1.27)
							)
						)
					)
				)
				(pin no_connect line
					(at 26.67 -60.96 180)
					(length 3.81) hide
					(name "NC"
						(effects
							(font
								(size 1.27 1.27)
							)
						)
					)
					(number "28"
						(effects
							(font
								(size 1.27 1.27)
							)
						)
					)
				)
				(pin output line
					(at 0 -46.99 0)
					(length 3.81)
					(name "PER1_N"
						(effects
							(font
								(size 1.27 1.27)
							)
						)
					)
					(number "29"
						(effects
							(font
								(size 1.27 1.27)
							)
						)
					)
				)
				(pin passive line
					(at 30.48 -77.47 180)
					(length 3.81) hide
					(name "GND"
						(effects
							(font
								(size 1.27 1.27)
							)
						)
					)
					(number "3"
						(effects
							(font
								(size 1.27 1.27)
							)
						)
					)
				)
				(pin no_connect line
					(at 26.67 -62.23 180)
					(length 3.81) hide
					(name "NC"
						(effects
							(font
								(size 1.27 1.27)
							)
						)
					)
					(number "30"
						(effects
							(font
								(size 1.27 1.27)
							)
						)
					)
				)
				(pin output line
					(at 0 -44.45 0)
					(length 3.81)
					(name "PER1_P"
						(effects
							(font
								(size 1.27 1.27)
							)
						)
					)
					(number "31"
						(effects
							(font
								(size 1.27 1.27)
							)
						)
					)
				)
				(pin no_connect line
					(at 26.67 -63.5 180)
					(length 3.81) hide
					(name "NC"
						(effects
							(font
								(size 1.27 1.27)
							)
						)
					)
					(number "32"
						(effects
							(font
								(size 1.27 1.27)
							)
						)
					)
				)
				(pin passive line
					(at 30.48 -77.47 180)
					(length 3.81) hide
					(name "GND"
						(effects
							(font
								(size 1.27 1.27)
							)
						)
					)
					(number "33"
						(effects
							(font
								(size 1.27 1.27)
							)
						)
					)
				)
				(pin no_connect line
					(at 26.67 -66.04 180)
					(length 3.81) hide
					(name "NC"
						(effects
							(font
								(size 1.27 1.27)
							)
						)
					)
					(number "34"
						(effects
							(font
								(size 1.27 1.27)
							)
						)
					)
				)
				(pin input line
					(at 0 -39.37 0)
					(length 3.81)
					(name "PET1_N"
						(effects
							(font
								(size 1.27 1.27)
							)
						)
					)
					(number "35"
						(effects
							(font
								(size 1.27 1.27)
							)
						)
					)
				)
				(pin no_connect line
					(at 26.67 -67.31 180)
					(length 3.81) hide
					(name "NC"
						(effects
							(font
								(size 1.27 1.27)
							)
						)
					)
					(number "36"
						(effects
							(font
								(size 1.27 1.27)
							)
						)
					)
				)
				(pin input line
					(at 0 -36.83 0)
					(length 3.81)
					(name "PET1_P"
						(effects
							(font
								(size 1.27 1.27)
							)
						)
					)
					(number "37"
						(effects
							(font
								(size 1.27 1.27)
							)
						)
					)
				)
				(pin no_connect line
					(at 26.67 -69.85 180)
					(length 3.81) hide
					(name "NC"
						(effects
							(font
								(size 1.27 1.27)
							)
						)
					)
					(number "38"
						(effects
							(font
								(size 1.27 1.27)
							)
						)
					)
				)
				(pin passive line
					(at 30.48 -77.47 180)
					(length 3.81) hide
					(name "GND"
						(effects
							(font
								(size 1.27 1.27)
							)
						)
					)
					(number "39"
						(effects
							(font
								(size 1.27 1.27)
							)
						)
					)
				)
				(pin passive line
					(at 30.48 0 180)
					(length 3.81) hide
					(name "3V3"
						(effects
							(font
								(size 1.27 1.27)
							)
						)
					)
					(number "4"
						(effects
							(font
								(size 1.27 1.27)
							)
						)
					)
				)
				(pin input line
					(at 30.48 -31.75 180)
					(length 3.81)
					(name "SMB_CLK"
						(effects
							(font
								(size 1.27 1.27)
							)
						)
					)
					(number "40"
						(effects
							(font
								(size 1.27 1.27)
							)
						)
					)
				)
				(pin output line
					(at 0 -31.75 0)
					(length 3.81)
					(name "PER0_N"
						(effects
							(font
								(size 1.27 1.27)
							)
						)
					)
					(number "41"
						(effects
							(font
								(size 1.27 1.27)
							)
						)
					)
				)
				(pin bidirectional line
					(at 30.48 -29.21 180)
					(length 3.81)
					(name "SMB_DATA"
						(effects
							(font
								(size 1.27 1.27)
							)
						)
					)
					(number "42"
						(effects
							(font
								(size 1.27 1.27)
							)
						)
					)
				)
				(pin output line
					(at 0 -29.21 0)
					(length 3.81)
					(name "PER0_P"
						(effects
							(font
								(size 1.27 1.27)
							)
						)
					)
					(number "43"
						(effects
							(font
								(size 1.27 1.27)
							)
						)
					)
				)
				(pin output line
					(at 30.48 -26.67 180)
					(length 3.81)
					(name "ALERT"
						(effects
							(font
								(size 1.27 1.27)
							)
						)
					)
					(number "44"
						(effects
							(font
								(size 1.27 1.27)
							)
						)
					)
				)
				(pin passive line
					(at 30.48 -77.47 180)
					(length 3.81) hide
					(name "GND"
						(effects
							(font
								(size 1.27 1.27)
							)
						)
					)
					(number "45"
						(effects
							(font
								(size 1.27 1.27)
							)
						)
					)
				)
				(pin no_connect line
					(at 26.67 -68.58 180)
					(length 3.81) hide
					(name "NC"
						(effects
							(font
								(size 1.27 1.27)
							)
						)
					)
					(number "46"
						(effects
							(font
								(size 1.27 1.27)
							)
						)
					)
				)
				(pin input line
					(at 0 -24.13 0)
					(length 3.81)
					(name "PET0_N"
						(effects
							(font
								(size 1.27 1.27)
							)
						)
					)
					(number "47"
						(effects
							(font
								(size 1.27 1.27)
							)
						)
					)
				)
				(pin no_connect line
					(at 26.67 -41.91 180)
					(length 3.81) hide
					(name "NC"
						(effects
							(font
								(size 1.27 1.27)
							)
						)
					)
					(number "48"
						(effects
							(font
								(size 1.27 1.27)
							)
						)
					)
				)
				(pin input line
					(at 0 -21.59 0)
					(length 3.81)
					(name "PET0_P"
						(effects
							(font
								(size 1.27 1.27)
							)
						)
					)
					(number "49"
						(effects
							(font
								(size 1.27 1.27)
							)
						)
					)
				)
				(pin output line
					(at 0 -77.47 0)
					(length 3.81)
					(name "PER3_N"
						(effects
							(font
								(size 1.27 1.27)
							)
						)
					)
					(number "5"
						(effects
							(font
								(size 1.27 1.27)
							)
						)
					)
				)
				(pin input line
					(at 0 0 0)
					(length 3.81)
					(name "~{PERST}"
						(effects
							(font
								(size 1.27 1.27)
							)
						)
					)
					(number "50"
						(effects
							(font
								(size 1.27 1.27)
							)
						)
					)
				)
				(pin passive line
					(at 30.48 -77.47 180)
					(length 3.81) hide
					(name "GND"
						(effects
							(font
								(size 1.27 1.27)
							)
						)
					)
					(number "51"
						(effects
							(font
								(size 1.27 1.27)
							)
						)
					)
				)
				(pin output line
					(at 0 -2.54 0)
					(length 3.81)
					(name "~{CLKREQ}"
						(effects
							(font
								(size 1.27 1.27)
							)
						)
					)
					(number "52"
						(effects
							(font
								(size 1.27 1.27)
							)
						)
					)
				)
				(pin input line
					(at 0 -15.24 0)
					(length 3.81)
					(name "REFCLK_N"
						(effects
							(font
								(size 1.27 1.27)
							)
						)
					)
					(number "53"
						(effects
							(font
								(size 1.27 1.27)
							)
						)
					)
				)
				(pin input line
					(at 0 -5.08 0)
					(length 3.81)
					(name "~{PEWAKE}"
						(effects
							(font
								(size 1.27 1.27)
							)
						)
					)
					(number "54"
						(effects
							(font
								(size 1.27 1.27)
							)
						)
					)
				)
				(pin input line
					(at 0 -12.7 0)
					(length 3.81)
					(name "REFCLK_P"
						(effects
							(font
								(size 1.27 1.27)
							)
						)
					)
					(number "55"
						(effects
							(font
								(size 1.27 1.27)
							)
						)
					)
				)
				(pin no_connect line
					(at 26.67 -43.18 180)
					(length 3.81) hide
					(name "NC"
						(effects
							(font
								(size 1.27 1.27)
							)
						)
					)
					(number "56"
						(effects
							(font
								(size 1.27 1.27)
							)
						)
					)
				)
				(pin passive line
					(at 30.48 -77.47 180)
					(length 3.81) hide
					(name "GND"
						(effects
							(font
								(size 1.27 1.27)
							)
						)
					)
					(number "57"
						(effects
							(font
								(size 1.27 1.27)
							)
						)
					)
				)
				(pin no_connect line
					(at 26.67 -71.12 180)
					(length 3.81) hide
					(name "NC"
						(effects
							(font
								(size 1.27 1.27)
							)
						)
					)
					(number "58"
						(effects
							(font
								(size 1.27 1.27)
							)
						)
					)
				)
				(pin no_connect line
					(at 26.67 -39.37 180)
					(length 3.81) hide
					(name "NC"
						(effects
							(font
								(size 1.27 1.27)
							)
						)
					)
					(number "6"
						(effects
							(font
								(size 1.27 1.27)
							)
						)
					)
				)
				(pin no_connect line
					(at 26.67 -40.64 180)
					(length 3.81) hide
					(name "NC"
						(effects
							(font
								(size 1.27 1.27)
							)
						)
					)
					(number "67"
						(effects
							(font
								(size 1.27 1.27)
							)
						)
					)
				)
				(pin input line
					(at 30.48 -12.7 180)
					(length 3.81)
					(name "SUSCLK"
						(effects
							(font
								(size 1.27 1.27)
							)
						)
					)
					(number "68"
						(effects
							(font
								(size 1.27 1.27)
							)
						)
					)
				)
				(pin no_connect line
					(at 26.67 -38.1 180)
					(length 3.81) hide
					(name "NC"
						(effects
							(font
								(size 1.27 1.27)
							)
						)
					)
					(number "69"
						(effects
							(font
								(size 1.27 1.27)
							)
						)
					)
				)
				(pin output line
					(at 0 -74.93 0)
					(length 3.81)
					(name "PER3_P"
						(effects
							(font
								(size 1.27 1.27)
							)
						)
					)
					(number "7"
						(effects
							(font
								(size 1.27 1.27)
							)
						)
					)
				)
				(pin passive line
					(at 30.48 0 180)
					(length 3.81) hide
					(name "3V3"
						(effects
							(font
								(size 1.27 1.27)
							)
						)
					)
					(number "70"
						(effects
							(font
								(size 1.27 1.27)
							)
						)
					)
				)
				(pin passive line
					(at 30.48 -77.47 180)
					(length 3.81) hide
					(name "GND"
						(effects
							(font
								(size 1.27 1.27)
							)
						)
					)
					(number "71"
						(effects
							(font
								(size 1.27 1.27)
							)
						)
					)
				)
				(pin passive line
					(at 30.48 0 180)
					(length 3.81) hide
					(name "3V3"
						(effects
							(font
								(size 1.27 1.27)
							)
						)
					)
					(number "72"
						(effects
							(font
								(size 1.27 1.27)
							)
						)
					)
				)
				(pin passive line
					(at 30.48 -77.47 180)
					(length 3.81) hide
					(name "GND"
						(effects
							(font
								(size 1.27 1.27)
							)
						)
					)
					(number "73"
						(effects
							(font
								(size 1.27 1.27)
							)
						)
					)
				)
				(pin passive line
					(at 30.48 0 180)
					(length 3.81) hide
					(name "3V3"
						(effects
							(font
								(size 1.27 1.27)
							)
						)
					)
					(number "74"
						(effects
							(font
								(size 1.27 1.27)
							)
						)
					)
				)
				(pin passive line
					(at 30.48 -77.47 180)
					(length 3.81) hide
					(name "GND"
						(effects
							(font
								(size 1.27 1.27)
							)
						)
					)
					(number "75"
						(effects
							(font
								(size 1.27 1.27)
							)
						)
					)
				)
				(pin no_connect line
					(at 26.67 -64.77 180)
					(length 3.81) hide
					(name "NC"
						(effects
							(font
								(size 1.27 1.27)
							)
						)
					)
					(number "8"
						(effects
							(font
								(size 1.27 1.27)
							)
						)
					)
				)
				(pin passive line
					(at 30.48 -77.47 180)
					(length 3.81) hide
					(name "GND"
						(effects
							(font
								(size 1.27 1.27)
							)
						)
					)
					(number "9"
						(effects
							(font
								(size 1.27 1.27)
							)
						)
					)
				)
				(pin passive line
					(at 30.48 -74.93 180)
					(length 3.81)
					(name "MP"
						(effects
							(font
								(size 1.27 1.27)
							)
						)
					)
					(number "MP1"
						(effects
							(font
								(size 1.27 1.27)
							)
						)
					)
				)
				(pin passive line
					(at 30.48 -74.93 180)
					(length 3.81) hide
					(name "MP"
						(effects
							(font
								(size 1.27 1.27)
							)
						)
					)
					(number "MP2"
						(effects
							(font
								(size 1.27 1.27)
							)
						)
					)
				)
			)
		)
	(symbol "antmicroPciConnectors:Bus_M.2_2199230-6"
			(exclude_from_sim no)
			(in_bom yes)
			(on_board yes)
			(property "Reference" "J"
				(at 45.72 -1.27 0)
				(effects
					(font
						(size 1.27 1.27)
						(thickness 0.15)
					)
					(justify left bottom)
				)
			)
			(property "Value" "Bus_M.2_2199230-6"
				(at 45.72 -3.81 0)
				(effects
					(font
						(size 1.27 1.27)
						(thickness 0.15)
					)
					(justify left bottom)
					(hide yes)
				)
			)
			(property "Footprint" "antmicro-footprints:Bus_M.2_Socket_Key_E_TE_2199230-6"
				(at 45.72 -6.35 0)
				(effects
					(font
						(size 1.27 1.27)
						(thickness 0.15)
					)
					(justify left bottom)
					(hide yes)
				)
			)
			(property "Datasheet" "https://www.te.com/usa-en/product-2199230-6.datasheet.pdf"
				(at 45.72 -8.89 0)
				(effects
					(font
						(size 1.27 1.27)
						(thickness 0.15)
					)
					(justify left bottom)
					(hide yes)
				)
			)
			(property "Description" "Key E, PCI connector"
				(at 0 0 0)
				(effects
					(font
						(size 1.27 1.27)
					)
					(hide yes)
				)
			)
			(property "MPN" "2199230-6 "
				(at 45.72 -11.43 0)
				(effects
					(font
						(size 1.27 1.27)
						(thickness 0.15)
					)
					(justify left bottom)
				)
			)
			(property "Manufacturer" "TE Connectivity"
				(at 45.72 -13.97 0)
				(effects
					(font
						(size 1.27 1.27)
						(thickness 0.15)
					)
					(justify left bottom)
					(hide yes)
				)
			)
			(property "Author" "Antmicro"
				(at 45.72 -16.51 0)
				(effects
					(font
						(size 1.27 1.27)
						(thickness 0.15)
					)
					(justify left bottom)
					(hide yes)
				)
			)
			(property "License" "Apache-2.0"
				(at 45.72 -19.05 0)
				(effects
					(font
						(size 1.27 1.27)
						(thickness 0.15)
					)
					(justify left bottom)
					(hide yes)
				)
			)
			(property "ki_keywords" "HORIZONTAL, SMT, PCIE, CONNECTOR"
				(at 0 0 0)
				(effects
					(font
						(size 1.27 1.27)
					)
					(hide yes)
				)
			)
			(symbol "Bus_M.2_2199230-6_0_0"
				(text "KEY E"
					(at 15.24 0 0)
					(effects
						(font
							(size 1.27 1.27)
							(bold yes)
						)
					)
				)
			)
			(symbol "Bus_M.2_2199230-6_1_1"
				(rectangle
					(start 2.54 3.81)
					(end 27.94 -110.49)
					(stroke
						(width 0.254)
						(type default)
					)
					(fill
						(type background)
					)
				)
				(pin power_in line
					(at 30.48 -106.68 180)
					(length 2.54)
					(name "GND"
						(effects
							(font
								(size 1.27 1.27)
							)
						)
					)
					(number "1"
						(effects
							(font
								(size 1.27 1.27)
							)
						)
					)
				)
				(pin bidirectional line
					(at 0 -68.58 0)
					(length 2.54)
					(name "PCM_SYNC"
						(effects
							(font
								(size 1.27 1.27)
							)
						)
					)
					(number "10"
						(effects
							(font
								(size 1.27 1.27)
							)
						)
					)
				)
				(pin bidirectional line
					(at 0 -88.9 0)
					(length 2.54)
					(name "SDIO_CMD"
						(effects
							(font
								(size 1.27 1.27)
							)
						)
					)
					(number "11"
						(effects
							(font
								(size 1.27 1.27)
							)
						)
					)
				)
				(pin bidirectional line
					(at 0 -73.66 0)
					(length 2.54)
					(name "PCM_IN"
						(effects
							(font
								(size 1.27 1.27)
							)
						)
					)
					(number "12"
						(effects
							(font
								(size 1.27 1.27)
							)
						)
					)
				)
				(pin bidirectional line
					(at 0 -91.44 0)
					(length 2.54)
					(name "SDIO_D0"
						(effects
							(font
								(size 1.27 1.27)
							)
						)
					)
					(number "13"
						(effects
							(font
								(size 1.27 1.27)
							)
						)
					)
				)
				(pin bidirectional line
					(at 0 -71.12 0)
					(length 2.54)
					(name "PCM_OUT"
						(effects
							(font
								(size 1.27 1.27)
							)
						)
					)
					(number "14"
						(effects
							(font
								(size 1.27 1.27)
							)
						)
					)
				)
				(pin bidirectional line
					(at 0 -93.98 0)
					(length 2.54)
					(name "SDIO_D1"
						(effects
							(font
								(size 1.27 1.27)
							)
						)
					)
					(number "15"
						(effects
							(font
								(size 1.27 1.27)
							)
						)
					)
				)
				(pin output line
					(at 30.48 -90.17 180)
					(length 2.54)
					(name "~{LED_2}"
						(effects
							(font
								(size 1.27 1.27)
							)
						)
					)
					(number "16"
						(effects
							(font
								(size 1.27 1.27)
							)
						)
					)
				)
				(pin bidirectional line
					(at 0 -96.52 0)
					(length 2.54)
					(name "SDIO_D2"
						(effects
							(font
								(size 1.27 1.27)
							)
						)
					)
					(number "17"
						(effects
							(font
								(size 1.27 1.27)
							)
						)
					)
				)
				(pin passive line
					(at 30.48 -106.68 180)
					(length 2.54) hide
					(name "GND"
						(effects
							(font
								(size 1.27 1.27)
							)
						)
					)
					(number "18"
						(effects
							(font
								(size 1.27 1.27)
							)
						)
					)
				)
				(pin bidirectional line
					(at 0 -99.06 0)
					(length 2.54)
					(name "SDIO_D3"
						(effects
							(font
								(size 1.27 1.27)
							)
						)
					)
					(number "19"
						(effects
							(font
								(size 1.27 1.27)
							)
						)
					)
				)
				(pin power_in line
					(at 30.48 0 180)
					(length 2.54)
					(name "3.3V"
						(effects
							(font
								(size 1.27 1.27)
							)
						)
					)
					(number "2"
						(effects
							(font
								(size 1.27 1.27)
							)
						)
					)
				)
				(pin output line
					(at 30.48 -43.18 180)
					(length 2.54)
					(name "~{UART_WAKE}"
						(effects
							(font
								(size 1.27 1.27)
							)
						)
					)
					(number "20"
						(effects
							(font
								(size 1.27 1.27)
							)
						)
					)
				)
				(pin bidirectional line
					(at 0 -101.6 0)
					(length 2.54)
					(name "SDIO_~{WAKE}"
						(effects
							(font
								(size 1.27 1.27)
							)
						)
					)
					(number "21"
						(effects
							(font
								(size 1.27 1.27)
							)
						)
					)
				)
				(pin bidirectional line
					(at 30.48 -48.26 180)
					(length 2.54)
					(name "UART_RXD"
						(effects
							(font
								(size 1.27 1.27)
							)
						)
					)
					(number "22"
						(effects
							(font
								(size 1.27 1.27)
							)
						)
					)
				)
				(pin input line
					(at 0 -104.14 0)
					(length 2.54)
					(name "SDIO_~{RESET}"
						(effects
							(font
								(size 1.27 1.27)
							)
						)
					)
					(number "23"
						(effects
							(font
								(size 1.27 1.27)
							)
						)
					)
				)
				(pin bidirectional line
					(at 0 -78.74 0)
					(length 2.54)
					(name "USB_D_P"
						(effects
							(font
								(size 1.27 1.27)
							)
						)
					)
					(number "3"
						(effects
							(font
								(size 1.27 1.27)
							)
						)
					)
				)
				(pin bidirectional line
					(at 30.48 -45.72 180)
					(length 2.54)
					(name "UART_TXD"
						(effects
							(font
								(size 1.27 1.27)
							)
						)
					)
					(number "32"
						(effects
							(font
								(size 1.27 1.27)
							)
						)
					)
				)
				(pin passive line
					(at 30.48 -106.68 180)
					(length 2.54) hide
					(name "GND"
						(effects
							(font
								(size 1.27 1.27)
							)
						)
					)
					(number "33"
						(effects
							(font
								(size 1.27 1.27)
							)
						)
					)
				)
				(pin bidirectional line
					(at 30.48 -53.34 180)
					(length 2.54)
					(name "UART_CTS"
						(effects
							(font
								(size 1.27 1.27)
							)
						)
					)
					(number "34"
						(effects
							(font
								(size 1.27 1.27)
							)
						)
					)
				)
				(pin input line
					(at 0 -17.78 0)
					(length 2.54)
					(name "PET0_P"
						(effects
							(font
								(size 1.27 1.27)
							)
						)
					)
					(number "35"
						(effects
							(font
								(size 1.27 1.27)
							)
						)
					)
				)
				(pin bidirectional line
					(at 30.48 -50.8 180)
					(length 2.54)
					(name "UART_RTS"
						(effects
							(font
								(size 1.27 1.27)
							)
						)
					)
					(number "36"
						(effects
							(font
								(size 1.27 1.27)
							)
						)
					)
				)
				(pin input line
					(at 0 -20.32 0)
					(length 2.54)
					(name "PET0_N"
						(effects
							(font
								(size 1.27 1.27)
							)
						)
					)
					(number "37"
						(effects
							(font
								(size 1.27 1.27)
							)
						)
					)
				)
				(pin bidirectional line
					(at 30.48 -74.93 180)
					(length 2.54)
					(name "VENDOR_1"
						(effects
							(font
								(size 1.27 1.27)
							)
						)
					)
					(number "38"
						(effects
							(font
								(size 1.27 1.27)
							)
						)
					)
				)
				(pin passive line
					(at 30.48 -106.68 180)
					(length 2.54) hide
					(name "GND"
						(effects
							(font
								(size 1.27 1.27)
							)
						)
					)
					(number "39"
						(effects
							(font
								(size 1.27 1.27)
							)
						)
					)
				)
				(pin passive line
					(at 30.48 0 180)
					(length 2.54) hide
					(name "3.3V"
						(effects
							(font
								(size 1.27 1.27)
							)
						)
					)
					(number "4"
						(effects
							(font
								(size 1.27 1.27)
							)
						)
					)
				)
				(pin bidirectional line
					(at 30.48 -77.47 180)
					(length 2.54)
					(name "VENDOR_2"
						(effects
							(font
								(size 1.27 1.27)
							)
						)
					)
					(number "40"
						(effects
							(font
								(size 1.27 1.27)
							)
						)
					)
				)
				(pin output line
					(at 0 -25.4 0)
					(length 2.54)
					(name "PER0_P"
						(effects
							(font
								(size 1.27 1.27)
							)
						)
					)
					(number "41"
						(effects
							(font
								(size 1.27 1.27)
							)
						)
					)
				)
				(pin bidirectional line
					(at 30.48 -80.01 180)
					(length 2.54)
					(name "VENDOR_3"
						(effects
							(font
								(size 1.27 1.27)
							)
						)
					)
					(number "42"
						(effects
							(font
								(size 1.27 1.27)
							)
						)
					)
				)
				(pin output line
					(at 0 -27.94 0)
					(length 2.54)
					(name "PER0_N"
						(effects
							(font
								(size 1.27 1.27)
							)
						)
					)
					(number "43"
						(effects
							(font
								(size 1.27 1.27)
							)
						)
					)
				)
				(pin bidirectional line
					(at 30.48 -68.58 180)
					(length 2.54)
					(name "COEX3"
						(effects
							(font
								(size 1.27 1.27)
							)
						)
					)
					(number "44"
						(effects
							(font
								(size 1.27 1.27)
							)
						)
					)
				)
				(pin passive line
					(at 30.48 -106.68 180)
					(length 2.54) hide
					(name "GND"
						(effects
							(font
								(size 1.27 1.27)
							)
						)
					)
					(number "45"
						(effects
							(font
								(size 1.27 1.27)
							)
						)
					)
				)
				(pin bidirectional line
					(at 30.48 -66.04 180)
					(length 2.54)
					(name "COEX_TXD"
						(effects
							(font
								(size 1.27 1.27)
							)
						)
					)
					(number "46"
						(effects
							(font
								(size 1.27 1.27)
							)
						)
					)
				)
				(pin input line
					(at 0 -10.16 0)
					(length 2.54)
					(name "REFCLK0_P"
						(effects
							(font
								(size 1.27 1.27)
							)
						)
					)
					(number "47"
						(effects
							(font
								(size 1.27 1.27)
							)
						)
					)
				)
				(pin bidirectional line
					(at 30.48 -63.5 180)
					(length 2.54)
					(name "COEX_RXD"
						(effects
							(font
								(size 1.27 1.27)
							)
						)
					)
					(number "48"
						(effects
							(font
								(size 1.27 1.27)
							)
						)
					)
				)
				(pin input line
					(at 0 -12.7 0)
					(length 2.54)
					(name "REFCLK0_N"
						(effects
							(font
								(size 1.27 1.27)
							)
						)
					)
					(number "49"
						(effects
							(font
								(size 1.27 1.27)
							)
						)
					)
				)
				(pin bidirectional line
					(at 0 -81.28 0)
					(length 2.54)
					(name "USB_D_N"
						(effects
							(font
								(size 1.27 1.27)
							)
						)
					)
					(number "5"
						(effects
							(font
								(size 1.27 1.27)
							)
						)
					)
				)
				(pin input line
					(at 30.48 -12.7 180)
					(length 2.54)
					(name "SUSCLK"
						(effects
							(font
								(size 1.27 1.27)
							)
						)
					)
					(number "50"
						(effects
							(font
								(size 1.27 1.27)
							)
						)
					)
				)
				(pin passive line
					(at 30.48 -106.68 180)
					(length 2.54) hide
					(name "GND"
						(effects
							(font
								(size 1.27 1.27)
							)
						)
					)
					(number "51"
						(effects
							(font
								(size 1.27 1.27)
							)
						)
					)
				)
				(pin input line
					(at 0 0 0)
					(length 2.54)
					(name "~{PERST0}"
						(effects
							(font
								(size 1.27 1.27)
							)
						)
					)
					(number "52"
						(effects
							(font
								(size 1.27 1.27)
							)
						)
					)
				)
				(pin output line
					(at 0 -2.54 0)
					(length 2.54)
					(name "~{CLKREQ0}"
						(effects
							(font
								(size 1.27 1.27)
							)
						)
					)
					(number "53"
						(effects
							(font
								(size 1.27 1.27)
							)
						)
					)
				)
				(pin input line
					(at 30.48 -38.1 180)
					(length 2.54)
					(name "W_DISABLE2"
						(effects
							(font
								(size 1.27 1.27)
							)
						)
					)
					(number "54"
						(effects
							(font
								(size 1.27 1.27)
							)
						)
					)
				)
				(pin output line
					(at 0 -5.08 0)
					(length 2.54)
					(name "~{PEWAKE0}"
						(effects
							(font
								(size 1.27 1.27)
							)
						)
					)
					(number "55"
						(effects
							(font
								(size 1.27 1.27)
							)
						)
					)
				)
				(pin input line
					(at 30.48 -35.56 180)
					(length 2.54)
					(name "W_DISABLE1"
						(effects
							(font
								(size 1.27 1.27)
							)
						)
					)
					(number "56"
						(effects
							(font
								(size 1.27 1.27)
							)
						)
					)
				)
				(pin passive line
					(at 30.48 -106.68 180)
					(length 2.54) hide
					(name "GND"
						(effects
							(font
								(size 1.27 1.27)
							)
						)
					)
					(number "57"
						(effects
							(font
								(size 1.27 1.27)
							)
						)
					)
				)
				(pin bidirectional line
					(at 30.48 -27.94 180)
					(length 2.54)
					(name "I2C_DATA"
						(effects
							(font
								(size 1.27 1.27)
							)
						)
					)
					(number "58"
						(effects
							(font
								(size 1.27 1.27)
							)
						)
					)
				)
				(pin input line
					(at 0 -40.64 0)
					(length 2.54)
					(name "PET1_P"
						(effects
							(font
								(size 1.27 1.27)
							)
						)
					)
					(number "59"
						(effects
							(font
								(size 1.27 1.27)
							)
						)
					)
				)
				(pin output line
					(at 30.48 -85.09 180)
					(length 2.54)
					(name "~{LED_1}"
						(effects
							(font
								(size 1.27 1.27)
							)
						)
					)
					(number "6"
						(effects
							(font
								(size 1.27 1.27)
							)
						)
					)
				)
				(pin bidirectional line
					(at 30.48 -30.48 180)
					(length 2.54)
					(name "I2C_CLK"
						(effects
							(font
								(size 1.27 1.27)
							)
						)
					)
					(number "60"
						(effects
							(font
								(size 1.27 1.27)
							)
						)
					)
				)
				(pin input line
					(at 0 -43.18 0)
					(length 2.54)
					(name "PET1_N"
						(effects
							(font
								(size 1.27 1.27)
							)
						)
					)
					(number "61"
						(effects
							(font
								(size 1.27 1.27)
							)
						)
					)
				)
				(pin output line
					(at 30.48 -25.4 180)
					(length 2.54)
					(name "~{ALERT}"
						(effects
							(font
								(size 1.27 1.27)
							)
						)
					)
					(number "62"
						(effects
							(font
								(size 1.27 1.27)
							)
						)
					)
				)
				(pin passive line
					(at 30.48 -106.68 180)
					(length 2.54) hide
					(name "GND"
						(effects
							(font
								(size 1.27 1.27)
							)
						)
					)
					(number "63"
						(effects
							(font
								(size 1.27 1.27)
							)
						)
					)
				)
				(pin no_connect line
					(at 30.48 -99.06 180)
					(length 2.54)
					(name "RFU"
						(effects
							(font
								(size 1.27 1.27)
							)
						)
					)
					(number "64"
						(effects
							(font
								(size 1.27 1.27)
							)
						)
					)
				)
				(pin output line
					(at 0 -48.26 0)
					(length 2.54)
					(name "PER1_P"
						(effects
							(font
								(size 1.27 1.27)
							)
						)
					)
					(number "65"
						(effects
							(font
								(size 1.27 1.27)
							)
						)
					)
				)
				(pin bidirectional line
					(at 0 -55.88 0)
					(length 2.54)
					(name "UIM_SWP"
						(effects
							(font
								(size 1.27 1.27)
							)
						)
					)
					(number "66"
						(effects
							(font
								(size 1.27 1.27)
							)
						)
					)
				)
				(pin output line
					(at 0 -50.8 0)
					(length 2.54)
					(name "PER1_N"
						(effects
							(font
								(size 1.27 1.27)
							)
						)
					)
					(number "67"
						(effects
							(font
								(size 1.27 1.27)
							)
						)
					)
				)
				(pin bidirectional line
					(at 0 -58.42 0)
					(length 2.54)
					(name "UIM_POWER_SNK"
						(effects
							(font
								(size 1.27 1.27)
							)
						)
					)
					(number "68"
						(effects
							(font
								(size 1.27 1.27)
							)
						)
					)
				)
				(pin passive line
					(at 30.48 -106.68 180)
					(length 2.54) hide
					(name "GND"
						(effects
							(font
								(size 1.27 1.27)
							)
						)
					)
					(number "69"
						(effects
							(font
								(size 1.27 1.27)
							)
						)
					)
				)
				(pin passive line
					(at 30.48 -106.68 180)
					(length 2.54) hide
					(name "GND"
						(effects
							(font
								(size 1.27 1.27)
							)
						)
					)
					(number "7"
						(effects
							(font
								(size 1.27 1.27)
							)
						)
					)
				)
				(pin bidirectional line
					(at 0 -60.96 0)
					(length 2.54)
					(name "UIM_POWER_SRC"
						(effects
							(font
								(size 1.27 1.27)
							)
						)
					)
					(number "70"
						(effects
							(font
								(size 1.27 1.27)
							)
						)
					)
				)
				(pin input line
					(at 0 -33.02 0)
					(length 2.54)
					(name "REFCLK1_P"
						(effects
							(font
								(size 1.27 1.27)
							)
						)
					)
					(number "71"
						(effects
							(font
								(size 1.27 1.27)
							)
						)
					)
				)
				(pin passive line
					(at 30.48 0 180)
					(length 2.54) hide
					(name "3.3V"
						(effects
							(font
								(size 1.27 1.27)
							)
						)
					)
					(number "72"
						(effects
							(font
								(size 1.27 1.27)
							)
						)
					)
				)
				(pin input line
					(at 0 -35.56 0)
					(length 2.54)
					(name "REFCLK1_N"
						(effects
							(font
								(size 1.27 1.27)
							)
						)
					)
					(number "73"
						(effects
							(font
								(size 1.27 1.27)
							)
						)
					)
				)
				(pin passive line
					(at 30.48 0 180)
					(length 2.54) hide
					(name "3.3V"
						(effects
							(font
								(size 1.27 1.27)
							)
						)
					)
					(number "74"
						(effects
							(font
								(size 1.27 1.27)
							)
						)
					)
				)
				(pin passive line
					(at 30.48 -106.68 180)
					(length 2.54) hide
					(name "GND"
						(effects
							(font
								(size 1.27 1.27)
							)
						)
					)
					(number "75"
						(effects
							(font
								(size 1.27 1.27)
							)
						)
					)
				)
				(pin bidirectional line
					(at 0 -66.04 0)
					(length 2.54)
					(name "PCM_CLK"
						(effects
							(font
								(size 1.27 1.27)
							)
						)
					)
					(number "8"
						(effects
							(font
								(size 1.27 1.27)
							)
						)
					)
				)
				(pin input line
					(at 0 -86.36 0)
					(length 2.54)
					(name "SDIO_CLK"
						(effects
							(font
								(size 1.27 1.27)
							)
						)
					)
					(number "9"
						(effects
							(font
								(size 1.27 1.27)
							)
						)
					)
				)
				(pin passive line
					(at 30.48 -104.14 180)
					(length 2.54)
					(name "MP"
						(effects
							(font
								(size 1.27 1.27)
							)
						)
					)
					(number "MP"
						(effects
							(font
								(size 1.27 1.27)
							)
						)
					)
				)
			)
		)
	(symbol "antmicroPushbuttonSwitches:SW_KMR211NGLFS_SMD"
			(pin_names hide)
			(exclude_from_sim no)
			(in_bom yes)
			(on_board yes)
			(property "Reference" "SW"
				(at 25.4 -2.54 0)
				(effects
					(font
						(size 1.27 1.27)
						(thickness 0.15)
					)
					(justify left bottom)
				)
			)
			(property "Value" "SW_KMR211NGLFS_SMD"
				(at 25.4 -7.62 0)
				(effects
					(font
						(size 1.27 1.27)
						(thickness 0.15)
					)
					(justify left bottom)
					(hide yes)
				)
			)
			(property "Footprint" "antmicro-footprints:SW_KMR211NGLFS_SMD"
				(at 25.4 -10.16 0)
				(effects
					(font
						(size 1.27 1.27)
						(thickness 0.15)
					)
					(justify left bottom)
					(hide yes)
				)
			)
			(property "Datasheet" "http://www.farnell.com/datasheets/2631211.pdf"
				(at 25.4 -12.7 0)
				(effects
					(font
						(size 1.27 1.27)
						(thickness 0.15)
					)
					(justify left bottom)
					(hide yes)
				)
			)
			(property "Description" "Tactile Switch, KMR 2 Series, Top Actuated, Surface Mount, Oval Button, 120 gf, 50mA at 32VDC"
				(at 0 0 0)
				(effects
					(font
						(size 1.27 1.27)
					)
					(hide yes)
				)
			)
			(property "MPN" "KMR211NGLFS"
				(at 25.4 -5.08 0)
				(effects
					(font
						(size 1.27 1.27)
						(thickness 0.15)
					)
					(justify left bottom)
				)
			)
			(property "Manufacturer" "C&K"
				(at 25.4 -15.24 0)
				(effects
					(font
						(size 1.27 1.27)
						(thickness 0.15)
					)
					(justify left bottom)
					(hide yes)
				)
			)
			(property "Author" "Antmicro"
				(at 25.4 -17.78 0)
				(effects
					(font
						(size 1.27 1.27)
						(thickness 0.15)
					)
					(justify left bottom)
					(hide yes)
				)
			)
			(property "License" "Apache-2.0"
				(at 25.4 -20.32 0)
				(effects
					(font
						(size 1.27 1.27)
						(thickness 0.15)
					)
					(justify left bottom)
					(hide yes)
				)
			)
			(property "ki_keywords" "VERTICAL, SMT, SWITCH, MECHANICAL, TACTILE"
				(at 0 0 0)
				(effects
					(font
						(size 1.27 1.27)
					)
					(hide yes)
				)
			)
			(symbol "SW_KMR211NGLFS_SMD_1_1"
				(polyline
					(pts
						(xy 2.54 -2.54) (xy 3.302 -2.54)
					)
					(stroke
						(width 0.254)
						(type default)
					)
					(fill
						(type none)
					)
				)
				(polyline
					(pts
						(xy 2.54 0) (xy 3.302 0)
					)
					(stroke
						(width 0.254)
						(type default)
					)
					(fill
						(type none)
					)
				)
				(polyline
					(pts
						(xy 3.302 1.27) (xy 6.858 1.27)
					)
					(stroke
						(width 0.254)
						(type default)
					)
					(fill
						(type none)
					)
				)
				(polyline
					(pts
						(xy 3.556 -0.3048) (xy 3.556 -2.1844)
					)
					(stroke
						(width 0.254)
						(type default)
					)
					(fill
						(type none)
					)
				)
				(polyline
					(pts
						(xy 4.064 2.794) (xy 6.096 2.794)
					)
					(stroke
						(width 0.254)
						(type default)
					)
					(fill
						(type none)
					)
				)
				(polyline
					(pts
						(xy 5.08 1.27) (xy 5.08 2.794)
					)
					(stroke
						(width 0.254)
						(type default)
					)
					(fill
						(type none)
					)
				)
				(polyline
					(pts
						(xy 6.604 -0.254) (xy 6.604 -2.1844)
					)
					(stroke
						(width 0.254)
						(type default)
					)
					(fill
						(type none)
					)
				)
				(polyline
					(pts
						(xy 7.62 -2.54) (xy 6.858 -2.54)
					)
					(stroke
						(width 0.254)
						(type default)
					)
					(fill
						(type none)
					)
				)
				(polyline
					(pts
						(xy 7.62 0) (xy 6.858 0)
					)
					(stroke
						(width 0.254)
						(type default)
					)
					(fill
						(type none)
					)
				)
				(circle
					(center 3.556 -2.54)
					(radius 0.254)
					(stroke
						(width 0.254)
						(type default)
					)
					(fill
						(type none)
					)
				)
				(circle
					(center 3.556 0)
					(radius 0.254)
					(stroke
						(width 0.254)
						(type default)
					)
					(fill
						(type none)
					)
				)
				(circle
					(center 6.604 -2.54)
					(radius 0.254)
					(stroke
						(width 0.254)
						(type default)
					)
					(fill
						(type none)
					)
				)
				(circle
					(center 6.604 0)
					(radius 0.254)
					(stroke
						(width 0.254)
						(type default)
					)
					(fill
						(type none)
					)
				)
				(pin passive line
					(at 0 0 0)
					(length 2.54)
					(name "1"
						(effects
							(font
								(size 1.27 1.27)
							)
						)
					)
					(number "1"
						(effects
							(font
								(size 1.27 1.27)
							)
						)
					)
				)
				(pin passive line
					(at 0 -2.54 0)
					(length 2.54)
					(name "2"
						(effects
							(font
								(size 1.27 1.27)
							)
						)
					)
					(number "2"
						(effects
							(font
								(size 1.27 1.27)
							)
						)
					)
				)
				(pin passive line
					(at 10.16 0 180)
					(length 2.54)
					(name "3"
						(effects
							(font
								(size 1.27 1.27)
							)
						)
					)
					(number "3"
						(effects
							(font
								(size 1.27 1.27)
							)
						)
					)
				)
				(pin passive line
					(at 10.16 -2.54 180)
					(length 2.54)
					(name "4"
						(effects
							(font
								(size 1.27 1.27)
							)
						)
					)
					(number "4"
						(effects
							(font
								(size 1.27 1.27)
							)
						)
					)
				)
			)
		)
	(symbol "antmicroResistorNetworksArrays:R_4x0R_0201_array"
			(pin_names hide)
			(exclude_from_sim no)
			(in_bom yes)
			(on_board yes)
			(property "Reference" "R"
				(at 26.67 -5.08 0)
				(effects
					(font
						(size 1.27 1.27)
						(thickness 0.15)
					)
					(justify left bottom)
				)
			)
			(property "Value" "R_4x0R_0201_array"
				(at 26.67 -7.62 0)
				(effects
					(font
						(size 1.27 1.27)
						(thickness 0.15)
					)
					(justify left bottom)
					(hide yes)
				)
			)
			(property "Footprint" "antmicro-footprints:R_Array_4x0201_Panasonic_EXB18V"
				(at 26.67 -12.7 0)
				(effects
					(font
						(size 1.27 1.27)
						(thickness 0.15)
					)
					(justify left bottom)
					(hide yes)
				)
			)
			(property "Datasheet" "http://industrial.panasonic.com/cdbs/www-data/pdf/AOC0000/AOC0000C14.pdf"
				(at 26.67 -15.24 0)
				(effects
					(font
						(size 1.27 1.27)
						(thickness 0.15)
					)
					(justify left bottom)
					(hide yes)
				)
			)
			(property "Description" "Zero Ohm Network Resistor, Jumper, 0201 [0603 Metric], Thick Film, Isolated, Flat, 4 Resistors"
				(at 0 0 0)
				(effects
					(font
						(size 1.27 1.27)
					)
					(hide yes)
				)
			)
			(property "MPN" "EXB-18VR000X"
				(at 26.67 -17.78 0)
				(effects
					(font
						(size 1.27 1.27)
						(thickness 0.15)
					)
					(justify left bottom)
					(hide yes)
				)
			)
			(property "Manufacturer" "Panasonic"
				(at 26.67 -20.32 0)
				(effects
					(font
						(size 1.27 1.27)
						(thickness 0.15)
					)
					(justify left bottom)
					(hide yes)
				)
			)
			(property "Val" "4x0R_0201"
				(at 26.67 -10.16 0)
				(effects
					(font
						(size 1.27 1.27)
						(thickness 0.15)
					)
					(justify left bottom)
				)
			)
			(property "Author" "Antmicro"
				(at 26.67 -22.86 0)
				(effects
					(font
						(size 1.27 1.27)
						(thickness 0.15)
					)
					(justify left bottom)
					(hide yes)
				)
			)
			(property "License" "Apache-2.0"
				(at 26.67 -25.4 0)
				(effects
					(font
						(size 1.27 1.27)
						(thickness 0.15)
					)
					(justify left bottom)
					(hide yes)
				)
			)
			(property "ki_keywords" "0201, SMT, RESISTOR, PASSIVE"
				(at 0 0 0)
				(effects
					(font
						(size 1.27 1.27)
					)
					(hide yes)
				)
			)
			(symbol "R_4x0R_0201_array_0_1"
				(polyline
					(pts
						(xy 2.54 -7.62) (xy 3.175 -7.62)
					)
					(stroke
						(width 0)
						(type default)
					)
					(fill
						(type none)
					)
				)
				(polyline
					(pts
						(xy 2.54 -5.08) (xy 3.175 -5.08)
					)
					(stroke
						(width 0)
						(type default)
					)
					(fill
						(type none)
					)
				)
				(polyline
					(pts
						(xy 2.54 -2.54) (xy 3.175 -2.54)
					)
					(stroke
						(width 0)
						(type default)
					)
					(fill
						(type none)
					)
				)
				(polyline
					(pts
						(xy 2.54 0) (xy 3.175 0)
					)
					(stroke
						(width 0)
						(type default)
					)
					(fill
						(type none)
					)
				)
				(polyline
					(pts
						(xy 6.985 -7.62) (xy 7.62 -7.62)
					)
					(stroke
						(width 0)
						(type default)
					)
					(fill
						(type none)
					)
				)
				(polyline
					(pts
						(xy 6.985 -5.08) (xy 7.62 -5.08)
					)
					(stroke
						(width 0)
						(type default)
					)
					(fill
						(type none)
					)
				)
				(polyline
					(pts
						(xy 6.985 -2.54) (xy 7.62 -2.54)
					)
					(stroke
						(width 0)
						(type default)
					)
					(fill
						(type none)
					)
				)
				(polyline
					(pts
						(xy 6.985 0) (xy 7.62 0)
					)
					(stroke
						(width 0)
						(type default)
					)
					(fill
						(type none)
					)
				)
				(rectangle
					(start 2.667 1.27)
					(end 7.493 -8.89)
					(stroke
						(width 0.254)
						(type default)
					)
					(fill
						(type background)
					)
				)
				(rectangle
					(start 6.985 -6.985)
					(end 3.175 -8.255)
					(stroke
						(width 0.254)
						(type default)
					)
					(fill
						(type none)
					)
				)
				(rectangle
					(start 6.985 -4.445)
					(end 3.175 -5.715)
					(stroke
						(width 0.254)
						(type default)
					)
					(fill
						(type none)
					)
				)
				(rectangle
					(start 6.985 -1.905)
					(end 3.175 -3.175)
					(stroke
						(width 0.254)
						(type default)
					)
					(fill
						(type none)
					)
				)
				(rectangle
					(start 6.985 0.635)
					(end 3.175 -0.635)
					(stroke
						(width 0.254)
						(type default)
					)
					(fill
						(type none)
					)
				)
			)
			(symbol "R_4x0R_0201_array_1_1"
				(pin passive line
					(at 0 0 0)
					(length 2.54)
					(name "R1.1"
						(effects
							(font
								(size 1.27 1.27)
							)
						)
					)
					(number "1"
						(effects
							(font
								(size 1.27 1.27)
							)
						)
					)
				)
				(pin passive line
					(at 0 -2.54 0)
					(length 2.54)
					(name "R2.1"
						(effects
							(font
								(size 1.27 1.27)
							)
						)
					)
					(number "2"
						(effects
							(font
								(size 1.27 1.27)
							)
						)
					)
				)
				(pin passive line
					(at 0 -5.08 0)
					(length 2.54)
					(name "R3.1"
						(effects
							(font
								(size 1.27 1.27)
							)
						)
					)
					(number "3"
						(effects
							(font
								(size 1.27 1.27)
							)
						)
					)
				)
				(pin passive line
					(at 0 -7.62 0)
					(length 2.54)
					(name "R4.1"
						(effects
							(font
								(size 1.27 1.27)
							)
						)
					)
					(number "4"
						(effects
							(font
								(size 1.27 1.27)
							)
						)
					)
				)
				(pin passive line
					(at 10.16 -7.62 180)
					(length 2.54)
					(name "R4.2"
						(effects
							(font
								(size 1.27 1.27)
							)
						)
					)
					(number "5"
						(effects
							(font
								(size 1.27 1.27)
							)
						)
					)
				)
				(pin passive line
					(at 10.16 -5.08 180)
					(length 2.54)
					(name "R3.2"
						(effects
							(font
								(size 1.27 1.27)
							)
						)
					)
					(number "6"
						(effects
							(font
								(size 1.27 1.27)
							)
						)
					)
				)
				(pin passive line
					(at 10.16 -2.54 180)
					(length 2.54)
					(name "R2.2"
						(effects
							(font
								(size 1.27 1.27)
							)
						)
					)
					(number "7"
						(effects
							(font
								(size 1.27 1.27)
							)
						)
					)
				)
				(pin passive line
					(at 10.16 0 180)
					(length 2.54)
					(name "R1.2"
						(effects
							(font
								(size 1.27 1.27)
							)
						)
					)
					(number "8"
						(effects
							(font
								(size 1.27 1.27)
							)
						)
					)
				)
			)
		)
	(symbol "antmicroResistorNetworksArrays:R_4x100R_0201_array"
			(pin_names hide)
			(exclude_from_sim no)
			(in_bom yes)
			(on_board yes)
			(property "Reference" "R"
				(at 26.67 -5.08 0)
				(effects
					(font
						(size 1.27 1.27)
						(thickness 0.15)
					)
					(justify left bottom)
				)
			)
			(property "Value" "R_4x100R_0201_array"
				(at 26.67 -7.62 0)
				(effects
					(font
						(size 1.27 1.27)
						(thickness 0.15)
					)
					(justify left bottom)
					(hide yes)
				)
			)
			(property "Footprint" "antmicro-footprints:R_Array_4x0201_Panasonic_EXB18V"
				(at 26.67 -12.7 0)
				(effects
					(font
						(size 1.27 1.27)
						(thickness 0.15)
					)
					(justify left bottom)
					(hide yes)
				)
			)
			(property "Datasheet" "http://industrial.panasonic.com/cdbs/www-data/pdf/AOC0000/AOC0000C14.pdf"
				(at 26.67 -15.24 0)
				(effects
					(font
						(size 1.27 1.27)
						(thickness 0.15)
					)
					(justify left bottom)
					(hide yes)
				)
			)
			(property "Description" "Fixed Network Resistor, 100 ohm, Isolated, 4 Resistors, 0502 [1406 Metric], Flat, ± 5%"
				(at 0 0 0)
				(effects
					(font
						(size 1.27 1.27)
					)
					(hide yes)
				)
			)
			(property "MPN" "EXB-18V101JX"
				(at 26.67 -17.78 0)
				(effects
					(font
						(size 1.27 1.27)
						(thickness 0.15)
					)
					(justify left bottom)
					(hide yes)
				)
			)
			(property "Manufacturer" "Panasonic"
				(at 26.67 -20.32 0)
				(effects
					(font
						(size 1.27 1.27)
						(thickness 0.15)
					)
					(justify left bottom)
					(hide yes)
				)
			)
			(property "Val" "R_4x100R_0201"
				(at 26.67 -10.16 0)
				(effects
					(font
						(size 1.27 1.27)
						(thickness 0.15)
					)
					(justify left bottom)
				)
			)
			(property "Author" "Antmicro"
				(at 26.67 -22.86 0)
				(effects
					(font
						(size 1.27 1.27)
						(thickness 0.15)
					)
					(justify left bottom)
					(hide yes)
				)
			)
			(property "License" "Apache-2.0"
				(at 26.67 -25.4 0)
				(effects
					(font
						(size 1.27 1.27)
						(thickness 0.15)
					)
					(justify left bottom)
					(hide yes)
				)
			)
			(property "ki_keywords" "0201, SMT, RESISTOR, PASSIVE, ARRAY"
				(at 0 0 0)
				(effects
					(font
						(size 1.27 1.27)
					)
					(hide yes)
				)
			)
			(symbol "R_4x100R_0201_array_0_1"
				(polyline
					(pts
						(xy 2.54 -7.62) (xy 3.175 -7.62)
					)
					(stroke
						(width 0)
						(type default)
					)
					(fill
						(type none)
					)
				)
				(polyline
					(pts
						(xy 2.54 -5.08) (xy 3.175 -5.08)
					)
					(stroke
						(width 0)
						(type default)
					)
					(fill
						(type none)
					)
				)
				(polyline
					(pts
						(xy 2.54 -2.54) (xy 3.175 -2.54)
					)
					(stroke
						(width 0)
						(type default)
					)
					(fill
						(type none)
					)
				)
				(polyline
					(pts
						(xy 2.54 0) (xy 3.175 0)
					)
					(stroke
						(width 0)
						(type default)
					)
					(fill
						(type none)
					)
				)
				(polyline
					(pts
						(xy 6.985 -7.62) (xy 7.62 -7.62)
					)
					(stroke
						(width 0)
						(type default)
					)
					(fill
						(type none)
					)
				)
				(polyline
					(pts
						(xy 6.985 -5.08) (xy 7.62 -5.08)
					)
					(stroke
						(width 0)
						(type default)
					)
					(fill
						(type none)
					)
				)
				(polyline
					(pts
						(xy 6.985 -2.54) (xy 7.62 -2.54)
					)
					(stroke
						(width 0)
						(type default)
					)
					(fill
						(type none)
					)
				)
				(polyline
					(pts
						(xy 6.985 0) (xy 7.62 0)
					)
					(stroke
						(width 0)
						(type default)
					)
					(fill
						(type none)
					)
				)
				(rectangle
					(start 2.667 1.27)
					(end 7.493 -8.89)
					(stroke
						(width 0.254)
						(type default)
					)
					(fill
						(type background)
					)
				)
				(rectangle
					(start 6.985 -6.985)
					(end 3.175 -8.255)
					(stroke
						(width 0.254)
						(type default)
					)
					(fill
						(type none)
					)
				)
				(rectangle
					(start 6.985 -4.445)
					(end 3.175 -5.715)
					(stroke
						(width 0.254)
						(type default)
					)
					(fill
						(type none)
					)
				)
				(rectangle
					(start 6.985 -1.905)
					(end 3.175 -3.175)
					(stroke
						(width 0.254)
						(type default)
					)
					(fill
						(type none)
					)
				)
				(rectangle
					(start 6.985 0.635)
					(end 3.175 -0.635)
					(stroke
						(width 0.254)
						(type default)
					)
					(fill
						(type none)
					)
				)
			)
			(symbol "R_4x100R_0201_array_1_1"
				(pin passive line
					(at 0 0 0)
					(length 2.54)
					(name "R1.1"
						(effects
							(font
								(size 1.27 1.27)
							)
						)
					)
					(number "1"
						(effects
							(font
								(size 1.27 1.27)
							)
						)
					)
				)
				(pin passive line
					(at 0 -2.54 0)
					(length 2.54)
					(name "R2.1"
						(effects
							(font
								(size 1.27 1.27)
							)
						)
					)
					(number "2"
						(effects
							(font
								(size 1.27 1.27)
							)
						)
					)
				)
				(pin passive line
					(at 0 -5.08 0)
					(length 2.54)
					(name "R3.1"
						(effects
							(font
								(size 1.27 1.27)
							)
						)
					)
					(number "3"
						(effects
							(font
								(size 1.27 1.27)
							)
						)
					)
				)
				(pin passive line
					(at 0 -7.62 0)
					(length 2.54)
					(name "R4.1"
						(effects
							(font
								(size 1.27 1.27)
							)
						)
					)
					(number "4"
						(effects
							(font
								(size 1.27 1.27)
							)
						)
					)
				)
				(pin passive line
					(at 10.16 -7.62 180)
					(length 2.54)
					(name "R4.2"
						(effects
							(font
								(size 1.27 1.27)
							)
						)
					)
					(number "5"
						(effects
							(font
								(size 1.27 1.27)
							)
						)
					)
				)
				(pin passive line
					(at 10.16 -5.08 180)
					(length 2.54)
					(name "R3.2"
						(effects
							(font
								(size 1.27 1.27)
							)
						)
					)
					(number "6"
						(effects
							(font
								(size 1.27 1.27)
							)
						)
					)
				)
				(pin passive line
					(at 10.16 -2.54 180)
					(length 2.54)
					(name "R2.2"
						(effects
							(font
								(size 1.27 1.27)
							)
						)
					)
					(number "7"
						(effects
							(font
								(size 1.27 1.27)
							)
						)
					)
				)
				(pin passive line
					(at 10.16 0 180)
					(length 2.54)
					(name "R1.2"
						(effects
							(font
								(size 1.27 1.27)
							)
						)
					)
					(number "8"
						(effects
							(font
								(size 1.27 1.27)
							)
						)
					)
				)
			)
		)
	(symbol "antmicroResistorNetworksArrays:R_4x2k2_0201_array"
			(pin_names hide)
			(exclude_from_sim no)
			(in_bom yes)
			(on_board yes)
			(property "Reference" "R"
				(at 26.67 -5.08 0)
				(effects
					(font
						(size 1.27 1.27)
						(thickness 0.15)
					)
					(justify left bottom)
				)
			)
			(property "Value" "R_4x2k2_0201_array"
				(at 26.67 -7.62 0)
				(effects
					(font
						(size 1.27 1.27)
						(thickness 0.15)
					)
					(justify left bottom)
					(hide yes)
				)
			)
			(property "Footprint" "antmicro-footprints:R_Array_4x0201_Panasonic_EXB18V"
				(at 26.67 -12.7 0)
				(effects
					(font
						(size 1.27 1.27)
						(thickness 0.15)
					)
					(justify left bottom)
					(hide yes)
				)
			)
			(property "Datasheet" "http://industrial.panasonic.com/cdbs/www-data/pdf/AOC0000/AOC0000C14.pdf"
				(at 26.67 -15.24 0)
				(effects
					(font
						(size 1.27 1.27)
						(thickness 0.15)
					)
					(justify left bottom)
					(hide yes)
				)
			)
			(property "Description" "Fixed Network Resistor, 2.2 kohm, Isolated, 4 Resistors, 0502 [1406 Metric], Flat, ± 5%"
				(at 0 0 0)
				(effects
					(font
						(size 1.27 1.27)
					)
					(hide yes)
				)
			)
			(property "MPN" "EXB-18V222JX"
				(at 26.67 -17.78 0)
				(effects
					(font
						(size 1.27 1.27)
						(thickness 0.15)
					)
					(justify left bottom)
					(hide yes)
				)
			)
			(property "Manufacturer" "Panasonic"
				(at 26.67 -20.32 0)
				(effects
					(font
						(size 1.27 1.27)
						(thickness 0.15)
					)
					(justify left bottom)
					(hide yes)
				)
			)
			(property "Val" "4x2k2_0201"
				(at 26.67 -10.16 0)
				(effects
					(font
						(size 1.27 1.27)
						(thickness 0.15)
					)
					(justify left bottom)
				)
			)
			(property "Author" "Antmicro"
				(at 26.67 -22.86 0)
				(effects
					(font
						(size 1.27 1.27)
						(thickness 0.15)
					)
					(justify left bottom)
					(hide yes)
				)
			)
			(property "License" "Apache-2.0"
				(at 26.67 -25.4 0)
				(effects
					(font
						(size 1.27 1.27)
						(thickness 0.15)
					)
					(justify left bottom)
					(hide yes)
				)
			)
			(property "ki_keywords" "0201, SMT, RESISTOR, PASSIVE"
				(at 0 0 0)
				(effects
					(font
						(size 1.27 1.27)
					)
					(hide yes)
				)
			)
			(symbol "R_4x2k2_0201_array_0_1"
				(polyline
					(pts
						(xy 2.54 -7.62) (xy 3.175 -7.62)
					)
					(stroke
						(width 0)
						(type default)
					)
					(fill
						(type none)
					)
				)
				(polyline
					(pts
						(xy 2.54 -5.08) (xy 3.175 -5.08)
					)
					(stroke
						(width 0)
						(type default)
					)
					(fill
						(type none)
					)
				)
				(polyline
					(pts
						(xy 2.54 -2.54) (xy 3.175 -2.54)
					)
					(stroke
						(width 0)
						(type default)
					)
					(fill
						(type none)
					)
				)
				(polyline
					(pts
						(xy 2.54 0) (xy 3.175 0)
					)
					(stroke
						(width 0)
						(type default)
					)
					(fill
						(type none)
					)
				)
				(polyline
					(pts
						(xy 6.985 -7.62) (xy 7.62 -7.62)
					)
					(stroke
						(width 0)
						(type default)
					)
					(fill
						(type none)
					)
				)
				(polyline
					(pts
						(xy 6.985 -5.08) (xy 7.62 -5.08)
					)
					(stroke
						(width 0)
						(type default)
					)
					(fill
						(type none)
					)
				)
				(polyline
					(pts
						(xy 6.985 -2.54) (xy 7.62 -2.54)
					)
					(stroke
						(width 0)
						(type default)
					)
					(fill
						(type none)
					)
				)
				(polyline
					(pts
						(xy 6.985 0) (xy 7.62 0)
					)
					(stroke
						(width 0)
						(type default)
					)
					(fill
						(type none)
					)
				)
				(rectangle
					(start 2.667 1.27)
					(end 7.493 -8.89)
					(stroke
						(width 0.254)
						(type default)
					)
					(fill
						(type background)
					)
				)
				(rectangle
					(start 6.985 -6.985)
					(end 3.175 -8.255)
					(stroke
						(width 0.254)
						(type default)
					)
					(fill
						(type none)
					)
				)
				(rectangle
					(start 6.985 -4.445)
					(end 3.175 -5.715)
					(stroke
						(width 0.254)
						(type default)
					)
					(fill
						(type none)
					)
				)
				(rectangle
					(start 6.985 -1.905)
					(end 3.175 -3.175)
					(stroke
						(width 0.254)
						(type default)
					)
					(fill
						(type none)
					)
				)
				(rectangle
					(start 6.985 0.635)
					(end 3.175 -0.635)
					(stroke
						(width 0.254)
						(type default)
					)
					(fill
						(type none)
					)
				)
			)
			(symbol "R_4x2k2_0201_array_1_1"
				(pin passive line
					(at 0 0 0)
					(length 2.54)
					(name "R1.1"
						(effects
							(font
								(size 1.27 1.27)
							)
						)
					)
					(number "1"
						(effects
							(font
								(size 1.27 1.27)
							)
						)
					)
				)
				(pin passive line
					(at 0 -2.54 0)
					(length 2.54)
					(name "R2.1"
						(effects
							(font
								(size 1.27 1.27)
							)
						)
					)
					(number "2"
						(effects
							(font
								(size 1.27 1.27)
							)
						)
					)
				)
				(pin passive line
					(at 0 -5.08 0)
					(length 2.54)
					(name "R3.1"
						(effects
							(font
								(size 1.27 1.27)
							)
						)
					)
					(number "3"
						(effects
							(font
								(size 1.27 1.27)
							)
						)
					)
				)
				(pin passive line
					(at 0 -7.62 0)
					(length 2.54)
					(name "R4.1"
						(effects
							(font
								(size 1.27 1.27)
							)
						)
					)
					(number "4"
						(effects
							(font
								(size 1.27 1.27)
							)
						)
					)
				)
				(pin passive line
					(at 10.16 -7.62 180)
					(length 2.54)
					(name "R4.2"
						(effects
							(font
								(size 1.27 1.27)
							)
						)
					)
					(number "5"
						(effects
							(font
								(size 1.27 1.27)
							)
						)
					)
				)
				(pin passive line
					(at 10.16 -5.08 180)
					(length 2.54)
					(name "R3.2"
						(effects
							(font
								(size 1.27 1.27)
							)
						)
					)
					(number "6"
						(effects
							(font
								(size 1.27 1.27)
							)
						)
					)
				)
				(pin passive line
					(at 10.16 -2.54 180)
					(length 2.54)
					(name "R2.2"
						(effects
							(font
								(size 1.27 1.27)
							)
						)
					)
					(number "7"
						(effects
							(font
								(size 1.27 1.27)
							)
						)
					)
				)
				(pin passive line
					(at 10.16 0 180)
					(length 2.54)
					(name "R1.2"
						(effects
							(font
								(size 1.27 1.27)
							)
						)
					)
					(number "8"
						(effects
							(font
								(size 1.27 1.27)
							)
						)
					)
				)
			)
		)
	(symbol "antmicroResistorNetworksArrays:R_4x330R_0402_array"
			(pin_names hide)
			(exclude_from_sim no)
			(in_bom yes)
			(on_board yes)
			(property "Reference" "R"
				(at 26.67 -2.54 0)
				(effects
					(font
						(size 1.27 1.27)
						(thickness 0.15)
					)
					(justify left bottom)
				)
			)
			(property "Value" "R_4x330R_0402_array"
				(at 26.67 -5.08 0)
				(effects
					(font
						(size 1.27 1.27)
						(thickness 0.15)
					)
					(justify left bottom)
					(hide yes)
				)
			)
			(property "Footprint" "antmicro-footprints:R_Array_4x0402"
				(at 26.67 -10.16 0)
				(effects
					(font
						(size 1.27 1.27)
						(thickness 0.15)
					)
					(justify left bottom)
					(hide yes)
				)
			)
			(property "Datasheet" "http://industrial.panasonic.com/cdbs/www-data/pdf/AOC0000/AOC0000C14.pdf"
				(at 26.67 -12.7 0)
				(effects
					(font
						(size 1.27 1.27)
						(thickness 0.15)
					)
					(justify left bottom)
					(hide yes)
				)
			)
			(property "Description" "Fixed Network Resistor, 330 ohm, Isolated, 4 Resistors, 0804 [2010 Metric], Convex, ± 5%"
				(at 0 0 0)
				(effects
					(font
						(size 1.27 1.27)
					)
					(hide yes)
				)
			)
			(property "MPN" "EXB-28V331JX"
				(at 26.67 -15.24 0)
				(effects
					(font
						(size 1.27 1.27)
						(thickness 0.15)
					)
					(justify left bottom)
					(hide yes)
				)
			)
			(property "Manufacturer" "Panasonic"
				(at 26.67 -17.78 0)
				(effects
					(font
						(size 1.27 1.27)
						(thickness 0.15)
					)
					(justify left bottom)
					(hide yes)
				)
			)
			(property "Author" "Antmicro"
				(at 26.67 -20.32 0)
				(effects
					(font
						(size 1.27 1.27)
						(thickness 0.15)
					)
					(justify left bottom)
					(hide yes)
				)
			)
			(property "License" "Apache-2.0"
				(at 26.67 -22.86 0)
				(effects
					(font
						(size 1.27 1.27)
						(thickness 0.15)
					)
					(justify left bottom)
					(hide yes)
				)
			)
			(property "Val" "R_4x330R_0402"
				(at 26.67 -7.62 0)
				(effects
					(font
						(size 1.27 1.27)
					)
					(justify left bottom)
				)
			)
			(property "ki_keywords" "0402, SMT, RESISTOR, PASSIVE"
				(at 0 0 0)
				(effects
					(font
						(size 1.27 1.27)
					)
					(hide yes)
				)
			)
			(symbol "R_4x330R_0402_array_0_1"
				(polyline
					(pts
						(xy 2.54 -7.62) (xy 3.175 -7.62)
					)
					(stroke
						(width 0)
						(type default)
					)
					(fill
						(type none)
					)
				)
				(polyline
					(pts
						(xy 2.54 -5.08) (xy 3.175 -5.08)
					)
					(stroke
						(width 0)
						(type default)
					)
					(fill
						(type none)
					)
				)
				(polyline
					(pts
						(xy 2.54 -2.54) (xy 3.175 -2.54)
					)
					(stroke
						(width 0)
						(type default)
					)
					(fill
						(type none)
					)
				)
				(polyline
					(pts
						(xy 2.54 0) (xy 3.175 0)
					)
					(stroke
						(width 0)
						(type default)
					)
					(fill
						(type none)
					)
				)
				(polyline
					(pts
						(xy 6.985 -7.62) (xy 7.62 -7.62)
					)
					(stroke
						(width 0)
						(type default)
					)
					(fill
						(type none)
					)
				)
				(polyline
					(pts
						(xy 6.985 -5.08) (xy 7.62 -5.08)
					)
					(stroke
						(width 0)
						(type default)
					)
					(fill
						(type none)
					)
				)
				(polyline
					(pts
						(xy 6.985 -2.54) (xy 7.62 -2.54)
					)
					(stroke
						(width 0)
						(type default)
					)
					(fill
						(type none)
					)
				)
				(polyline
					(pts
						(xy 6.985 0) (xy 7.62 0)
					)
					(stroke
						(width 0)
						(type default)
					)
					(fill
						(type none)
					)
				)
				(rectangle
					(start 2.667 1.27)
					(end 7.493 -8.89)
					(stroke
						(width 0.254)
						(type default)
					)
					(fill
						(type background)
					)
				)
				(rectangle
					(start 6.985 -6.985)
					(end 3.175 -8.255)
					(stroke
						(width 0.254)
						(type default)
					)
					(fill
						(type none)
					)
				)
				(rectangle
					(start 6.985 -4.445)
					(end 3.175 -5.715)
					(stroke
						(width 0.254)
						(type default)
					)
					(fill
						(type none)
					)
				)
				(rectangle
					(start 6.985 -1.905)
					(end 3.175 -3.175)
					(stroke
						(width 0.254)
						(type default)
					)
					(fill
						(type none)
					)
				)
				(rectangle
					(start 6.985 0.635)
					(end 3.175 -0.635)
					(stroke
						(width 0.254)
						(type default)
					)
					(fill
						(type none)
					)
				)
			)
			(symbol "R_4x330R_0402_array_1_1"
				(pin passive line
					(at 0 0 0)
					(length 2.54)
					(name "R1.1"
						(effects
							(font
								(size 1.27 1.27)
							)
						)
					)
					(number "1"
						(effects
							(font
								(size 1.27 1.27)
							)
						)
					)
				)
				(pin passive line
					(at 0 -2.54 0)
					(length 2.54)
					(name "R2.1"
						(effects
							(font
								(size 1.27 1.27)
							)
						)
					)
					(number "2"
						(effects
							(font
								(size 1.27 1.27)
							)
						)
					)
				)
				(pin passive line
					(at 0 -5.08 0)
					(length 2.54)
					(name "R3.1"
						(effects
							(font
								(size 1.27 1.27)
							)
						)
					)
					(number "3"
						(effects
							(font
								(size 1.27 1.27)
							)
						)
					)
				)
				(pin passive line
					(at 0 -7.62 0)
					(length 2.54)
					(name "R4.1"
						(effects
							(font
								(size 1.27 1.27)
							)
						)
					)
					(number "4"
						(effects
							(font
								(size 1.27 1.27)
							)
						)
					)
				)
				(pin passive line
					(at 10.16 -7.62 180)
					(length 2.54)
					(name "R4.2"
						(effects
							(font
								(size 1.27 1.27)
							)
						)
					)
					(number "5"
						(effects
							(font
								(size 1.27 1.27)
							)
						)
					)
				)
				(pin passive line
					(at 10.16 -5.08 180)
					(length 2.54)
					(name "R3.2"
						(effects
							(font
								(size 1.27 1.27)
							)
						)
					)
					(number "6"
						(effects
							(font
								(size 1.27 1.27)
							)
						)
					)
				)
				(pin passive line
					(at 10.16 -2.54 180)
					(length 2.54)
					(name "R2.2"
						(effects
							(font
								(size 1.27 1.27)
							)
						)
					)
					(number "7"
						(effects
							(font
								(size 1.27 1.27)
							)
						)
					)
				)
				(pin passive line
					(at 10.16 0 180)
					(length 2.54)
					(name "R1.2"
						(effects
							(font
								(size 1.27 1.27)
							)
						)
					)
					(number "8"
						(effects
							(font
								(size 1.27 1.27)
							)
						)
					)
				)
			)
		)
	(symbol "antmicroResistors0402:R_0R_0402"
			(pin_numbers hide)
			(pin_names hide)
			(exclude_from_sim no)
			(in_bom yes)
			(on_board yes)
			(property "Reference" "R"
				(at 20.32 -5.08 0)
				(effects
					(font
						(size 1.27 1.27)
						(thickness 0.15)
					)
					(justify left bottom)
				)
			)
			(property "Value" "R_0R_0402"
				(at 20.32 -12.7 0)
				(effects
					(font
						(size 1.27 1.27)
						(thickness 0.15)
					)
					(justify left bottom)
					(hide yes)
				)
			)
			(property "Footprint" "antmicro-footprints:R_0402_1005Metric"
				(at 20.32 -15.24 0)
				(effects
					(font
						(size 1.27 1.27)
						(thickness 0.15)
					)
					(justify left bottom)
					(hide yes)
				)
			)
			(property "Datasheet" "https://industrial.panasonic.com/cdbs/www-data/pdf/RDA0000/AOA0000C301.pdf"
				(at 20.32 -17.78 0)
				(effects
					(font
						(size 1.27 1.27)
						(thickness 0.15)
					)
					(justify left bottom)
					(hide yes)
				)
			)
			(property "Description" "SMD Chip Resistor, Jumper, 0 ohm, 100 mW, 0402 [1005 Metric], Thick Film, General Purpose"
				(at 0 0 0)
				(effects
					(font
						(size 1.27 1.27)
					)
					(hide yes)
				)
			)
			(property "MPN" "ERJ2GE0R00X"
				(at 20.32 -20.32 0)
				(effects
					(font
						(size 1.27 1.27)
						(thickness 0.15)
					)
					(justify left bottom)
					(hide yes)
				)
			)
			(property "Manufacturer" "Panasonic"
				(at 20.32 -22.86 0)
				(effects
					(font
						(size 1.27 1.27)
						(thickness 0.15)
					)
					(justify left bottom)
					(hide yes)
				)
			)
			(property "License" "Apache-2.0"
				(at 20.32 -25.4 0)
				(effects
					(font
						(size 1.27 1.27)
						(thickness 0.15)
					)
					(justify left bottom)
					(hide yes)
				)
			)
			(property "Author" "Antmicro"
				(at 20.32 -27.94 0)
				(effects
					(font
						(size 1.27 1.27)
						(thickness 0.15)
					)
					(justify left bottom)
					(hide yes)
				)
			)
			(property "Val" "0R"
				(at 20.32 -7.62 0)
				(effects
					(font
						(size 1.27 1.27)
						(thickness 0.15)
					)
					(justify left bottom)
				)
			)
			(property "Tolerance" "~"
				(at 20.32 -10.16 0)
				(effects
					(font
						(size 1.27 1.27)
					)
					(justify left bottom)
					(hide yes)
				)
			)
			(property "Current" "1A"
				(at 20.32 -30.48 0)
				(effects
					(font
						(size 1.27 1.27)
						(thickness 0.15)
					)
					(justify left bottom)
					(hide yes)
				)
			)
			(property "ki_keywords" "0402, SMT, RESISTOR, PASSIVE"
				(at 0 0 0)
				(effects
					(font
						(size 1.27 1.27)
					)
					(hide yes)
				)
			)
			(symbol "R_0R_0402_0_1"
				(rectangle
					(start 0.635 0.889)
					(end 4.445 -0.889)
					(stroke
						(width 0.254)
						(type default)
					)
					(fill
						(type none)
					)
				)
			)
			(symbol "R_0R_0402_1_1"
				(pin passive line
					(at 0 0 0)
					(length 0.635)
					(name "~"
						(effects
							(font
								(size 1.27 1.27)
							)
						)
					)
					(number "1"
						(effects
							(font
								(size 1.27 1.27)
							)
						)
					)
				)
				(pin passive line
					(at 5.08 0 180)
					(length 0.635)
					(name "~"
						(effects
							(font
								(size 1.27 1.27)
							)
						)
					)
					(number "2"
						(effects
							(font
								(size 1.27 1.27)
							)
						)
					)
				)
			)
		)
	(symbol "antmicroResistors0402:R_100k_0402"
			(pin_numbers hide)
			(pin_names hide)
			(exclude_from_sim no)
			(in_bom yes)
			(on_board yes)
			(property "Reference" "R"
				(at 20.32 -5.08 0)
				(effects
					(font
						(size 1.27 1.27)
						(thickness 0.15)
					)
					(justify left bottom)
				)
			)
			(property "Value" "R_100k_0402"
				(at 20.32 -12.7 0)
				(effects
					(font
						(size 1.27 1.27)
						(thickness 0.15)
					)
					(justify left bottom)
					(hide yes)
				)
			)
			(property "Footprint" "antmicro-footprints:R_0402_1005Metric"
				(at 20.32 -15.24 0)
				(effects
					(font
						(size 1.27 1.27)
						(thickness 0.15)
					)
					(justify left bottom)
					(hide yes)
				)
			)
			(property "Datasheet" "https://www.bourns.com/docs/product-datasheets/cr.pdf"
				(at 20.32 -17.78 0)
				(effects
					(font
						(size 1.27 1.27)
						(thickness 0.15)
					)
					(justify left bottom)
					(hide yes)
				)
			)
			(property "Description" "SMD Chip Resistor, 100 kohm, ± 1%, 62.5 mW, 0402 [1005 Metric], Thick Film, General Purpose"
				(at 0 0 0)
				(effects
					(font
						(size 1.27 1.27)
					)
					(hide yes)
				)
			)
			(property "MPN" "CR0402-FX-1003GLF"
				(at 20.32 -20.32 0)
				(effects
					(font
						(size 1.27 1.27)
						(thickness 0.15)
					)
					(justify left bottom)
					(hide yes)
				)
			)
			(property "Manufacturer" "Bourns"
				(at 20.32 -22.86 0)
				(effects
					(font
						(size 1.27 1.27)
						(thickness 0.15)
					)
					(justify left bottom)
					(hide yes)
				)
			)
			(property "License" "Apache-2.0"
				(at 20.32 -25.4 0)
				(effects
					(font
						(size 1.27 1.27)
						(thickness 0.15)
					)
					(justify left bottom)
					(hide yes)
				)
			)
			(property "Author" "Antmicro"
				(at 20.32 -27.94 0)
				(effects
					(font
						(size 1.27 1.27)
						(thickness 0.15)
					)
					(justify left bottom)
					(hide yes)
				)
			)
			(property "Val" "100k"
				(at 20.32 -7.62 0)
				(effects
					(font
						(size 1.27 1.27)
						(thickness 0.15)
					)
					(justify left bottom)
				)
			)
			(property "Tolerance" "1%"
				(at 20.32 -10.16 0)
				(effects
					(font
						(size 1.27 1.27)
					)
					(justify left bottom)
					(hide yes)
				)
			)
			(property "ki_keywords" "0402, SMT, RESISTOR, PASSIVE"
				(at 0 0 0)
				(effects
					(font
						(size 1.27 1.27)
					)
					(hide yes)
				)
			)
			(symbol "R_100k_0402_0_1"
				(rectangle
					(start 0.635 0.889)
					(end 4.445 -0.889)
					(stroke
						(width 0.254)
						(type default)
					)
					(fill
						(type none)
					)
				)
			)
			(symbol "R_100k_0402_1_1"
				(pin passive line
					(at 0 0 0)
					(length 0.635)
					(name "~"
						(effects
							(font
								(size 1.27 1.27)
							)
						)
					)
					(number "1"
						(effects
							(font
								(size 1.27 1.27)
							)
						)
					)
				)
				(pin passive line
					(at 5.08 0 180)
					(length 0.635)
					(name "~"
						(effects
							(font
								(size 1.27 1.27)
							)
						)
					)
					(number "2"
						(effects
							(font
								(size 1.27 1.27)
							)
						)
					)
				)
			)
		)
	(symbol "antmicroResistors0402:R_10M_0402"
			(pin_numbers hide)
			(pin_names hide)
			(exclude_from_sim no)
			(in_bom yes)
			(on_board yes)
			(property "Reference" "R"
				(at 20.32 -5.08 0)
				(effects
					(font
						(size 1.27 1.27)
						(thickness 0.15)
					)
					(justify left bottom)
				)
			)
			(property "Value" "R_10M_0402"
				(at 20.32 -12.7 0)
				(effects
					(font
						(size 1.27 1.27)
						(thickness 0.15)
					)
					(justify left bottom)
					(hide yes)
				)
			)
			(property "Footprint" "antmicro-footprints:R_0402_1005Metric"
				(at 20.32 -15.24 0)
				(effects
					(font
						(size 1.27 1.27)
						(thickness 0.15)
					)
					(justify left bottom)
					(hide yes)
				)
			)
			(property "Datasheet" "https://www.bourns.com/docs/product-datasheets/cr.pdf"
				(at 20.32 -17.78 0)
				(effects
					(font
						(size 1.27 1.27)
						(thickness 0.15)
					)
					(justify left bottom)
					(hide yes)
				)
			)
			(property "Description" "SMD Chip Resistor"
				(at 0 0 0)
				(effects
					(font
						(size 1.27 1.27)
					)
					(hide yes)
				)
			)
			(property "MPN" "CR0402-FX-1005GLF"
				(at 20.32 -20.32 0)
				(effects
					(font
						(size 1.27 1.27)
						(thickness 0.15)
					)
					(justify left bottom)
					(hide yes)
				)
			)
			(property "Manufacturer" "Bourns"
				(at 20.32 -22.86 0)
				(effects
					(font
						(size 1.27 1.27)
						(thickness 0.15)
					)
					(justify left bottom)
					(hide yes)
				)
			)
			(property "License" "Apache-2.0"
				(at 20.32 -25.4 0)
				(effects
					(font
						(size 1.27 1.27)
						(thickness 0.15)
					)
					(justify left bottom)
					(hide yes)
				)
			)
			(property "Author" "Antmicro"
				(at 20.32 -27.94 0)
				(effects
					(font
						(size 1.27 1.27)
						(thickness 0.15)
					)
					(justify left bottom)
					(hide yes)
				)
			)
			(property "Val" "10M"
				(at 20.32 -7.62 0)
				(effects
					(font
						(size 1.27 1.27)
						(thickness 0.15)
					)
					(justify left bottom)
				)
			)
			(property "Tolerance" "1%"
				(at 20.32 -10.16 0)
				(effects
					(font
						(size 1.27 1.27)
					)
					(justify left bottom)
					(hide yes)
				)
			)
			(property "ki_keywords" "0402, SMT, RESISTOR, PASSIVE"
				(at 0 0 0)
				(effects
					(font
						(size 1.27 1.27)
					)
					(hide yes)
				)
			)
			(symbol "R_10M_0402_0_1"
				(rectangle
					(start 0.635 0.889)
					(end 4.445 -0.889)
					(stroke
						(width 0.254)
						(type default)
					)
					(fill
						(type none)
					)
				)
			)
			(symbol "R_10M_0402_1_1"
				(pin passive line
					(at 0 0 0)
					(length 0.635)
					(name "~"
						(effects
							(font
								(size 1.27 1.27)
							)
						)
					)
					(number "1"
						(effects
							(font
								(size 1.27 1.27)
							)
						)
					)
				)
				(pin passive line
					(at 5.08 0 180)
					(length 0.635)
					(name "~"
						(effects
							(font
								(size 1.27 1.27)
							)
						)
					)
					(number "2"
						(effects
							(font
								(size 1.27 1.27)
							)
						)
					)
				)
			)
		)
	(symbol "antmicroResistors0402:R_10k_0402"
			(pin_numbers hide)
			(pin_names hide)
			(exclude_from_sim no)
			(in_bom yes)
			(on_board yes)
			(property "Reference" "R"
				(at 20.32 -5.08 0)
				(effects
					(font
						(size 1.27 1.27)
						(thickness 0.15)
					)
					(justify left bottom)
				)
			)
			(property "Value" "R_10k_0402"
				(at 20.32 -12.7 0)
				(effects
					(font
						(size 1.27 1.27)
						(thickness 0.15)
					)
					(justify left bottom)
					(hide yes)
				)
			)
			(property "Footprint" "antmicro-footprints:R_0402_1005Metric"
				(at 20.32 -15.24 0)
				(effects
					(font
						(size 1.27 1.27)
						(thickness 0.15)
					)
					(justify left bottom)
					(hide yes)
				)
			)
			(property "Datasheet" "https://www.bourns.com/docs/product-datasheets/cr.pdf"
				(at 20.32 -17.78 0)
				(effects
					(font
						(size 1.27 1.27)
						(thickness 0.15)
					)
					(justify left bottom)
					(hide yes)
				)
			)
			(property "Description" "SMD Chip Resistor, 10 kohm, ± 1%, 62.5 mW, 0402 [1005 Metric], Thick Film, General Purpose"
				(at 0 0 0)
				(effects
					(font
						(size 1.27 1.27)
					)
					(hide yes)
				)
			)
			(property "MPN" "CR0402-FX-1002GLF"
				(at 20.32 -20.32 0)
				(effects
					(font
						(size 1.27 1.27)
						(thickness 0.15)
					)
					(justify left bottom)
					(hide yes)
				)
			)
			(property "Manufacturer" "Bourns"
				(at 20.32 -22.86 0)
				(effects
					(font
						(size 1.27 1.27)
						(thickness 0.15)
					)
					(justify left bottom)
					(hide yes)
				)
			)
			(property "License" "Apache-2.0"
				(at 20.32 -25.4 0)
				(effects
					(font
						(size 1.27 1.27)
						(thickness 0.15)
					)
					(justify left bottom)
					(hide yes)
				)
			)
			(property "Author" "Antmicro"
				(at 20.32 -27.94 0)
				(effects
					(font
						(size 1.27 1.27)
						(thickness 0.15)
					)
					(justify left bottom)
					(hide yes)
				)
			)
			(property "Val" "10k"
				(at 20.32 -7.62 0)
				(effects
					(font
						(size 1.27 1.27)
						(thickness 0.15)
					)
					(justify left bottom)
				)
			)
			(property "Tolerance" "1%"
				(at 20.32 -10.16 0)
				(effects
					(font
						(size 1.27 1.27)
					)
					(justify left bottom)
					(hide yes)
				)
			)
			(property "ki_keywords" "0402, SMT, RESISTOR, PASSIVE"
				(at 0 0 0)
				(effects
					(font
						(size 1.27 1.27)
					)
					(hide yes)
				)
			)
			(symbol "R_10k_0402_0_1"
				(rectangle
					(start 0.635 0.889)
					(end 4.445 -0.889)
					(stroke
						(width 0.254)
						(type default)
					)
					(fill
						(type none)
					)
				)
			)
			(symbol "R_10k_0402_1_1"
				(pin passive line
					(at 0 0 0)
					(length 0.635)
					(name "~"
						(effects
							(font
								(size 1.27 1.27)
							)
						)
					)
					(number "1"
						(effects
							(font
								(size 1.27 1.27)
							)
						)
					)
				)
				(pin passive line
					(at 5.08 0 180)
					(length 0.635)
					(name "~"
						(effects
							(font
								(size 1.27 1.27)
							)
						)
					)
					(number "2"
						(effects
							(font
								(size 1.27 1.27)
							)
						)
					)
				)
			)
		)
	(symbol "antmicroResistors0402:R_15k_0402"
			(pin_numbers hide)
			(pin_names hide)
			(exclude_from_sim no)
			(in_bom yes)
			(on_board yes)
			(property "Reference" "R"
				(at 20.32 -5.08 0)
				(effects
					(font
						(size 1.27 1.27)
						(thickness 0.15)
					)
					(justify left bottom)
				)
			)
			(property "Value" "R_15k_0402"
				(at 20.32 -12.7 0)
				(effects
					(font
						(size 1.27 1.27)
						(thickness 0.15)
					)
					(justify left bottom)
					(hide yes)
				)
			)
			(property "Footprint" "antmicro-footprints:R_0402_1005Metric"
				(at 20.32 -15.24 0)
				(effects
					(font
						(size 1.27 1.27)
						(thickness 0.15)
					)
					(justify left bottom)
					(hide yes)
				)
			)
			(property "Datasheet" "https://www.bourns.com/docs/product-datasheets/cr.pdf"
				(at 20.32 -17.78 0)
				(effects
					(font
						(size 1.27 1.27)
						(thickness 0.15)
					)
					(justify left bottom)
					(hide yes)
				)
			)
			(property "Description" "SMD Chip Resistor, 15 kohm, ± 1%, 62.5 mW, 0402 [1005 Metric], Thick Film, General Purpose"
				(at 0 0 0)
				(effects
					(font
						(size 1.27 1.27)
					)
					(hide yes)
				)
			)
			(property "MPN" "CR0402-FX-1502GLF"
				(at 20.32 -20.32 0)
				(effects
					(font
						(size 1.27 1.27)
						(thickness 0.15)
					)
					(justify left bottom)
					(hide yes)
				)
			)
			(property "Manufacturer" "Bourns"
				(at 20.32 -22.86 0)
				(effects
					(font
						(size 1.27 1.27)
						(thickness 0.15)
					)
					(justify left bottom)
					(hide yes)
				)
			)
			(property "License" "Apache-2.0"
				(at 20.32 -25.4 0)
				(effects
					(font
						(size 1.27 1.27)
						(thickness 0.15)
					)
					(justify left bottom)
					(hide yes)
				)
			)
			(property "Author" "Antmicro"
				(at 20.32 -27.94 0)
				(effects
					(font
						(size 1.27 1.27)
						(thickness 0.15)
					)
					(justify left bottom)
					(hide yes)
				)
			)
			(property "Val" "15k"
				(at 20.32 -7.62 0)
				(effects
					(font
						(size 1.27 1.27)
						(thickness 0.15)
					)
					(justify left bottom)
				)
			)
			(property "Tolerance" "1%"
				(at 20.32 -10.16 0)
				(effects
					(font
						(size 1.27 1.27)
					)
					(justify left bottom)
					(hide yes)
				)
			)
			(property "ki_keywords" "0402, SMT, RESISTOR, PASSIVE"
				(at 0 0 0)
				(effects
					(font
						(size 1.27 1.27)
					)
					(hide yes)
				)
			)
			(symbol "R_15k_0402_0_1"
				(rectangle
					(start 0.635 0.889)
					(end 4.445 -0.889)
					(stroke
						(width 0.254)
						(type default)
					)
					(fill
						(type none)
					)
				)
			)
			(symbol "R_15k_0402_1_1"
				(pin passive line
					(at 0 0 0)
					(length 0.635)
					(name "~"
						(effects
							(font
								(size 1.27 1.27)
							)
						)
					)
					(number "1"
						(effects
							(font
								(size 1.27 1.27)
							)
						)
					)
				)
				(pin passive line
					(at 5.08 0 180)
					(length 0.635)
					(name "~"
						(effects
							(font
								(size 1.27 1.27)
							)
						)
					)
					(number "2"
						(effects
							(font
								(size 1.27 1.27)
							)
						)
					)
				)
			)
		)
	(symbol "antmicroResistors0402:R_1k2_0402"
			(pin_numbers hide)
			(pin_names hide)
			(exclude_from_sim no)
			(in_bom yes)
			(on_board yes)
			(property "Reference" "R"
				(at 20.32 -5.08 0)
				(effects
					(font
						(size 1.27 1.27)
						(thickness 0.15)
					)
					(justify left bottom)
				)
			)
			(property "Value" "R_1k2_0402"
				(at 20.32 -12.7 0)
				(effects
					(font
						(size 1.27 1.27)
						(thickness 0.15)
					)
					(justify left bottom)
					(hide yes)
				)
			)
			(property "Footprint" "antmicro-footprints:R_0402_1005Metric"
				(at 20.32 -15.24 0)
				(effects
					(font
						(size 1.27 1.27)
						(thickness 0.15)
					)
					(justify left bottom)
					(hide yes)
				)
			)
			(property "Datasheet" "https://www.bourns.com/docs/product-datasheets/cr.pdf"
				(at 20.32 -17.78 0)
				(effects
					(font
						(size 1.27 1.27)
						(thickness 0.15)
					)
					(justify left bottom)
					(hide yes)
				)
			)
			(property "Description" "SMD Chip Resistor, 1.2 kohm, ± 1%, 62.5 mW, 0402 [1005 Metric], Thick Film, General Purpose"
				(at 0 0 0)
				(effects
					(font
						(size 1.27 1.27)
					)
					(hide yes)
				)
			)
			(property "MPN" "CR0402-FX-1201GLF"
				(at 20.32 -20.32 0)
				(effects
					(font
						(size 1.27 1.27)
						(thickness 0.15)
					)
					(justify left bottom)
					(hide yes)
				)
			)
			(property "Manufacturer" "Bourns"
				(at 20.32 -22.86 0)
				(effects
					(font
						(size 1.27 1.27)
						(thickness 0.15)
					)
					(justify left bottom)
					(hide yes)
				)
			)
			(property "License" "Apache-2.0"
				(at 20.32 -25.4 0)
				(effects
					(font
						(size 1.27 1.27)
						(thickness 0.15)
					)
					(justify left bottom)
					(hide yes)
				)
			)
			(property "Author" "Antmicro"
				(at 20.32 -27.94 0)
				(effects
					(font
						(size 1.27 1.27)
						(thickness 0.15)
					)
					(justify left bottom)
					(hide yes)
				)
			)
			(property "Val" "1k2"
				(at 20.32 -7.62 0)
				(effects
					(font
						(size 1.27 1.27)
						(thickness 0.15)
					)
					(justify left bottom)
				)
			)
			(property "Tolerance" "1%"
				(at 20.32 -10.16 0)
				(effects
					(font
						(size 1.27 1.27)
					)
					(justify left bottom)
					(hide yes)
				)
			)
			(property "ki_keywords" "0402, SMT, RESISTOR, PASSIVE"
				(at 0 0 0)
				(effects
					(font
						(size 1.27 1.27)
					)
					(hide yes)
				)
			)
			(symbol "R_1k2_0402_0_1"
				(rectangle
					(start 0.635 0.889)
					(end 4.445 -0.889)
					(stroke
						(width 0.254)
						(type default)
					)
					(fill
						(type none)
					)
				)
			)
			(symbol "R_1k2_0402_1_1"
				(pin passive line
					(at 0 0 0)
					(length 0.635)
					(name "~"
						(effects
							(font
								(size 1.27 1.27)
							)
						)
					)
					(number "1"
						(effects
							(font
								(size 1.27 1.27)
							)
						)
					)
				)
				(pin passive line
					(at 5.08 0 180)
					(length 0.635)
					(name "~"
						(effects
							(font
								(size 1.27 1.27)
							)
						)
					)
					(number "2"
						(effects
							(font
								(size 1.27 1.27)
							)
						)
					)
				)
			)
		)
	(symbol "antmicroResistors0402:R_1k3_0402"
			(pin_numbers hide)
			(pin_names hide)
			(exclude_from_sim no)
			(in_bom yes)
			(on_board yes)
			(property "Reference" "R"
				(at 20.32 -5.08 0)
				(effects
					(font
						(size 1.27 1.27)
						(thickness 0.15)
					)
					(justify left bottom)
				)
			)
			(property "Value" "R_1k3_0402"
				(at 20.32 -12.7 0)
				(effects
					(font
						(size 1.27 1.27)
						(thickness 0.15)
					)
					(justify left bottom)
					(hide yes)
				)
			)
			(property "Footprint" "antmicro-footprints:R_0402_1005Metric"
				(at 20.32 -15.24 0)
				(effects
					(font
						(size 1.27 1.27)
						(thickness 0.15)
					)
					(justify left bottom)
					(hide yes)
				)
			)
			(property "Datasheet" "https://www.bourns.com/docs/product-datasheets/cr.pdf"
				(at 20.32 -17.78 0)
				(effects
					(font
						(size 1.27 1.27)
						(thickness 0.15)
					)
					(justify left bottom)
					(hide yes)
				)
			)
			(property "Description" "SMD Chip Resistor, 1.3 kohm, ± 1%, 62.5 mW, 0402 [1005 Metric], Thick Film, General Purpose"
				(at 0 0 0)
				(effects
					(font
						(size 1.27 1.27)
					)
					(hide yes)
				)
			)
			(property "MPN" "CR0402-FX-1301GLF"
				(at 20.32 -20.32 0)
				(effects
					(font
						(size 1.27 1.27)
						(thickness 0.15)
					)
					(justify left bottom)
					(hide yes)
				)
			)
			(property "Manufacturer" "Bourns"
				(at 20.32 -22.86 0)
				(effects
					(font
						(size 1.27 1.27)
						(thickness 0.15)
					)
					(justify left bottom)
					(hide yes)
				)
			)
			(property "License" "Apache-2.0"
				(at 20.32 -25.4 0)
				(effects
					(font
						(size 1.27 1.27)
						(thickness 0.15)
					)
					(justify left bottom)
					(hide yes)
				)
			)
			(property "Author" "Antmicro"
				(at 20.32 -27.94 0)
				(effects
					(font
						(size 1.27 1.27)
						(thickness 0.15)
					)
					(justify left bottom)
					(hide yes)
				)
			)
			(property "Val" "1k3"
				(at 20.32 -7.62 0)
				(effects
					(font
						(size 1.27 1.27)
						(thickness 0.15)
					)
					(justify left bottom)
				)
			)
			(property "Tolerance" "1%"
				(at 20.32 -10.16 0)
				(effects
					(font
						(size 1.27 1.27)
					)
					(justify left bottom)
					(hide yes)
				)
			)
			(property "ki_keywords" "0402, SMT, RESISTOR, PASSIVE"
				(at 0 0 0)
				(effects
					(font
						(size 1.27 1.27)
					)
					(hide yes)
				)
			)
			(symbol "R_1k3_0402_0_1"
				(rectangle
					(start 0.635 0.889)
					(end 4.445 -0.889)
					(stroke
						(width 0.254)
						(type default)
					)
					(fill
						(type none)
					)
				)
			)
			(symbol "R_1k3_0402_1_1"
				(pin passive line
					(at 0 0 0)
					(length 0.635)
					(name "~"
						(effects
							(font
								(size 1.27 1.27)
							)
						)
					)
					(number "1"
						(effects
							(font
								(size 1.27 1.27)
							)
						)
					)
				)
				(pin passive line
					(at 5.08 0 180)
					(length 0.635)
					(name "~"
						(effects
							(font
								(size 1.27 1.27)
							)
						)
					)
					(number "2"
						(effects
							(font
								(size 1.27 1.27)
							)
						)
					)
				)
			)
		)
	(symbol "antmicroResistors0402:R_1k_0402"
			(pin_numbers hide)
			(pin_names hide)
			(exclude_from_sim no)
			(in_bom yes)
			(on_board yes)
			(property "Reference" "R"
				(at 20.32 -5.08 0)
				(effects
					(font
						(size 1.27 1.27)
						(thickness 0.15)
					)
					(justify left bottom)
				)
			)
			(property "Value" "R_1k_0402"
				(at 20.32 -12.7 0)
				(effects
					(font
						(size 1.27 1.27)
						(thickness 0.15)
					)
					(justify left bottom)
					(hide yes)
				)
			)
			(property "Footprint" "antmicro-footprints:R_0402_1005Metric"
				(at 20.32 -15.24 0)
				(effects
					(font
						(size 1.27 1.27)
						(thickness 0.15)
					)
					(justify left bottom)
					(hide yes)
				)
			)
			(property "Datasheet" "https://www.bourns.com/docs/product-datasheets/cr.pdf"
				(at 20.32 -17.78 0)
				(effects
					(font
						(size 1.27 1.27)
						(thickness 0.15)
					)
					(justify left bottom)
					(hide yes)
				)
			)
			(property "Description" "SMD Chip Resistor, 1 kohm, ± 1%, 63 mW, 0402 [1005 Metric], Thick Film, General Purpose"
				(at 0 0 0)
				(effects
					(font
						(size 1.27 1.27)
					)
					(hide yes)
				)
			)
			(property "MPN" "CR0402-FX-1001GLF"
				(at 20.32 -20.32 0)
				(effects
					(font
						(size 1.27 1.27)
						(thickness 0.15)
					)
					(justify left bottom)
					(hide yes)
				)
			)
			(property "Manufacturer" "Bourns"
				(at 20.32 -22.86 0)
				(effects
					(font
						(size 1.27 1.27)
						(thickness 0.15)
					)
					(justify left bottom)
					(hide yes)
				)
			)
			(property "License" "Apache-2.0"
				(at 20.32 -25.4 0)
				(effects
					(font
						(size 1.27 1.27)
						(thickness 0.15)
					)
					(justify left bottom)
					(hide yes)
				)
			)
			(property "Author" "Antmicro"
				(at 20.32 -27.94 0)
				(effects
					(font
						(size 1.27 1.27)
						(thickness 0.15)
					)
					(justify left bottom)
					(hide yes)
				)
			)
			(property "Val" "1k"
				(at 20.32 -7.62 0)
				(effects
					(font
						(size 1.27 1.27)
						(thickness 0.15)
					)
					(justify left bottom)
				)
			)
			(property "Tolerance" "1%"
				(at 20.32 -10.16 0)
				(effects
					(font
						(size 1.27 1.27)
					)
					(justify left bottom)
					(hide yes)
				)
			)
			(property "ki_keywords" "0402, SMT, RESISTOR, PASSIVE"
				(at 0 0 0)
				(effects
					(font
						(size 1.27 1.27)
					)
					(hide yes)
				)
			)
			(symbol "R_1k_0402_0_1"
				(rectangle
					(start 0.635 0.889)
					(end 4.445 -0.889)
					(stroke
						(width 0.254)
						(type default)
					)
					(fill
						(type none)
					)
				)
			)
			(symbol "R_1k_0402_1_1"
				(pin passive line
					(at 0 0 0)
					(length 0.635)
					(name "~"
						(effects
							(font
								(size 1.27 1.27)
							)
						)
					)
					(number "1"
						(effects
							(font
								(size 1.27 1.27)
							)
						)
					)
				)
				(pin passive line
					(at 5.08 0 180)
					(length 0.635)
					(name "~"
						(effects
							(font
								(size 1.27 1.27)
							)
						)
					)
					(number "2"
						(effects
							(font
								(size 1.27 1.27)
							)
						)
					)
				)
			)
		)
	(symbol "antmicroResistors0402:R_200R_0402"
			(pin_numbers hide)
			(pin_names hide)
			(exclude_from_sim no)
			(in_bom yes)
			(on_board yes)
			(property "Reference" "R"
				(at 20.32 -5.08 0)
				(effects
					(font
						(size 1.27 1.27)
						(thickness 0.15)
					)
					(justify left bottom)
				)
			)
			(property "Value" "R_200R_0402"
				(at 20.32 -12.7 0)
				(effects
					(font
						(size 1.27 1.27)
						(thickness 0.15)
					)
					(justify left bottom)
					(hide yes)
				)
			)
			(property "Footprint" "antmicro-footprints:R_0402_1005Metric"
				(at 20.32 -15.24 0)
				(effects
					(font
						(size 1.27 1.27)
						(thickness 0.15)
					)
					(justify left bottom)
					(hide yes)
				)
			)
			(property "Datasheet" "https://www.bourns.com/docs/product-datasheets/cr.pdf"
				(at 20.32 -17.78 0)
				(effects
					(font
						(size 1.27 1.27)
						(thickness 0.15)
					)
					(justify left bottom)
					(hide yes)
				)
			)
			(property "Description" "SMD Chip Resistor, 200 ohm, ± 1%, 62.5 mW, 0402 [1005 Metric], Thick Film, General Purpose"
				(at 0 0 0)
				(effects
					(font
						(size 1.27 1.27)
					)
					(hide yes)
				)
			)
			(property "MPN" "CR0402-FX-2000GLF"
				(at 20.32 -20.32 0)
				(effects
					(font
						(size 1.27 1.27)
						(thickness 0.15)
					)
					(justify left bottom)
					(hide yes)
				)
			)
			(property "Manufacturer" "Bourns"
				(at 20.32 -22.86 0)
				(effects
					(font
						(size 1.27 1.27)
						(thickness 0.15)
					)
					(justify left bottom)
					(hide yes)
				)
			)
			(property "License" "Apache-2.0"
				(at 20.32 -25.4 0)
				(effects
					(font
						(size 1.27 1.27)
						(thickness 0.15)
					)
					(justify left bottom)
					(hide yes)
				)
			)
			(property "Author" "Antmicro"
				(at 20.32 -27.94 0)
				(effects
					(font
						(size 1.27 1.27)
						(thickness 0.15)
					)
					(justify left bottom)
					(hide yes)
				)
			)
			(property "Val" "200R"
				(at 20.32 -7.62 0)
				(effects
					(font
						(size 1.27 1.27)
						(thickness 0.15)
					)
					(justify left bottom)
				)
			)
			(property "Tolerance" "1%"
				(at 20.32 -10.16 0)
				(effects
					(font
						(size 1.27 1.27)
					)
					(justify left bottom)
					(hide yes)
				)
			)
			(property "ki_keywords" "0402, SMT, RESISTOR, PASSIVE"
				(at 0 0 0)
				(effects
					(font
						(size 1.27 1.27)
					)
					(hide yes)
				)
			)
			(symbol "R_200R_0402_0_1"
				(rectangle
					(start 0.635 0.889)
					(end 4.445 -0.889)
					(stroke
						(width 0.254)
						(type default)
					)
					(fill
						(type none)
					)
				)
			)
			(symbol "R_200R_0402_1_1"
				(pin passive line
					(at 0 0 0)
					(length 0.635)
					(name "~"
						(effects
							(font
								(size 1.27 1.27)
							)
						)
					)
					(number "1"
						(effects
							(font
								(size 1.27 1.27)
							)
						)
					)
				)
				(pin passive line
					(at 5.08 0 180)
					(length 0.635)
					(name "~"
						(effects
							(font
								(size 1.27 1.27)
							)
						)
					)
					(number "2"
						(effects
							(font
								(size 1.27 1.27)
							)
						)
					)
				)
			)
		)
	(symbol "antmicroResistors0402:R_200k_0402"
			(pin_numbers hide)
			(pin_names hide)
			(exclude_from_sim no)
			(in_bom yes)
			(on_board yes)
			(property "Reference" "R"
				(at 20.32 -5.08 0)
				(effects
					(font
						(size 1.27 1.27)
						(thickness 0.15)
					)
					(justify left bottom)
				)
			)
			(property "Value" "R_200k_0402"
				(at 20.32 -12.7 0)
				(effects
					(font
						(size 1.27 1.27)
						(thickness 0.15)
					)
					(justify left bottom)
					(hide yes)
				)
			)
			(property "Footprint" "antmicro-footprints:R_0402_1005Metric"
				(at 20.32 -15.24 0)
				(effects
					(font
						(size 1.27 1.27)
						(thickness 0.15)
					)
					(justify left bottom)
					(hide yes)
				)
			)
			(property "Datasheet" "https://www.bourns.com/docs/product-datasheets/cr.pdf"
				(at 20.32 -17.78 0)
				(effects
					(font
						(size 1.27 1.27)
						(thickness 0.15)
					)
					(justify left bottom)
					(hide yes)
				)
			)
			(property "Description" "SMD Chip Resistor, 200 kohm, ± 1%, 62.5 mW, 0402 [1005 Metric], Thick Film, General Purpose"
				(at 0 0 0)
				(effects
					(font
						(size 1.27 1.27)
					)
					(hide yes)
				)
			)
			(property "MPN" "CR0402-FX-2003GLF"
				(at 20.32 -20.32 0)
				(effects
					(font
						(size 1.27 1.27)
						(thickness 0.15)
					)
					(justify left bottom)
					(hide yes)
				)
			)
			(property "Manufacturer" "Bourns"
				(at 20.32 -22.86 0)
				(effects
					(font
						(size 1.27 1.27)
						(thickness 0.15)
					)
					(justify left bottom)
					(hide yes)
				)
			)
			(property "License" "Apache-2.0"
				(at 20.32 -25.4 0)
				(effects
					(font
						(size 1.27 1.27)
						(thickness 0.15)
					)
					(justify left bottom)
					(hide yes)
				)
			)
			(property "Author" "Antmicro"
				(at 20.32 -27.94 0)
				(effects
					(font
						(size 1.27 1.27)
						(thickness 0.15)
					)
					(justify left bottom)
					(hide yes)
				)
			)
			(property "Val" "200k"
				(at 20.32 -7.62 0)
				(effects
					(font
						(size 1.27 1.27)
						(thickness 0.15)
					)
					(justify left bottom)
				)
			)
			(property "Tolerance" "1%"
				(at 20.32 -10.16 0)
				(effects
					(font
						(size 1.27 1.27)
					)
					(justify left bottom)
					(hide yes)
				)
			)
			(property "ki_keywords" "0402, SMT, RESISTOR, PASSIVE"
				(at 0 0 0)
				(effects
					(font
						(size 1.27 1.27)
					)
					(hide yes)
				)
			)
			(symbol "R_200k_0402_0_1"
				(rectangle
					(start 0.635 0.889)
					(end 4.445 -0.889)
					(stroke
						(width 0.254)
						(type default)
					)
					(fill
						(type none)
					)
				)
			)
			(symbol "R_200k_0402_1_1"
				(pin passive line
					(at 0 0 0)
					(length 0.635)
					(name "~"
						(effects
							(font
								(size 1.27 1.27)
							)
						)
					)
					(number "1"
						(effects
							(font
								(size 1.27 1.27)
							)
						)
					)
				)
				(pin passive line
					(at 5.08 0 180)
					(length 0.635)
					(name "~"
						(effects
							(font
								(size 1.27 1.27)
							)
						)
					)
					(number "2"
						(effects
							(font
								(size 1.27 1.27)
							)
						)
					)
				)
			)
		)
	(symbol "antmicroResistors0402:R_20k_0402"
			(pin_numbers hide)
			(pin_names hide)
			(exclude_from_sim no)
			(in_bom yes)
			(on_board yes)
			(property "Reference" "R"
				(at 20.32 -5.08 0)
				(effects
					(font
						(size 1.27 1.27)
						(thickness 0.15)
					)
					(justify left bottom)
				)
			)
			(property "Value" "R_20k_0402"
				(at 20.32 -12.7 0)
				(effects
					(font
						(size 1.27 1.27)
						(thickness 0.15)
					)
					(justify left bottom)
					(hide yes)
				)
			)
			(property "Footprint" "antmicro-footprints:R_0402_1005Metric"
				(at 20.32 -15.24 0)
				(effects
					(font
						(size 1.27 1.27)
						(thickness 0.15)
					)
					(justify left bottom)
					(hide yes)
				)
			)
			(property "Datasheet" "https://www.bourns.com/docs/product-datasheets/cr.pdf"
				(at 20.32 -17.78 0)
				(effects
					(font
						(size 1.27 1.27)
						(thickness 0.15)
					)
					(justify left bottom)
					(hide yes)
				)
			)
			(property "Description" "SMD Chip Resistor, 20 kohm, ± 1%, 62.5 mW, 0402 [1005 Metric], Thick Film, General Purpose"
				(at 0 0 0)
				(effects
					(font
						(size 1.27 1.27)
					)
					(hide yes)
				)
			)
			(property "MPN" "CR0402-FX-2002GLF"
				(at 20.32 -20.32 0)
				(effects
					(font
						(size 1.27 1.27)
						(thickness 0.15)
					)
					(justify left bottom)
					(hide yes)
				)
			)
			(property "Manufacturer" "Bourns"
				(at 20.32 -22.86 0)
				(effects
					(font
						(size 1.27 1.27)
						(thickness 0.15)
					)
					(justify left bottom)
					(hide yes)
				)
			)
			(property "License" "Apache-2.0"
				(at 20.32 -25.4 0)
				(effects
					(font
						(size 1.27 1.27)
						(thickness 0.15)
					)
					(justify left bottom)
					(hide yes)
				)
			)
			(property "Author" "Antmicro"
				(at 20.32 -27.94 0)
				(effects
					(font
						(size 1.27 1.27)
						(thickness 0.15)
					)
					(justify left bottom)
					(hide yes)
				)
			)
			(property "Val" "20k"
				(at 20.32 -7.62 0)
				(effects
					(font
						(size 1.27 1.27)
						(thickness 0.15)
					)
					(justify left bottom)
				)
			)
			(property "Tolerance" "1%"
				(at 20.32 -10.16 0)
				(effects
					(font
						(size 1.27 1.27)
					)
					(justify left bottom)
					(hide yes)
				)
			)
			(property "ki_keywords" "0402, SMT, RESISTOR, PASSIVE"
				(at 0 0 0)
				(effects
					(font
						(size 1.27 1.27)
					)
					(hide yes)
				)
			)
			(symbol "R_20k_0402_0_1"
				(rectangle
					(start 0.635 0.889)
					(end 4.445 -0.889)
					(stroke
						(width 0.254)
						(type default)
					)
					(fill
						(type none)
					)
				)
			)
			(symbol "R_20k_0402_1_1"
				(pin passive line
					(at 0 0 0)
					(length 0.635)
					(name "~"
						(effects
							(font
								(size 1.27 1.27)
							)
						)
					)
					(number "1"
						(effects
							(font
								(size 1.27 1.27)
							)
						)
					)
				)
				(pin passive line
					(at 5.08 0 180)
					(length 0.635)
					(name "~"
						(effects
							(font
								(size 1.27 1.27)
							)
						)
					)
					(number "2"
						(effects
							(font
								(size 1.27 1.27)
							)
						)
					)
				)
			)
		)
	(symbol "antmicroResistors0402:R_24k9_0402"
			(pin_numbers hide)
			(pin_names hide)
			(exclude_from_sim no)
			(in_bom yes)
			(on_board yes)
			(property "Reference" "R"
				(at 20.32 -5.08 0)
				(effects
					(font
						(size 1.27 1.27)
						(thickness 0.15)
					)
					(justify left bottom)
				)
			)
			(property "Value" "R_24k9_0402"
				(at 20.32 -12.7 0)
				(effects
					(font
						(size 1.27 1.27)
						(thickness 0.15)
					)
					(justify left bottom)
					(hide yes)
				)
			)
			(property "Footprint" "antmicro-footprints:R_0402_1005Metric"
				(at 20.32 -15.24 0)
				(effects
					(font
						(size 1.27 1.27)
						(thickness 0.15)
					)
					(justify left bottom)
					(hide yes)
				)
			)
			(property "Datasheet" "https://www.bourns.com/docs/product-datasheets/cr.pdf"
				(at 20.32 -17.78 0)
				(effects
					(font
						(size 1.27 1.27)
						(thickness 0.15)
					)
					(justify left bottom)
					(hide yes)
				)
			)
			(property "Description" "SMD Chip Resistor, 24.9 kohm, ± 1%, 63 mW, 0402 [1005 Metric], Thick Film, General Purpose"
				(at 0 0 0)
				(effects
					(font
						(size 1.27 1.27)
					)
					(hide yes)
				)
			)
			(property "MPN" "CR0402-FX-2492GLF"
				(at 20.32 -20.32 0)
				(effects
					(font
						(size 1.27 1.27)
						(thickness 0.15)
					)
					(justify left bottom)
					(hide yes)
				)
			)
			(property "Manufacturer" "Bourns"
				(at 20.32 -22.86 0)
				(effects
					(font
						(size 1.27 1.27)
						(thickness 0.15)
					)
					(justify left bottom)
					(hide yes)
				)
			)
			(property "License" "Apache-2.0"
				(at 20.32 -25.4 0)
				(effects
					(font
						(size 1.27 1.27)
						(thickness 0.15)
					)
					(justify left bottom)
					(hide yes)
				)
			)
			(property "Author" "Antmicro"
				(at 20.32 -27.94 0)
				(effects
					(font
						(size 1.27 1.27)
						(thickness 0.15)
					)
					(justify left bottom)
					(hide yes)
				)
			)
			(property "Val" "24k9"
				(at 20.32 -7.62 0)
				(effects
					(font
						(size 1.27 1.27)
						(thickness 0.15)
					)
					(justify left bottom)
				)
			)
			(property "Tolerance" "1%"
				(at 20.32 -10.16 0)
				(effects
					(font
						(size 1.27 1.27)
					)
					(justify left bottom)
					(hide yes)
				)
			)
			(property "ki_keywords" "0402, SMT, RESISTOR, PASSIVE"
				(at 0 0 0)
				(effects
					(font
						(size 1.27 1.27)
					)
					(hide yes)
				)
			)
			(symbol "R_24k9_0402_0_1"
				(rectangle
					(start 0.635 0.889)
					(end 4.445 -0.889)
					(stroke
						(width 0.254)
						(type default)
					)
					(fill
						(type none)
					)
				)
			)
			(symbol "R_24k9_0402_1_1"
				(pin passive line
					(at 0 0 0)
					(length 0.635)
					(name "~"
						(effects
							(font
								(size 1.27 1.27)
							)
						)
					)
					(number "1"
						(effects
							(font
								(size 1.27 1.27)
							)
						)
					)
				)
				(pin passive line
					(at 5.08 0 180)
					(length 0.635)
					(name "~"
						(effects
							(font
								(size 1.27 1.27)
							)
						)
					)
					(number "2"
						(effects
							(font
								(size 1.27 1.27)
							)
						)
					)
				)
			)
		)
	(symbol "antmicroResistors0402:R_27R_0402"
			(pin_numbers hide)
			(pin_names hide)
			(exclude_from_sim no)
			(in_bom yes)
			(on_board yes)
			(property "Reference" "R"
				(at 20.32 -5.08 0)
				(effects
					(font
						(size 1.27 1.27)
						(thickness 0.15)
					)
					(justify left bottom)
				)
			)
			(property "Value" "R_27R_0402"
				(at 20.32 -12.7 0)
				(effects
					(font
						(size 1.27 1.27)
						(thickness 0.15)
					)
					(justify left bottom)
					(hide yes)
				)
			)
			(property "Footprint" "antmicro-footprints:R_0402_1005Metric"
				(at 20.32 -15.24 0)
				(effects
					(font
						(size 1.27 1.27)
						(thickness 0.15)
					)
					(justify left bottom)
					(hide yes)
				)
			)
			(property "Datasheet" "https://www.bourns.com/docs/product-datasheets/cr.pdf"
				(at 20.32 -17.78 0)
				(effects
					(font
						(size 1.27 1.27)
						(thickness 0.15)
					)
					(justify left bottom)
					(hide yes)
				)
			)
			(property "Description" "SMD Chip Resistor, 27 ohm, ± 1%, 63 mW, 0402 [1005 Metric], Thick Film, General Purpose"
				(at 0 0 0)
				(effects
					(font
						(size 1.27 1.27)
					)
					(hide yes)
				)
			)
			(property "MPN" "CR0402-FX-27R0GLF"
				(at 20.32 -20.32 0)
				(effects
					(font
						(size 1.27 1.27)
						(thickness 0.15)
					)
					(justify left bottom)
					(hide yes)
				)
			)
			(property "Manufacturer" "Bourns"
				(at 20.32 -22.86 0)
				(effects
					(font
						(size 1.27 1.27)
						(thickness 0.15)
					)
					(justify left bottom)
					(hide yes)
				)
			)
			(property "License" "Apache-2.0"
				(at 20.32 -25.4 0)
				(effects
					(font
						(size 1.27 1.27)
						(thickness 0.15)
					)
					(justify left bottom)
					(hide yes)
				)
			)
			(property "Author" "Antmicro"
				(at 20.32 -27.94 0)
				(effects
					(font
						(size 1.27 1.27)
						(thickness 0.15)
					)
					(justify left bottom)
					(hide yes)
				)
			)
			(property "Val" "27R"
				(at 20.32 -7.62 0)
				(effects
					(font
						(size 1.27 1.27)
						(thickness 0.15)
					)
					(justify left bottom)
				)
			)
			(property "Tolerance" "1%"
				(at 20.32 -10.16 0)
				(effects
					(font
						(size 1.27 1.27)
					)
					(justify left bottom)
					(hide yes)
				)
			)
			(property "ki_keywords" "0402, SMT, RESISTOR, PASSIVE"
				(at 0 0 0)
				(effects
					(font
						(size 1.27 1.27)
					)
					(hide yes)
				)
			)
			(symbol "R_27R_0402_0_1"
				(rectangle
					(start 0.635 0.889)
					(end 4.445 -0.889)
					(stroke
						(width 0.254)
						(type default)
					)
					(fill
						(type none)
					)
				)
			)
			(symbol "R_27R_0402_1_1"
				(pin passive line
					(at 0 0 0)
					(length 0.635)
					(name "~"
						(effects
							(font
								(size 1.27 1.27)
							)
						)
					)
					(number "1"
						(effects
							(font
								(size 1.27 1.27)
							)
						)
					)
				)
				(pin passive line
					(at 5.08 0 180)
					(length 0.635)
					(name "~"
						(effects
							(font
								(size 1.27 1.27)
							)
						)
					)
					(number "2"
						(effects
							(font
								(size 1.27 1.27)
							)
						)
					)
				)
			)
		)
	(symbol "antmicroResistors0402:R_2M_0402"
			(pin_numbers hide)
			(pin_names hide)
			(exclude_from_sim no)
			(in_bom yes)
			(on_board yes)
			(property "Reference" "R"
				(at 20.32 -5.08 0)
				(effects
					(font
						(size 1.27 1.27)
						(thickness 0.15)
					)
					(justify left bottom)
				)
			)
			(property "Value" "R_2M_0402"
				(at 20.32 -12.7 0)
				(effects
					(font
						(size 1.27 1.27)
						(thickness 0.15)
					)
					(justify left bottom)
					(hide yes)
				)
			)
			(property "Footprint" "antmicro-footprints:R_0402_1005Metric"
				(at 20.32 -15.24 0)
				(effects
					(font
						(size 1.27 1.27)
						(thickness 0.15)
					)
					(justify left bottom)
					(hide yes)
				)
			)
			(property "Datasheet" "https://www.mouser.com/datasheet/2/447/YAGEO_PYu_RC_Group_51_RoHS_L_12-3313492.pdf"
				(at 20.32 -17.78 0)
				(effects
					(font
						(size 1.27 1.27)
						(thickness 0.15)
					)
					(justify left bottom)
					(hide yes)
				)
			)
			(property "Description" "SMD Chip Resistor, 2 Mohm, ± 1%, 62.5 mW, 0402 [1005 Metric], Thick Film, General Purpose"
				(at 0 0 0)
				(effects
					(font
						(size 1.27 1.27)
					)
					(hide yes)
				)
			)
			(property "MPN" "RC0402FR-072ML"
				(at 20.32 -20.32 0)
				(effects
					(font
						(size 1.27 1.27)
						(thickness 0.15)
					)
					(justify left bottom)
					(hide yes)
				)
			)
			(property "Manufacturer" "YAGEO"
				(at 20.32 -22.86 0)
				(effects
					(font
						(size 1.27 1.27)
						(thickness 0.15)
					)
					(justify left bottom)
					(hide yes)
				)
			)
			(property "License" "Apache-2.0"
				(at 20.32 -25.4 0)
				(effects
					(font
						(size 1.27 1.27)
						(thickness 0.15)
					)
					(justify left bottom)
					(hide yes)
				)
			)
			(property "Author" "Antmicro"
				(at 20.32 -27.94 0)
				(effects
					(font
						(size 1.27 1.27)
						(thickness 0.15)
					)
					(justify left bottom)
					(hide yes)
				)
			)
			(property "Val" "2M"
				(at 20.32 -7.62 0)
				(effects
					(font
						(size 1.27 1.27)
						(thickness 0.15)
					)
					(justify left bottom)
				)
			)
			(property "Tolerance" "1%"
				(at 20.32 -10.16 0)
				(effects
					(font
						(size 1.27 1.27)
					)
					(justify left bottom)
					(hide yes)
				)
			)
			(property "ki_keywords" "0402, SMT, RESISTOR, PASSIVE"
				(at 0 0 0)
				(effects
					(font
						(size 1.27 1.27)
					)
					(hide yes)
				)
			)
			(symbol "R_2M_0402_0_1"
				(rectangle
					(start 0.635 0.889)
					(end 4.445 -0.889)
					(stroke
						(width 0.254)
						(type default)
					)
					(fill
						(type none)
					)
				)
			)
			(symbol "R_2M_0402_1_1"
				(pin passive line
					(at 0 0 0)
					(length 0.635)
					(name "~"
						(effects
							(font
								(size 1.27 1.27)
							)
						)
					)
					(number "1"
						(effects
							(font
								(size 1.27 1.27)
							)
						)
					)
				)
				(pin passive line
					(at 5.08 0 180)
					(length 0.635)
					(name "~"
						(effects
							(font
								(size 1.27 1.27)
							)
						)
					)
					(number "2"
						(effects
							(font
								(size 1.27 1.27)
							)
						)
					)
				)
			)
		)
	(symbol "antmicroResistors0402:R_2k2_0402"
			(pin_numbers hide)
			(pin_names hide)
			(exclude_from_sim no)
			(in_bom yes)
			(on_board yes)
			(property "Reference" "R"
				(at 20.32 -5.08 0)
				(effects
					(font
						(size 1.27 1.27)
						(thickness 0.15)
					)
					(justify left bottom)
				)
			)
			(property "Value" "R_2k2_0402"
				(at 20.32 -12.7 0)
				(effects
					(font
						(size 1.27 1.27)
						(thickness 0.15)
					)
					(justify left bottom)
					(hide yes)
				)
			)
			(property "Footprint" "antmicro-footprints:R_0402_1005Metric"
				(at 20.32 -15.24 0)
				(effects
					(font
						(size 1.27 1.27)
						(thickness 0.15)
					)
					(justify left bottom)
					(hide yes)
				)
			)
			(property "Datasheet" "https://www.bourns.com/docs/product-datasheets/cr.pdf"
				(at 20.32 -17.78 0)
				(effects
					(font
						(size 1.27 1.27)
						(thickness 0.15)
					)
					(justify left bottom)
					(hide yes)
				)
			)
			(property "Description" "SMD Chip Resistor, 2.2 kohm, ± 1%, 62.5 mW, 0402 [1005 Metric], Thick Film, General Purpose"
				(at 0 0 0)
				(effects
					(font
						(size 1.27 1.27)
					)
					(hide yes)
				)
			)
			(property "MPN" "CR0402-FX-2201GLF"
				(at 20.32 -20.32 0)
				(effects
					(font
						(size 1.27 1.27)
						(thickness 0.15)
					)
					(justify left bottom)
					(hide yes)
				)
			)
			(property "Manufacturer" "Bourns"
				(at 20.32 -22.86 0)
				(effects
					(font
						(size 1.27 1.27)
						(thickness 0.15)
					)
					(justify left bottom)
					(hide yes)
				)
			)
			(property "License" "Apache-2.0"
				(at 20.32 -25.4 0)
				(effects
					(font
						(size 1.27 1.27)
						(thickness 0.15)
					)
					(justify left bottom)
					(hide yes)
				)
			)
			(property "Author" "Antmicro"
				(at 20.32 -27.94 0)
				(effects
					(font
						(size 1.27 1.27)
						(thickness 0.15)
					)
					(justify left bottom)
					(hide yes)
				)
			)
			(property "Val" "2k2"
				(at 20.32 -7.62 0)
				(effects
					(font
						(size 1.27 1.27)
						(thickness 0.15)
					)
					(justify left bottom)
				)
			)
			(property "Tolerance" "1%"
				(at 20.32 -10.16 0)
				(effects
					(font
						(size 1.27 1.27)
					)
					(justify left bottom)
					(hide yes)
				)
			)
			(property "ki_keywords" "0402, SMT, RESISTOR, PASSIVE"
				(at 0 0 0)
				(effects
					(font
						(size 1.27 1.27)
					)
					(hide yes)
				)
			)
			(symbol "R_2k2_0402_0_1"
				(rectangle
					(start 0.635 0.889)
					(end 4.445 -0.889)
					(stroke
						(width 0.254)
						(type default)
					)
					(fill
						(type none)
					)
				)
			)
			(symbol "R_2k2_0402_1_1"
				(pin passive line
					(at 0 0 0)
					(length 0.635)
					(name "~"
						(effects
							(font
								(size 1.27 1.27)
							)
						)
					)
					(number "1"
						(effects
							(font
								(size 1.27 1.27)
							)
						)
					)
				)
				(pin passive line
					(at 5.08 0 180)
					(length 0.635)
					(name "~"
						(effects
							(font
								(size 1.27 1.27)
							)
						)
					)
					(number "2"
						(effects
							(font
								(size 1.27 1.27)
							)
						)
					)
				)
			)
		)
	(symbol "antmicroResistors0402:R_2k7_0402"
			(pin_numbers hide)
			(pin_names hide)
			(exclude_from_sim no)
			(in_bom yes)
			(on_board yes)
			(property "Reference" "R"
				(at 20.32 -5.08 0)
				(effects
					(font
						(size 1.27 1.27)
						(thickness 0.15)
					)
					(justify left bottom)
				)
			)
			(property "Value" "R_2k7_0402"
				(at 20.32 -12.7 0)
				(effects
					(font
						(size 1.27 1.27)
						(thickness 0.15)
					)
					(justify left bottom)
					(hide yes)
				)
			)
			(property "Footprint" "antmicro-footprints:R_0402_1005Metric"
				(at 20.32 -15.24 0)
				(effects
					(font
						(size 1.27 1.27)
						(thickness 0.15)
					)
					(justify left bottom)
					(hide yes)
				)
			)
			(property "Datasheet" "https://www.bourns.com/docs/product-datasheets/cr.pdf"
				(at 20.32 -17.78 0)
				(effects
					(font
						(size 1.27 1.27)
						(thickness 0.15)
					)
					(justify left bottom)
					(hide yes)
				)
			)
			(property "Description" "SMD Chip Resistor, 2.7 kohm, ± 1%, 63 mW, 0402 [1005 Metric], Thick Film, General Purpose"
				(at 0 0 0)
				(effects
					(font
						(size 1.27 1.27)
					)
					(hide yes)
				)
			)
			(property "MPN" "CR0402-FX-2701GLF"
				(at 20.32 -20.32 0)
				(effects
					(font
						(size 1.27 1.27)
						(thickness 0.15)
					)
					(justify left bottom)
					(hide yes)
				)
			)
			(property "Manufacturer" "Bourns"
				(at 20.32 -22.86 0)
				(effects
					(font
						(size 1.27 1.27)
						(thickness 0.15)
					)
					(justify left bottom)
					(hide yes)
				)
			)
			(property "License" "Apache-2.0"
				(at 20.32 -25.4 0)
				(effects
					(font
						(size 1.27 1.27)
						(thickness 0.15)
					)
					(justify left bottom)
					(hide yes)
				)
			)
			(property "Author" "Antmicro"
				(at 20.32 -27.94 0)
				(effects
					(font
						(size 1.27 1.27)
						(thickness 0.15)
					)
					(justify left bottom)
					(hide yes)
				)
			)
			(property "Val" "2k7"
				(at 20.32 -7.62 0)
				(effects
					(font
						(size 1.27 1.27)
						(thickness 0.15)
					)
					(justify left bottom)
				)
			)
			(property "Tolerance" "1%"
				(at 20.32 -10.16 0)
				(effects
					(font
						(size 1.27 1.27)
					)
					(justify left bottom)
					(hide yes)
				)
			)
			(property "ki_keywords" "0402, SMT, RESISTOR, PASSIVE"
				(at 0 0 0)
				(effects
					(font
						(size 1.27 1.27)
					)
					(hide yes)
				)
			)
			(symbol "R_2k7_0402_0_1"
				(rectangle
					(start 0.635 0.889)
					(end 4.445 -0.889)
					(stroke
						(width 0.254)
						(type default)
					)
					(fill
						(type none)
					)
				)
			)
			(symbol "R_2k7_0402_1_1"
				(pin passive line
					(at 0 0 0)
					(length 0.635)
					(name "~"
						(effects
							(font
								(size 1.27 1.27)
							)
						)
					)
					(number "1"
						(effects
							(font
								(size 1.27 1.27)
							)
						)
					)
				)
				(pin passive line
					(at 5.08 0 180)
					(length 0.635)
					(name "~"
						(effects
							(font
								(size 1.27 1.27)
							)
						)
					)
					(number "2"
						(effects
							(font
								(size 1.27 1.27)
							)
						)
					)
				)
			)
		)
	(symbol "antmicroResistors0402:R_45k3_0402"
			(pin_numbers hide)
			(pin_names hide)
			(exclude_from_sim no)
			(in_bom yes)
			(on_board yes)
			(property "Reference" "R"
				(at 20.32 -5.08 0)
				(effects
					(font
						(size 1.27 1.27)
						(thickness 0.15)
					)
					(justify left bottom)
				)
			)
			(property "Value" "R_45k3_0402"
				(at 20.32 -12.7 0)
				(effects
					(font
						(size 1.27 1.27)
						(thickness 0.15)
					)
					(justify left bottom)
					(hide yes)
				)
			)
			(property "Footprint" "antmicro-footprints:R_0402_1005Metric"
				(at 20.32 -15.24 0)
				(effects
					(font
						(size 1.27 1.27)
						(thickness 0.15)
					)
					(justify left bottom)
					(hide yes)
				)
			)
			(property "Datasheet" "https://www.bourns.com/docs/product-datasheets/cr.pdf"
				(at 20.32 -17.78 0)
				(effects
					(font
						(size 1.27 1.27)
						(thickness 0.15)
					)
					(justify left bottom)
					(hide yes)
				)
			)
			(property "Description" "SMD Chip Resistor"
				(at 0 0 0)
				(effects
					(font
						(size 1.27 1.27)
					)
					(hide yes)
				)
			)
			(property "MPN" "CR0402-FX-4532GLF"
				(at 20.32 -20.32 0)
				(effects
					(font
						(size 1.27 1.27)
						(thickness 0.15)
					)
					(justify left bottom)
					(hide yes)
				)
			)
			(property "Manufacturer" "Bourns"
				(at 20.32 -22.86 0)
				(effects
					(font
						(size 1.27 1.27)
						(thickness 0.15)
					)
					(justify left bottom)
					(hide yes)
				)
			)
			(property "License" "Apache-2.0"
				(at 20.32 -25.4 0)
				(effects
					(font
						(size 1.27 1.27)
						(thickness 0.15)
					)
					(justify left bottom)
					(hide yes)
				)
			)
			(property "Author" "Antmicro"
				(at 20.32 -27.94 0)
				(effects
					(font
						(size 1.27 1.27)
						(thickness 0.15)
					)
					(justify left bottom)
					(hide yes)
				)
			)
			(property "Val" "45k3"
				(at 20.32 -7.62 0)
				(effects
					(font
						(size 1.27 1.27)
						(thickness 0.15)
					)
					(justify left bottom)
				)
			)
			(property "Tolerance" "1%"
				(at 20.32 -10.16 0)
				(effects
					(font
						(size 1.27 1.27)
					)
					(justify left bottom)
					(hide yes)
				)
			)
			(property "ki_keywords" "0402, SMT, RESISTOR, PASSIVE"
				(at 0 0 0)
				(effects
					(font
						(size 1.27 1.27)
					)
					(hide yes)
				)
			)
			(symbol "R_45k3_0402_0_1"
				(rectangle
					(start 0.635 0.889)
					(end 4.445 -0.889)
					(stroke
						(width 0.254)
						(type default)
					)
					(fill
						(type none)
					)
				)
			)
			(symbol "R_45k3_0402_1_1"
				(pin passive line
					(at 0 0 0)
					(length 0.635)
					(name "~"
						(effects
							(font
								(size 1.27 1.27)
							)
						)
					)
					(number "1"
						(effects
							(font
								(size 1.27 1.27)
							)
						)
					)
				)
				(pin passive line
					(at 5.08 0 180)
					(length 0.635)
					(name "~"
						(effects
							(font
								(size 1.27 1.27)
							)
						)
					)
					(number "2"
						(effects
							(font
								(size 1.27 1.27)
							)
						)
					)
				)
			)
		)
	(symbol "antmicroResistors0402:R_470R_0402"
			(pin_numbers hide)
			(pin_names hide)
			(exclude_from_sim no)
			(in_bom yes)
			(on_board yes)
			(property "Reference" "R"
				(at 20.32 -5.08 0)
				(effects
					(font
						(size 1.27 1.27)
						(thickness 0.15)
					)
					(justify left bottom)
				)
			)
			(property "Value" "R_470R_0402"
				(at 20.32 -12.7 0)
				(effects
					(font
						(size 1.27 1.27)
						(thickness 0.15)
					)
					(justify left bottom)
					(hide yes)
				)
			)
			(property "Footprint" "antmicro-footprints:R_0402_1005Metric"
				(at 20.32 -15.24 0)
				(effects
					(font
						(size 1.27 1.27)
						(thickness 0.15)
					)
					(justify left bottom)
					(hide yes)
				)
			)
			(property "Datasheet" "https://www.bourns.com/docs/product-datasheets/cr.pdf"
				(at 20.32 -17.78 0)
				(effects
					(font
						(size 1.27 1.27)
						(thickness 0.15)
					)
					(justify left bottom)
					(hide yes)
				)
			)
			(property "Description" "SMD Chip Resistor, 470 ohm, ± 1%, 62.5 mW, 0402 [1005 Metric], Thick Film, General Purpose"
				(at 0 0 0)
				(effects
					(font
						(size 1.27 1.27)
					)
					(hide yes)
				)
			)
			(property "MPN" "CR0402-FX-4700GLF"
				(at 20.32 -20.32 0)
				(effects
					(font
						(size 1.27 1.27)
						(thickness 0.15)
					)
					(justify left bottom)
					(hide yes)
				)
			)
			(property "Manufacturer" "Bourns"
				(at 20.32 -22.86 0)
				(effects
					(font
						(size 1.27 1.27)
						(thickness 0.15)
					)
					(justify left bottom)
					(hide yes)
				)
			)
			(property "License" "Apache-2.0"
				(at 20.32 -25.4 0)
				(effects
					(font
						(size 1.27 1.27)
						(thickness 0.15)
					)
					(justify left bottom)
					(hide yes)
				)
			)
			(property "Author" "Antmicro"
				(at 20.32 -27.94 0)
				(effects
					(font
						(size 1.27 1.27)
						(thickness 0.15)
					)
					(justify left bottom)
					(hide yes)
				)
			)
			(property "Val" "470R"
				(at 20.32 -7.62 0)
				(effects
					(font
						(size 1.27 1.27)
						(thickness 0.15)
					)
					(justify left bottom)
				)
			)
			(property "Tolerance" "1%"
				(at 20.32 -10.16 0)
				(effects
					(font
						(size 1.27 1.27)
					)
					(justify left bottom)
					(hide yes)
				)
			)
			(property "ki_keywords" "0402, SMT, RESISTOR, PASSIVE"
				(at 0 0 0)
				(effects
					(font
						(size 1.27 1.27)
					)
					(hide yes)
				)
			)
			(symbol "R_470R_0402_0_1"
				(rectangle
					(start 0.635 0.889)
					(end 4.445 -0.889)
					(stroke
						(width 0.254)
						(type default)
					)
					(fill
						(type none)
					)
				)
			)
			(symbol "R_470R_0402_1_1"
				(pin passive line
					(at 0 0 0)
					(length 0.635)
					(name "~"
						(effects
							(font
								(size 1.27 1.27)
							)
						)
					)
					(number "1"
						(effects
							(font
								(size 1.27 1.27)
							)
						)
					)
				)
				(pin passive line
					(at 5.08 0 180)
					(length 0.635)
					(name "~"
						(effects
							(font
								(size 1.27 1.27)
							)
						)
					)
					(number "2"
						(effects
							(font
								(size 1.27 1.27)
							)
						)
					)
				)
			)
		)
	(symbol "antmicroResistors0402:R_470k_0402"
			(pin_numbers hide)
			(pin_names hide)
			(exclude_from_sim no)
			(in_bom yes)
			(on_board yes)
			(property "Reference" "R"
				(at 20.32 -5.08 0)
				(effects
					(font
						(size 1.27 1.27)
						(thickness 0.15)
					)
					(justify left bottom)
				)
			)
			(property "Value" "R_470k_0402"
				(at 20.32 -12.7 0)
				(effects
					(font
						(size 1.27 1.27)
						(thickness 0.15)
					)
					(justify left bottom)
					(hide yes)
				)
			)
			(property "Footprint" "antmicro-footprints:R_0402_1005Metric"
				(at 20.32 -15.24 0)
				(effects
					(font
						(size 1.27 1.27)
						(thickness 0.15)
					)
					(justify left bottom)
					(hide yes)
				)
			)
			(property "Datasheet" "https://www.bourns.com/docs/product-datasheets/cr.pdf"
				(at 20.32 -17.78 0)
				(effects
					(font
						(size 1.27 1.27)
						(thickness 0.15)
					)
					(justify left bottom)
					(hide yes)
				)
			)
			(property "Description" "SMD Chip Resistor, 470 kohm, ± 1%, 62.5 mW, 0402 [1005 Metric], Thick Film, Sulfur Resistant"
				(at 0 0 0)
				(effects
					(font
						(size 1.27 1.27)
					)
					(hide yes)
				)
			)
			(property "MPN" "CR0402-FX-4703GLF"
				(at 20.32 -20.32 0)
				(effects
					(font
						(size 1.27 1.27)
						(thickness 0.15)
					)
					(justify left bottom)
					(hide yes)
				)
			)
			(property "Manufacturer" "Bourns"
				(at 20.32 -22.86 0)
				(effects
					(font
						(size 1.27 1.27)
						(thickness 0.15)
					)
					(justify left bottom)
					(hide yes)
				)
			)
			(property "License" "Apache-2.0"
				(at 20.32 -25.4 0)
				(effects
					(font
						(size 1.27 1.27)
						(thickness 0.15)
					)
					(justify left bottom)
					(hide yes)
				)
			)
			(property "Author" "Antmicro"
				(at 20.32 -27.94 0)
				(effects
					(font
						(size 1.27 1.27)
						(thickness 0.15)
					)
					(justify left bottom)
					(hide yes)
				)
			)
			(property "Val" "470k"
				(at 20.32 -7.62 0)
				(effects
					(font
						(size 1.27 1.27)
						(thickness 0.15)
					)
					(justify left bottom)
				)
			)
			(property "Tolerance" "1%"
				(at 20.32 -10.16 0)
				(effects
					(font
						(size 1.27 1.27)
					)
					(justify left bottom)
					(hide yes)
				)
			)
			(property "ki_keywords" "0402, SMT, RESISTOR, PASSIVE"
				(at 0 0 0)
				(effects
					(font
						(size 1.27 1.27)
					)
					(hide yes)
				)
			)
			(symbol "R_470k_0402_0_1"
				(rectangle
					(start 0.635 0.889)
					(end 4.445 -0.889)
					(stroke
						(width 0.254)
						(type default)
					)
					(fill
						(type none)
					)
				)
			)
			(symbol "R_470k_0402_1_1"
				(pin passive line
					(at 0 0 0)
					(length 0.635)
					(name "~"
						(effects
							(font
								(size 1.27 1.27)
							)
						)
					)
					(number "1"
						(effects
							(font
								(size 1.27 1.27)
							)
						)
					)
				)
				(pin passive line
					(at 5.08 0 180)
					(length 0.635)
					(name "~"
						(effects
							(font
								(size 1.27 1.27)
							)
						)
					)
					(number "2"
						(effects
							(font
								(size 1.27 1.27)
							)
						)
					)
				)
			)
		)
	(symbol "antmicroResistors0402:R_47k_0402"
			(pin_numbers hide)
			(pin_names hide)
			(exclude_from_sim no)
			(in_bom yes)
			(on_board yes)
			(property "Reference" "R"
				(at 20.32 -5.08 0)
				(effects
					(font
						(size 1.27 1.27)
						(thickness 0.15)
					)
					(justify left bottom)
				)
			)
			(property "Value" "R_47k_0402"
				(at 20.32 -12.7 0)
				(effects
					(font
						(size 1.27 1.27)
						(thickness 0.15)
					)
					(justify left bottom)
					(hide yes)
				)
			)
			(property "Footprint" "antmicro-footprints:R_0402_1005Metric"
				(at 20.32 -15.24 0)
				(effects
					(font
						(size 1.27 1.27)
						(thickness 0.15)
					)
					(justify left bottom)
					(hide yes)
				)
			)
			(property "Datasheet" "https://www.bourns.com/docs/product-datasheets/cr.pdf"
				(at 20.32 -17.78 0)
				(effects
					(font
						(size 1.27 1.27)
						(thickness 0.15)
					)
					(justify left bottom)
					(hide yes)
				)
			)
			(property "Description" "SMD Chip Resistor, 47 kohm, ± 1%, 62.5 mW, 0402 [1005 Metric], Thick Film, General Purpose"
				(at 0 0 0)
				(effects
					(font
						(size 1.27 1.27)
					)
					(hide yes)
				)
			)
			(property "MPN" "CR0402-FX-4702GLF"
				(at 20.32 -20.32 0)
				(effects
					(font
						(size 1.27 1.27)
						(thickness 0.15)
					)
					(justify left bottom)
					(hide yes)
				)
			)
			(property "Manufacturer" "Bourns"
				(at 20.32 -22.86 0)
				(effects
					(font
						(size 1.27 1.27)
						(thickness 0.15)
					)
					(justify left bottom)
					(hide yes)
				)
			)
			(property "License" "Apache-2.0"
				(at 20.32 -25.4 0)
				(effects
					(font
						(size 1.27 1.27)
						(thickness 0.15)
					)
					(justify left bottom)
					(hide yes)
				)
			)
			(property "Author" "Antmicro"
				(at 20.32 -27.94 0)
				(effects
					(font
						(size 1.27 1.27)
						(thickness 0.15)
					)
					(justify left bottom)
					(hide yes)
				)
			)
			(property "Val" "47k"
				(at 20.32 -7.62 0)
				(effects
					(font
						(size 1.27 1.27)
						(thickness 0.15)
					)
					(justify left bottom)
				)
			)
			(property "Tolerance" "1%"
				(at 20.32 -10.16 0)
				(effects
					(font
						(size 1.27 1.27)
					)
					(justify left bottom)
					(hide yes)
				)
			)
			(property "ki_keywords" "0402, SMT, RESISTOR, PASSIVE"
				(at 0 0 0)
				(effects
					(font
						(size 1.27 1.27)
					)
					(hide yes)
				)
			)
			(symbol "R_47k_0402_0_1"
				(rectangle
					(start 0.635 0.889)
					(end 4.445 -0.889)
					(stroke
						(width 0.254)
						(type default)
					)
					(fill
						(type none)
					)
				)
			)
			(symbol "R_47k_0402_1_1"
				(pin passive line
					(at 0 0 0)
					(length 0.635)
					(name "~"
						(effects
							(font
								(size 1.27 1.27)
							)
						)
					)
					(number "1"
						(effects
							(font
								(size 1.27 1.27)
							)
						)
					)
				)
				(pin passive line
					(at 5.08 0 180)
					(length 0.635)
					(name "~"
						(effects
							(font
								(size 1.27 1.27)
							)
						)
					)
					(number "2"
						(effects
							(font
								(size 1.27 1.27)
							)
						)
					)
				)
			)
		)
	(symbol "antmicroResistors0402:R_499R_0402"
			(pin_numbers hide)
			(pin_names hide)
			(exclude_from_sim no)
			(in_bom yes)
			(on_board yes)
			(property "Reference" "R"
				(at 20.32 -5.08 0)
				(effects
					(font
						(size 1.27 1.27)
						(thickness 0.15)
					)
					(justify left bottom)
				)
			)
			(property "Value" "R_499R_0402"
				(at 20.32 -12.7 0)
				(effects
					(font
						(size 1.27 1.27)
						(thickness 0.15)
					)
					(justify left bottom)
					(hide yes)
				)
			)
			(property "Footprint" "antmicro-footprints:R_0402_1005Metric"
				(at 20.32 -15.24 0)
				(effects
					(font
						(size 1.27 1.27)
						(thickness 0.15)
					)
					(justify left bottom)
					(hide yes)
				)
			)
			(property "Datasheet" "https://www.mouser.com/datasheet/2/54/cr-1858361.pdf"
				(at 20.32 -17.78 0)
				(effects
					(font
						(size 1.27 1.27)
						(thickness 0.15)
					)
					(justify left bottom)
					(hide yes)
				)
			)
			(property "Description" "SMD Chip Resistor, 499 ohm, ± 1%, 63 mW, 0402 [1005 Metric], Thick Film, General Purpose"
				(at 0 0 0)
				(effects
					(font
						(size 1.27 1.27)
					)
					(hide yes)
				)
			)
			(property "MPN" "CR0402-FX-4990GLF"
				(at 20.32 -20.32 0)
				(effects
					(font
						(size 1.27 1.27)
						(thickness 0.15)
					)
					(justify left bottom)
					(hide yes)
				)
			)
			(property "Manufacturer" "Bourns"
				(at 20.32 -22.86 0)
				(effects
					(font
						(size 1.27 1.27)
						(thickness 0.15)
					)
					(justify left bottom)
					(hide yes)
				)
			)
			(property "License" "Apache-2.0"
				(at 20.32 -25.4 0)
				(effects
					(font
						(size 1.27 1.27)
						(thickness 0.15)
					)
					(justify left bottom)
					(hide yes)
				)
			)
			(property "Author" "Antmicro"
				(at 20.32 -27.94 0)
				(effects
					(font
						(size 1.27 1.27)
						(thickness 0.15)
					)
					(justify left bottom)
					(hide yes)
				)
			)
			(property "Val" "499R"
				(at 20.32 -7.62 0)
				(effects
					(font
						(size 1.27 1.27)
						(thickness 0.15)
					)
					(justify left bottom)
				)
			)
			(property "Tolerance" "1%"
				(at 20.32 -10.16 0)
				(effects
					(font
						(size 1.27 1.27)
					)
					(justify left bottom)
					(hide yes)
				)
			)
			(property "ki_keywords" "0402, SMT, RESISTOR, PASSIVE"
				(at 0 0 0)
				(effects
					(font
						(size 1.27 1.27)
					)
					(hide yes)
				)
			)
			(symbol "R_499R_0402_0_1"
				(rectangle
					(start 0.635 0.889)
					(end 4.445 -0.889)
					(stroke
						(width 0.254)
						(type default)
					)
					(fill
						(type none)
					)
				)
			)
			(symbol "R_499R_0402_1_1"
				(pin passive line
					(at 0 0 0)
					(length 0.635)
					(name "~"
						(effects
							(font
								(size 1.27 1.27)
							)
						)
					)
					(number "1"
						(effects
							(font
								(size 1.27 1.27)
							)
						)
					)
				)
				(pin passive line
					(at 5.08 0 180)
					(length 0.635)
					(name "~"
						(effects
							(font
								(size 1.27 1.27)
							)
						)
					)
					(number "2"
						(effects
							(font
								(size 1.27 1.27)
							)
						)
					)
				)
			)
		)
	(symbol "antmicroResistors0402:R_499k_0402"
			(pin_numbers hide)
			(pin_names hide)
			(exclude_from_sim no)
			(in_bom yes)
			(on_board yes)
			(property "Reference" "R"
				(at 20.32 -5.08 0)
				(effects
					(font
						(size 1.27 1.27)
						(thickness 0.15)
					)
					(justify left bottom)
				)
			)
			(property "Value" "R_499k_0402"
				(at 20.32 -12.7 0)
				(effects
					(font
						(size 1.27 1.27)
						(thickness 0.15)
					)
					(justify left bottom)
					(hide yes)
				)
			)
			(property "Footprint" "antmicro-footprints:R_0402_1005Metric"
				(at 20.32 -15.24 0)
				(effects
					(font
						(size 1.27 1.27)
						(thickness 0.15)
					)
					(justify left bottom)
					(hide yes)
				)
			)
			(property "Datasheet" "https://www.mouser.com/datasheet/2/54/cr-1858361.pdf"
				(at 20.32 -17.78 0)
				(effects
					(font
						(size 1.27 1.27)
						(thickness 0.15)
					)
					(justify left bottom)
					(hide yes)
				)
			)
			(property "Description" "SMD Chip Resistor, 499 kohm, ± 1%, 63 mW, 0402 [1005 Metric], Thick Film, General Purpose"
				(at 0 0 0)
				(effects
					(font
						(size 1.27 1.27)
					)
					(hide yes)
				)
			)
			(property "MPN" "CR0402-FX-4993GLF"
				(at 20.32 -20.32 0)
				(effects
					(font
						(size 1.27 1.27)
						(thickness 0.15)
					)
					(justify left bottom)
					(hide yes)
				)
			)
			(property "Manufacturer" "Bourns"
				(at 20.32 -22.86 0)
				(effects
					(font
						(size 1.27 1.27)
						(thickness 0.15)
					)
					(justify left bottom)
					(hide yes)
				)
			)
			(property "License" "Apache-2.0"
				(at 20.32 -25.4 0)
				(effects
					(font
						(size 1.27 1.27)
						(thickness 0.15)
					)
					(justify left bottom)
					(hide yes)
				)
			)
			(property "Author" "Antmicro"
				(at 20.32 -27.94 0)
				(effects
					(font
						(size 1.27 1.27)
						(thickness 0.15)
					)
					(justify left bottom)
					(hide yes)
				)
			)
			(property "Val" "499k"
				(at 20.32 -7.62 0)
				(effects
					(font
						(size 1.27 1.27)
						(thickness 0.15)
					)
					(justify left bottom)
				)
			)
			(property "Tolerance" "1%"
				(at 20.32 -10.16 0)
				(effects
					(font
						(size 1.27 1.27)
					)
					(justify left bottom)
					(hide yes)
				)
			)
			(property "ki_keywords" "0402, SMT, RESISTOR, PASSIVE"
				(at 0 0 0)
				(effects
					(font
						(size 1.27 1.27)
					)
					(hide yes)
				)
			)
			(symbol "R_499k_0402_0_1"
				(rectangle
					(start 0.635 0.889)
					(end 4.445 -0.889)
					(stroke
						(width 0.254)
						(type default)
					)
					(fill
						(type none)
					)
				)
			)
			(symbol "R_499k_0402_1_1"
				(pin passive line
					(at 0 0 0)
					(length 0.635)
					(name "~"
						(effects
							(font
								(size 1.27 1.27)
							)
						)
					)
					(number "1"
						(effects
							(font
								(size 1.27 1.27)
							)
						)
					)
				)
				(pin passive line
					(at 5.08 0 180)
					(length 0.635)
					(name "~"
						(effects
							(font
								(size 1.27 1.27)
							)
						)
					)
					(number "2"
						(effects
							(font
								(size 1.27 1.27)
							)
						)
					)
				)
			)
		)
	(symbol "antmicroResistors0402:R_49k9_0402"
			(pin_numbers hide)
			(pin_names hide)
			(exclude_from_sim no)
			(in_bom yes)
			(on_board yes)
			(property "Reference" "R"
				(at 20.32 -5.08 0)
				(effects
					(font
						(size 1.27 1.27)
						(thickness 0.15)
					)
					(justify left bottom)
				)
			)
			(property "Value" "R_49k9_0402"
				(at 20.32 -12.7 0)
				(effects
					(font
						(size 1.27 1.27)
						(thickness 0.15)
					)
					(justify left bottom)
					(hide yes)
				)
			)
			(property "Footprint" "antmicro-footprints:R_0402_1005Metric"
				(at 20.32 -15.24 0)
				(effects
					(font
						(size 1.27 1.27)
						(thickness 0.15)
					)
					(justify left bottom)
					(hide yes)
				)
			)
			(property "Datasheet" "https://www.bourns.com/docs/product-datasheets/cr.pdf"
				(at 20.32 -17.78 0)
				(effects
					(font
						(size 1.27 1.27)
						(thickness 0.15)
					)
					(justify left bottom)
					(hide yes)
				)
			)
			(property "Description" "SMD Chip Resistor, 49.9 kohm, ± 1%, 63 mW, 0402 [1005 Metric], Thick Film, General Purpose"
				(at 0 0 0)
				(effects
					(font
						(size 1.27 1.27)
					)
					(hide yes)
				)
			)
			(property "MPN" "CR0402-FX-4992GLF"
				(at 20.32 -20.32 0)
				(effects
					(font
						(size 1.27 1.27)
						(thickness 0.15)
					)
					(justify left bottom)
					(hide yes)
				)
			)
			(property "Manufacturer" "Bourns"
				(at 20.32 -22.86 0)
				(effects
					(font
						(size 1.27 1.27)
						(thickness 0.15)
					)
					(justify left bottom)
					(hide yes)
				)
			)
			(property "License" "Apache-2.0"
				(at 20.32 -25.4 0)
				(effects
					(font
						(size 1.27 1.27)
						(thickness 0.15)
					)
					(justify left bottom)
					(hide yes)
				)
			)
			(property "Author" "Antmicro"
				(at 20.32 -27.94 0)
				(effects
					(font
						(size 1.27 1.27)
						(thickness 0.15)
					)
					(justify left bottom)
					(hide yes)
				)
			)
			(property "Val" "49k9"
				(at 20.32 -7.62 0)
				(effects
					(font
						(size 1.27 1.27)
						(thickness 0.15)
					)
					(justify left bottom)
				)
			)
			(property "Tolerance" "1%"
				(at 20.32 -10.16 0)
				(effects
					(font
						(size 1.27 1.27)
					)
					(justify left bottom)
					(hide yes)
				)
			)
			(property "ki_keywords" "0402, SMT, RESISTOR, PASSIVE"
				(at 0 0 0)
				(effects
					(font
						(size 1.27 1.27)
					)
					(hide yes)
				)
			)
			(symbol "R_49k9_0402_0_1"
				(rectangle
					(start 0.635 0.889)
					(end 4.445 -0.889)
					(stroke
						(width 0.254)
						(type default)
					)
					(fill
						(type none)
					)
				)
			)
			(symbol "R_49k9_0402_1_1"
				(pin passive line
					(at 0 0 0)
					(length 0.635)
					(name "~"
						(effects
							(font
								(size 1.27 1.27)
							)
						)
					)
					(number "1"
						(effects
							(font
								(size 1.27 1.27)
							)
						)
					)
				)
				(pin passive line
					(at 5.08 0 180)
					(length 0.635)
					(name "~"
						(effects
							(font
								(size 1.27 1.27)
							)
						)
					)
					(number "2"
						(effects
							(font
								(size 1.27 1.27)
							)
						)
					)
				)
			)
		)
	(symbol "antmicroResistors0402:R_4k7_0402"
			(pin_numbers hide)
			(pin_names hide)
			(exclude_from_sim no)
			(in_bom yes)
			(on_board yes)
			(property "Reference" "R"
				(at 20.32 -5.08 0)
				(effects
					(font
						(size 1.27 1.27)
						(thickness 0.15)
					)
					(justify left bottom)
				)
			)
			(property "Value" "R_4k7_0402"
				(at 20.32 -12.7 0)
				(effects
					(font
						(size 1.27 1.27)
						(thickness 0.15)
					)
					(justify left bottom)
					(hide yes)
				)
			)
			(property "Footprint" "antmicro-footprints:R_0402_1005Metric"
				(at 20.32 -15.24 0)
				(effects
					(font
						(size 1.27 1.27)
						(thickness 0.15)
					)
					(justify left bottom)
					(hide yes)
				)
			)
			(property "Datasheet" "https://www.bourns.com/docs/product-datasheets/cr.pdf"
				(at 20.32 -17.78 0)
				(effects
					(font
						(size 1.27 1.27)
						(thickness 0.15)
					)
					(justify left bottom)
					(hide yes)
				)
			)
			(property "Description" "SMD Chip Resistor, 4.7 kohm, ± 1%, 62.5 mW, 0402 [1005 Metric], Thick Film, General Purpose"
				(at 0 0 0)
				(effects
					(font
						(size 1.27 1.27)
					)
					(hide yes)
				)
			)
			(property "MPN" "CR0402-FX-4701GLF"
				(at 20.32 -20.32 0)
				(effects
					(font
						(size 1.27 1.27)
						(thickness 0.15)
					)
					(justify left bottom)
					(hide yes)
				)
			)
			(property "Manufacturer" "Bourns"
				(at 20.32 -22.86 0)
				(effects
					(font
						(size 1.27 1.27)
						(thickness 0.15)
					)
					(justify left bottom)
					(hide yes)
				)
			)
			(property "License" "Apache-2.0"
				(at 20.32 -25.4 0)
				(effects
					(font
						(size 1.27 1.27)
						(thickness 0.15)
					)
					(justify left bottom)
					(hide yes)
				)
			)
			(property "Author" "Antmicro"
				(at 20.32 -27.94 0)
				(effects
					(font
						(size 1.27 1.27)
						(thickness 0.15)
					)
					(justify left bottom)
					(hide yes)
				)
			)
			(property "Val" "4k7"
				(at 20.32 -7.62 0)
				(effects
					(font
						(size 1.27 1.27)
						(thickness 0.15)
					)
					(justify left bottom)
				)
			)
			(property "Tolerance" "1%"
				(at 20.32 -10.16 0)
				(effects
					(font
						(size 1.27 1.27)
					)
					(justify left bottom)
					(hide yes)
				)
			)
			(property "ki_keywords" "0402, SMT, RESISTOR, PASSIVE"
				(at 0 0 0)
				(effects
					(font
						(size 1.27 1.27)
					)
					(hide yes)
				)
			)
			(symbol "R_4k7_0402_0_1"
				(rectangle
					(start 0.635 0.889)
					(end 4.445 -0.889)
					(stroke
						(width 0.254)
						(type default)
					)
					(fill
						(type none)
					)
				)
			)
			(symbol "R_4k7_0402_1_1"
				(pin passive line
					(at 0 0 0)
					(length 0.635)
					(name "~"
						(effects
							(font
								(size 1.27 1.27)
							)
						)
					)
					(number "1"
						(effects
							(font
								(size 1.27 1.27)
							)
						)
					)
				)
				(pin passive line
					(at 5.08 0 180)
					(length 0.635)
					(name "~"
						(effects
							(font
								(size 1.27 1.27)
							)
						)
					)
					(number "2"
						(effects
							(font
								(size 1.27 1.27)
							)
						)
					)
				)
			)
		)
	(symbol "antmicroResistors0402:R_560R_0402"
			(pin_numbers hide)
			(pin_names hide)
			(exclude_from_sim no)
			(in_bom yes)
			(on_board yes)
			(property "Reference" "R"
				(at 20.32 -5.08 0)
				(effects
					(font
						(size 1.27 1.27)
						(thickness 0.15)
					)
					(justify left bottom)
				)
			)
			(property "Value" "R_560R_0402"
				(at 20.32 -12.7 0)
				(effects
					(font
						(size 1.27 1.27)
						(thickness 0.15)
					)
					(justify left bottom)
					(hide yes)
				)
			)
			(property "Footprint" "antmicro-footprints:R_0402_1005Metric"
				(at 20.32 -15.24 0)
				(effects
					(font
						(size 1.27 1.27)
						(thickness 0.15)
					)
					(justify left bottom)
					(hide yes)
				)
			)
			(property "Datasheet" "https://www.bourns.com/docs/product-datasheets/cr.pdf"
				(at 20.32 -17.78 0)
				(effects
					(font
						(size 1.27 1.27)
						(thickness 0.15)
					)
					(justify left bottom)
					(hide yes)
				)
			)
			(property "Description" "SMD Chip Resistor, 560 ohm, ± 1%, 100 mW, 0402 [1005 Metric], Thick Film, Precision"
				(at 0 0 0)
				(effects
					(font
						(size 1.27 1.27)
					)
					(hide yes)
				)
			)
			(property "MPN" "CR0402-FX-5600GLF"
				(at 20.32 -20.32 0)
				(effects
					(font
						(size 1.27 1.27)
						(thickness 0.15)
					)
					(justify left bottom)
					(hide yes)
				)
			)
			(property "Manufacturer" "Bourns"
				(at 20.32 -22.86 0)
				(effects
					(font
						(size 1.27 1.27)
						(thickness 0.15)
					)
					(justify left bottom)
					(hide yes)
				)
			)
			(property "License" "Apache-2.0"
				(at 20.32 -25.4 0)
				(effects
					(font
						(size 1.27 1.27)
						(thickness 0.15)
					)
					(justify left bottom)
					(hide yes)
				)
			)
			(property "Author" "Antmicro"
				(at 20.32 -27.94 0)
				(effects
					(font
						(size 1.27 1.27)
						(thickness 0.15)
					)
					(justify left bottom)
					(hide yes)
				)
			)
			(property "Val" "560R"
				(at 20.32 -7.62 0)
				(effects
					(font
						(size 1.27 1.27)
						(thickness 0.15)
					)
					(justify left bottom)
				)
			)
			(property "Tolerance" "1%"
				(at 20.32 -10.16 0)
				(effects
					(font
						(size 1.27 1.27)
					)
					(justify left bottom)
					(hide yes)
				)
			)
			(property "ki_keywords" "0402, SMT, RESISTOR, PASSIVE"
				(at 0 0 0)
				(effects
					(font
						(size 1.27 1.27)
					)
					(hide yes)
				)
			)
			(symbol "R_560R_0402_0_1"
				(rectangle
					(start 0.635 0.889)
					(end 4.445 -0.889)
					(stroke
						(width 0.254)
						(type default)
					)
					(fill
						(type none)
					)
				)
			)
			(symbol "R_560R_0402_1_1"
				(pin passive line
					(at 0 0 0)
					(length 0.635)
					(name "~"
						(effects
							(font
								(size 1.27 1.27)
							)
						)
					)
					(number "1"
						(effects
							(font
								(size 1.27 1.27)
							)
						)
					)
				)
				(pin passive line
					(at 5.08 0 180)
					(length 0.635)
					(name "~"
						(effects
							(font
								(size 1.27 1.27)
							)
						)
					)
					(number "2"
						(effects
							(font
								(size 1.27 1.27)
							)
						)
					)
				)
			)
		)
	(symbol "antmicroResistors0402:R_73k2_0402"
			(pin_numbers hide)
			(pin_names hide)
			(exclude_from_sim no)
			(in_bom yes)
			(on_board yes)
			(property "Reference" "R"
				(at 20.32 -5.08 0)
				(effects
					(font
						(size 1.27 1.27)
						(thickness 0.15)
					)
					(justify left bottom)
				)
			)
			(property "Value" "R_73k2_0402"
				(at 20.32 -12.7 0)
				(effects
					(font
						(size 1.27 1.27)
						(thickness 0.15)
					)
					(justify left bottom)
					(hide yes)
				)
			)
			(property "Footprint" "antmicro-footprints:R_0402_1005Metric"
				(at 20.32 -15.24 0)
				(effects
					(font
						(size 1.27 1.27)
						(thickness 0.15)
					)
					(justify left bottom)
					(hide yes)
				)
			)
			(property "Datasheet" "https://www.bourns.com/docs/product-datasheets/cr.pdf"
				(at 20.32 -17.78 0)
				(effects
					(font
						(size 1.27 1.27)
						(thickness 0.15)
					)
					(justify left bottom)
					(hide yes)
				)
			)
			(property "Description" "SMD Chip Resistor"
				(at 0 0 0)
				(effects
					(font
						(size 1.27 1.27)
					)
					(hide yes)
				)
			)
			(property "MPN" "CR0402-FX-7322GLF"
				(at 20.32 -20.32 0)
				(effects
					(font
						(size 1.27 1.27)
						(thickness 0.15)
					)
					(justify left bottom)
					(hide yes)
				)
			)
			(property "Manufacturer" "Bourns"
				(at 20.32 -22.86 0)
				(effects
					(font
						(size 1.27 1.27)
						(thickness 0.15)
					)
					(justify left bottom)
					(hide yes)
				)
			)
			(property "License" "Apache-2.0"
				(at 20.32 -25.4 0)
				(effects
					(font
						(size 1.27 1.27)
						(thickness 0.15)
					)
					(justify left bottom)
					(hide yes)
				)
			)
			(property "Author" "Antmicro"
				(at 20.32 -27.94 0)
				(effects
					(font
						(size 1.27 1.27)
						(thickness 0.15)
					)
					(justify left bottom)
					(hide yes)
				)
			)
			(property "Val" "73k2"
				(at 20.32 -7.62 0)
				(effects
					(font
						(size 1.27 1.27)
						(thickness 0.15)
					)
					(justify left bottom)
				)
			)
			(property "Tolerance" "1%"
				(at 20.32 -10.16 0)
				(effects
					(font
						(size 1.27 1.27)
					)
					(justify left bottom)
					(hide yes)
				)
			)
			(property "ki_keywords" "0402, SMT, RESISTOR, PASSIVE"
				(at 0 0 0)
				(effects
					(font
						(size 1.27 1.27)
					)
					(hide yes)
				)
			)
			(symbol "R_73k2_0402_0_1"
				(rectangle
					(start 0.635 0.889)
					(end 4.445 -0.889)
					(stroke
						(width 0.254)
						(type default)
					)
					(fill
						(type none)
					)
				)
			)
			(symbol "R_73k2_0402_1_1"
				(pin passive line
					(at 0 0 0)
					(length 0.635)
					(name "~"
						(effects
							(font
								(size 1.27 1.27)
							)
						)
					)
					(number "1"
						(effects
							(font
								(size 1.27 1.27)
							)
						)
					)
				)
				(pin passive line
					(at 5.08 0 180)
					(length 0.635)
					(name "~"
						(effects
							(font
								(size 1.27 1.27)
							)
						)
					)
					(number "2"
						(effects
							(font
								(size 1.27 1.27)
							)
						)
					)
				)
			)
		)
	(symbol "antmicroResistors0402:R_887k_0402"
			(pin_numbers hide)
			(pin_names hide)
			(exclude_from_sim no)
			(in_bom yes)
			(on_board yes)
			(property "Reference" "R"
				(at 20.32 -5.08 0)
				(effects
					(font
						(size 1.27 1.27)
						(thickness 0.15)
					)
					(justify left bottom)
				)
			)
			(property "Value" "R_887k_0402"
				(at 20.32 -12.7 0)
				(effects
					(font
						(size 1.27 1.27)
						(thickness 0.15)
					)
					(justify left bottom)
					(hide yes)
				)
			)
			(property "Footprint" "antmicro-footprints:R_0402_1005Metric"
				(at 20.32 -15.24 0)
				(effects
					(font
						(size 1.27 1.27)
						(thickness 0.15)
					)
					(justify left bottom)
					(hide yes)
				)
			)
			(property "Datasheet" "https://eu.mouser.com/datasheet/2/315/AOA0000C304-1149620.pdf"
				(at 20.32 -17.78 0)
				(effects
					(font
						(size 1.27 1.27)
						(thickness 0.15)
					)
					(justify left bottom)
					(hide yes)
				)
			)
			(property "Description" "SMD Chip Resistor"
				(at 0 0 0)
				(effects
					(font
						(size 1.27 1.27)
					)
					(hide yes)
				)
			)
			(property "MPN" "ERJ-2RKF8873X"
				(at 20.32 -20.32 0)
				(effects
					(font
						(size 1.27 1.27)
						(thickness 0.15)
					)
					(justify left bottom)
					(hide yes)
				)
			)
			(property "Manufacturer" "Panasonic"
				(at 20.32 -22.86 0)
				(effects
					(font
						(size 1.27 1.27)
						(thickness 0.15)
					)
					(justify left bottom)
					(hide yes)
				)
			)
			(property "License" "Apache-2.0"
				(at 20.32 -25.4 0)
				(effects
					(font
						(size 1.27 1.27)
						(thickness 0.15)
					)
					(justify left bottom)
					(hide yes)
				)
			)
			(property "Author" "Antmicro"
				(at 20.32 -27.94 0)
				(effects
					(font
						(size 1.27 1.27)
						(thickness 0.15)
					)
					(justify left bottom)
					(hide yes)
				)
			)
			(property "Val" "887k"
				(at 20.32 -7.62 0)
				(effects
					(font
						(size 1.27 1.27)
						(thickness 0.15)
					)
					(justify left bottom)
				)
			)
			(property "Tolerance" "1%"
				(at 20.32 -10.16 0)
				(effects
					(font
						(size 1.27 1.27)
					)
					(justify left bottom)
					(hide yes)
				)
			)
			(property "ki_keywords" "0402, SMT, RESISTOR, PASSIVE"
				(at 0 0 0)
				(effects
					(font
						(size 1.27 1.27)
					)
					(hide yes)
				)
			)
			(symbol "R_887k_0402_0_1"
				(rectangle
					(start 0.635 0.889)
					(end 4.445 -0.889)
					(stroke
						(width 0.254)
						(type default)
					)
					(fill
						(type none)
					)
				)
			)
			(symbol "R_887k_0402_1_1"
				(pin passive line
					(at 0 0 0)
					(length 0.635)
					(name "~"
						(effects
							(font
								(size 1.27 1.27)
							)
						)
					)
					(number "1"
						(effects
							(font
								(size 1.27 1.27)
							)
						)
					)
				)
				(pin passive line
					(at 5.08 0 180)
					(length 0.635)
					(name "~"
						(effects
							(font
								(size 1.27 1.27)
							)
						)
					)
					(number "2"
						(effects
							(font
								(size 1.27 1.27)
							)
						)
					)
				)
			)
		)
	(symbol "antmicroResistors0603:R_0R_0603"
			(pin_numbers hide)
			(pin_names hide)
			(exclude_from_sim no)
			(in_bom yes)
			(on_board yes)
			(property "Reference" "R"
				(at 20.32 -5.08 0)
				(effects
					(font
						(size 1.27 1.27)
						(thickness 0.15)
					)
					(justify left bottom)
				)
			)
			(property "Value" "R_0R_0603"
				(at 20.32 -12.7 0)
				(effects
					(font
						(size 1.27 1.27)
						(thickness 0.15)
					)
					(justify left bottom)
					(hide yes)
				)
			)
			(property "Footprint" "antmicro-footprints:R_0603_1608Metric"
				(at 20.32 -15.24 0)
				(effects
					(font
						(size 1.27 1.27)
						(thickness 0.15)
					)
					(justify left bottom)
					(hide yes)
				)
			)
			(property "Datasheet" "https://www.bourns.com/docs/product-datasheets/cr.pdf?sfvrsn=574d41f6_14"
				(at 20.32 -17.78 0)
				(effects
					(font
						(size 1.27 1.27)
						(thickness 0.15)
					)
					(justify left bottom)
					(hide yes)
				)
			)
			(property "Description" "Zero Ohm Resistor, Jumper, 0603 [1608 Metric], Thick Film, 100 mW, 1 A, Surface Mount Device, CR"
				(at 0 0 0)
				(effects
					(font
						(size 1.27 1.27)
					)
					(hide yes)
				)
			)
			(property "MPN" "CR0603-J/-000ELF"
				(at 20.32 -20.32 0)
				(effects
					(font
						(size 1.27 1.27)
						(thickness 0.15)
					)
					(justify left bottom)
					(hide yes)
				)
			)
			(property "Manufacturer" "Bourns"
				(at 20.32 -22.86 0)
				(effects
					(font
						(size 1.27 1.27)
						(thickness 0.15)
					)
					(justify left bottom)
					(hide yes)
				)
			)
			(property "License" "Apache-2.0"
				(at 20.32 -25.4 0)
				(effects
					(font
						(size 1.27 1.27)
						(thickness 0.15)
					)
					(justify left bottom)
					(hide yes)
				)
			)
			(property "Author" "Antmicro"
				(at 20.32 -27.94 0)
				(effects
					(font
						(size 1.27 1.27)
						(thickness 0.15)
					)
					(justify left bottom)
					(hide yes)
				)
			)
			(property "Val" "0R"
				(at 20.32 -7.62 0)
				(effects
					(font
						(size 1.27 1.27)
						(thickness 0.15)
					)
					(justify left bottom)
				)
			)
			(property "Tolerance" "~"
				(at 20.32 -10.16 0)
				(effects
					(font
						(size 1.27 1.27)
					)
					(justify left bottom)
					(hide yes)
				)
			)
			(property "Current" "1A"
				(at 20.32 -30.48 0)
				(effects
					(font
						(size 1.27 1.27)
						(thickness 0.15)
					)
					(justify left bottom)
					(hide yes)
				)
			)
			(property "ki_keywords" "0603, SMT, RESISTOR, PASSIVE"
				(at 0 0 0)
				(effects
					(font
						(size 1.27 1.27)
					)
					(hide yes)
				)
			)
			(symbol "R_0R_0603_0_1"
				(rectangle
					(start 0.635 0.889)
					(end 4.445 -0.889)
					(stroke
						(width 0.254)
						(type default)
					)
					(fill
						(type none)
					)
				)
			)
			(symbol "R_0R_0603_1_1"
				(pin passive line
					(at 0 0 0)
					(length 0.635)
					(name "~"
						(effects
							(font
								(size 1.27 1.27)
							)
						)
					)
					(number "1"
						(effects
							(font
								(size 1.27 1.27)
							)
						)
					)
				)
				(pin passive line
					(at 5.08 0 180)
					(length 0.635)
					(name "~"
						(effects
							(font
								(size 1.27 1.27)
							)
						)
					)
					(number "2"
						(effects
							(font
								(size 1.27 1.27)
							)
						)
					)
				)
			)
		)
	(symbol "antmicroResistors0603:R_0R_22.4A_0603"
			(pin_numbers hide)
			(pin_names hide)
			(exclude_from_sim no)
			(in_bom yes)
			(on_board yes)
			(property "Reference" "R"
				(at 15.24 -2.54 0)
				(effects
					(font
						(size 1.27 1.27)
						(thickness 0.15)
					)
					(justify left bottom)
				)
			)
			(property "Value" "R_0R_22.4A_0603"
				(at 15.24 -5.08 0)
				(effects
					(font
						(size 1.27 1.27)
						(thickness 0.15)
					)
					(justify left bottom)
				)
			)
			(property "Footprint" "antmicro-footprints:R_0603_1608Metric"
				(at 15.24 -10.16 0)
				(effects
					(font
						(size 1.27 1.27)
						(thickness 0.15)
					)
					(justify left bottom)
					(hide yes)
				)
			)
			(property "Datasheet" "https://fscdn.rohm.com/en/products/databook/datasheet/passive/resistor/chip_resistor/pmr-jpw-e.pdf"
				(at 15.24 -12.7 0)
				(effects
					(font
						(size 1.27 1.27)
						(thickness 0.15)
					)
					(justify left bottom)
					(hide yes)
				)
			)
			(property "Description" "SMD Chip Resistor"
				(at 0 0 0)
				(effects
					(font
						(size 1.27 1.27)
					)
					(hide yes)
				)
			)
			(property "MPN" "PMR03EZPJ000"
				(at 15.24 -15.24 0)
				(effects
					(font
						(size 1.27 1.27)
						(thickness 0.15)
					)
					(justify left bottom)
					(hide yes)
				)
			)
			(property "Manufacturer" "ROHM Semiconductor"
				(at 15.24 -17.78 0)
				(effects
					(font
						(size 1.27 1.27)
						(thickness 0.15)
					)
					(justify left bottom)
					(hide yes)
				)
			)
			(property "Val" "0R"
				(at 15.24 -7.62 0)
				(effects
					(font
						(size 1.27 1.27)
						(thickness 0.15)
					)
					(justify left bottom)
				)
			)
			(property "Max. Curr." "22.4A"
				(at 15.24 -20.32 0)
				(effects
					(font
						(size 1.27 1.27)
						(thickness 0.15)
					)
					(justify left bottom)
				)
			)
			(property "Author" "Antmicro"
				(at 15.24 -22.86 0)
				(effects
					(font
						(size 1.27 1.27)
						(thickness 0.15)
					)
					(justify left bottom)
					(hide yes)
				)
			)
			(property "License" "Apache-2.0"
				(at 15.24 -25.4 0)
				(effects
					(font
						(size 1.27 1.27)
						(thickness 0.15)
					)
					(justify left bottom)
					(hide yes)
				)
			)
			(property "Tolerance" "template_tolerance"
				(at 20.32 -10.16 0)
				(effects
					(font
						(size 1.27 1.27)
					)
					(justify left bottom)
					(hide yes)
				)
			)
			(property "ki_keywords" "0603, SMT, RESISTOR, PASSIVE"
				(at 0 0 0)
				(effects
					(font
						(size 1.27 1.27)
					)
					(hide yes)
				)
			)
			(symbol "R_0R_22.4A_0603_0_1"
				(rectangle
					(start 0.635 0.889)
					(end 4.445 -0.889)
					(stroke
						(width 0.254)
						(type default)
					)
					(fill
						(type none)
					)
				)
			)
			(symbol "R_0R_22.4A_0603_1_1"
				(pin passive line
					(at 0 0 0)
					(length 0.635)
					(name "~"
						(effects
							(font
								(size 1.27 1.27)
							)
						)
					)
					(number "1"
						(effects
							(font
								(size 1.27 1.27)
							)
						)
					)
				)
				(pin passive line
					(at 5.08 0 180)
					(length 0.635)
					(name "~"
						(effects
							(font
								(size 1.27 1.27)
							)
						)
					)
					(number "2"
						(effects
							(font
								(size 1.27 1.27)
							)
						)
					)
				)
			)
		)
	(symbol "antmicroResistors0603:R_63R4_0603"
			(pin_numbers hide)
			(pin_names hide)
			(exclude_from_sim no)
			(in_bom yes)
			(on_board yes)
			(property "Reference" "R"
				(at 20.32 -5.08 0)
				(effects
					(font
						(size 1.27 1.27)
						(thickness 0.15)
					)
					(justify left bottom)
				)
			)
			(property "Value" "R_63R4_0603"
				(at 20.32 -12.7 0)
				(effects
					(font
						(size 1.27 1.27)
						(thickness 0.15)
					)
					(justify left bottom)
					(hide yes)
				)
			)
			(property "Footprint" "antmicro-footprints:R_0603_1608Metric"
				(at 20.32 -15.24 0)
				(effects
					(font
						(size 1.27 1.27)
						(thickness 0.15)
					)
					(justify left bottom)
					(hide yes)
				)
			)
			(property "Datasheet" "https://www.bourns.com/docs/product-datasheets/cr.pdf"
				(at 20.32 -17.78 0)
				(effects
					(font
						(size 1.27 1.27)
						(thickness 0.15)
					)
					(justify left bottom)
					(hide yes)
				)
			)
			(property "Description" "SMD Chip Resistor"
				(at 0 0 0)
				(effects
					(font
						(size 1.27 1.27)
					)
					(hide yes)
				)
			)
			(property "MPN" "CR0603-FX-63R4ELF"
				(at 20.32 -20.32 0)
				(effects
					(font
						(size 1.27 1.27)
						(thickness 0.15)
					)
					(justify left bottom)
					(hide yes)
				)
			)
			(property "Manufacturer" "Bourns"
				(at 20.32 -22.86 0)
				(effects
					(font
						(size 1.27 1.27)
						(thickness 0.15)
					)
					(justify left bottom)
					(hide yes)
				)
			)
			(property "License" "Apache-2.0"
				(at 20.32 -25.4 0)
				(effects
					(font
						(size 1.27 1.27)
						(thickness 0.15)
					)
					(justify left bottom)
					(hide yes)
				)
			)
			(property "Author" "Antmicro"
				(at 20.32 -27.94 0)
				(effects
					(font
						(size 1.27 1.27)
						(thickness 0.15)
					)
					(justify left bottom)
					(hide yes)
				)
			)
			(property "Val" "63R4"
				(at 20.32 -7.62 0)
				(effects
					(font
						(size 1.27 1.27)
						(thickness 0.15)
					)
					(justify left bottom)
				)
			)
			(property "Tolerance" "1%"
				(at 20.32 -10.16 0)
				(effects
					(font
						(size 1.27 1.27)
					)
					(justify left bottom)
					(hide yes)
				)
			)
			(property "ki_keywords" "0603, SMT, RESISTOR, PASSIVE"
				(at 0 0 0)
				(effects
					(font
						(size 1.27 1.27)
					)
					(hide yes)
				)
			)
			(symbol "R_63R4_0603_0_1"
				(rectangle
					(start 0.635 0.889)
					(end 4.445 -0.889)
					(stroke
						(width 0.254)
						(type default)
					)
					(fill
						(type none)
					)
				)
			)
			(symbol "R_63R4_0603_1_1"
				(pin passive line
					(at 0 0 0)
					(length 0.635)
					(name "~"
						(effects
							(font
								(size 1.27 1.27)
							)
						)
					)
					(number "1"
						(effects
							(font
								(size 1.27 1.27)
							)
						)
					)
				)
				(pin passive line
					(at 5.08 0 180)
					(length 0.635)
					(name "~"
						(effects
							(font
								(size 1.27 1.27)
							)
						)
					)
					(number "2"
						(effects
							(font
								(size 1.27 1.27)
							)
						)
					)
				)
			)
		)
	(symbol "antmicroSlideSwitches:SW_SPDT_PCM12SMTR"
			(exclude_from_sim no)
			(in_bom yes)
			(on_board yes)
			(property "Reference" "SW"
				(at 27.94 -5.08 0)
				(effects
					(font
						(size 1.27 1.27)
						(thickness 0.15)
					)
					(justify left bottom)
				)
			)
			(property "Value" "SW_SPDT_PCM12SMTR"
				(at 27.94 -7.62 0)
				(effects
					(font
						(size 1.27 1.27)
						(thickness 0.15)
					)
					(justify left bottom)
				)
			)
			(property "Footprint" "antmicro-footprints:PCM12SMTR"
				(at 27.94 -10.16 0)
				(effects
					(font
						(size 1.27 1.27)
						(thickness 0.15)
					)
					(justify left bottom)
					(hide yes)
				)
			)
			(property "Datasheet" "https://www.mouser.com/datasheet/2/60/pcm-1841544.pdf"
				(at 27.94 -12.7 0)
				(effects
					(font
						(size 1.27 1.27)
						(thickness 0.15)
					)
					(justify left bottom)
					(hide yes)
				)
			)
			(property "Description" "Slide switch"
				(at 0 0 0)
				(effects
					(font
						(size 1.27 1.27)
					)
					(hide yes)
				)
			)
			(property "Manufacturer" "C&K"
				(at 27.94 -15.24 0)
				(effects
					(font
						(size 1.27 1.27)
						(thickness 0.15)
					)
					(justify left bottom)
					(hide yes)
				)
			)
			(property "MPN" "PCM12SMTR"
				(at 27.94 -17.78 0)
				(effects
					(font
						(size 1.27 1.27)
						(thickness 0.15)
					)
					(justify left bottom)
					(hide yes)
				)
			)
			(property "Author" "Antmicro"
				(at 27.94 -20.32 0)
				(effects
					(font
						(size 1.27 1.27)
						(thickness 0.15)
					)
					(justify left bottom)
					(hide yes)
				)
			)
			(property "License" "Apache-2.0"
				(at 27.94 -22.86 0)
				(effects
					(font
						(size 1.27 1.27)
						(thickness 0.15)
					)
					(justify left bottom)
					(hide yes)
				)
			)
			(property "ki_keywords" "VERTICAL, SMT, SWITCH, SWITCH, SLIDE"
				(at 0 0 0)
				(effects
					(font
						(size 1.27 1.27)
					)
					(hide yes)
				)
			)
			(symbol "SW_SPDT_PCM12SMTR_1_1"
				(polyline
					(pts
						(xy 3.81 0) (xy 2.54 0)
					)
					(stroke
						(width 0.254)
						(type default)
					)
					(fill
						(type none)
					)
				)
				(polyline
					(pts
						(xy 4.318 0) (xy 8.89 -2.54)
					)
					(stroke
						(width 0.254)
						(type default)
					)
					(fill
						(type none)
					)
				)
				(polyline
					(pts
						(xy 10.16 -2.54) (xy 8.89 -2.54)
					)
					(stroke
						(width 0.254)
						(type default)
					)
					(fill
						(type none)
					)
				)
				(polyline
					(pts
						(xy 10.16 2.54) (xy 8.89 2.54)
					)
					(stroke
						(width 0.254)
						(type default)
					)
					(fill
						(type none)
					)
				)
				(rectangle
					(start 2.54 3.81)
					(end 10.16 -3.81)
					(stroke
						(width 0.254)
						(type default)
					)
					(fill
						(type background)
					)
				)
				(circle
					(center 4.064 0)
					(radius 0.3556)
					(stroke
						(width 0.254)
						(type default)
					)
					(fill
						(type outline)
					)
				)
				(circle
					(center 8.636 -2.54)
					(radius 0.3556)
					(stroke
						(width 0.254)
						(type default)
					)
					(fill
						(type outline)
					)
				)
				(circle
					(center 8.89 2.54)
					(radius 0.3556)
					(stroke
						(width 0.254)
						(type default)
					)
					(fill
						(type outline)
					)
				)
				(pin passive line
					(at 12.7 2.54 180)
					(length 2.54)
					(name "~"
						(effects
							(font
								(size 1.27 1.27)
							)
						)
					)
					(number "1"
						(effects
							(font
								(size 1.27 1.27)
							)
						)
					)
				)
				(pin passive line
					(at 0 0 0)
					(length 2.54)
					(name "~"
						(effects
							(font
								(size 1.27 1.27)
							)
						)
					)
					(number "2"
						(effects
							(font
								(size 1.27 1.27)
							)
						)
					)
				)
				(pin passive line
					(at 12.7 -2.54 180)
					(length 2.54)
					(name "~"
						(effects
							(font
								(size 1.27 1.27)
							)
						)
					)
					(number "3"
						(effects
							(font
								(size 1.27 1.27)
							)
						)
					)
				)
				(pin passive line
					(at 0 -2.54 0)
					(length 2.54) hide
					(name "SH"
						(effects
							(font
								(size 1.27 1.27)
							)
						)
					)
					(number "S1"
						(effects
							(font
								(size 1.27 1.27)
							)
						)
					)
				)
				(pin passive line
					(at 0 -2.54 0)
					(length 2.54) hide
					(name "SH"
						(effects
							(font
								(size 1.27 1.27)
							)
						)
					)
					(number "S2"
						(effects
							(font
								(size 1.27 1.27)
							)
						)
					)
				)
				(pin passive line
					(at 0 -2.54 0)
					(length 2.54) hide
					(name "SH"
						(effects
							(font
								(size 1.27 1.27)
							)
						)
					)
					(number "S3"
						(effects
							(font
								(size 1.27 1.27)
							)
						)
					)
				)
				(pin passive line
					(at 0 -2.54 0)
					(length 2.54)
					(name "SH"
						(effects
							(font
								(size 1.27 1.27)
							)
						)
					)
					(number "S4"
						(effects
							(font
								(size 1.27 1.27)
							)
						)
					)
				)
			)
		)
	(symbol "antmicroSoMConnectors:Bus_DDR4_SODIMM_CUSTOM_Jetson-Orin-H9.2mm-socket"
			(exclude_from_sim no)
			(in_bom yes)
			(on_board yes)
			(property "Reference" "J"
				(at 62.23 -5.08 0)
				(effects
					(font
						(size 1.27 1.27)
						(thickness 0.15)
					)
					(justify left bottom)
				)
			)
			(property "Value" "Bus_DDR4_SODIMM_CUSTOM_Jetson-Orin-H9.2mm-socket"
				(at 62.23 -7.62 0)
				(effects
					(font
						(size 1.27 1.27)
						(thickness 0.15)
					)
					(justify left bottom)
					(hide yes)
				)
			)
			(property "Footprint" "antmicro-footprints:TE_2309413"
				(at 62.23 -10.16 0)
				(effects
					(font
						(size 1.27 1.27)
						(thickness 0.15)
					)
					(justify left bottom)
					(hide yes)
				)
			)
			(property "Datasheet" "https://developer.nvidia.com/jetson-orin-nx-series-data-sheet"
				(at 62.23 -12.7 0)
				(effects
					(font
						(size 1.27 1.27)
						(thickness 0.15)
					)
					(justify left bottom)
					(hide yes)
				)
			)
			(property "Description" "SoM connector"
				(at 0 0 0)
				(effects
					(font
						(size 1.27 1.27)
					)
					(hide yes)
				)
			)
			(property "Manufacturer" "TE Connectivity"
				(at 62.23 -15.24 0)
				(effects
					(font
						(size 1.27 1.27)
						(thickness 0.15)
					)
					(justify left bottom)
					(hide yes)
				)
			)
			(property "MPN" "2309413-1"
				(at 62.23 -17.78 0)
				(effects
					(font
						(size 1.27 1.27)
						(thickness 0.15)
					)
					(justify left bottom)
				)
			)
			(property "License" "Apache-2.0"
				(at 62.23 -20.32 0)
				(effects
					(font
						(size 1.27 1.27)
						(thickness 0.15)
					)
					(justify left bottom)
					(hide yes)
				)
			)
			(property "Author" "Antmicro"
				(at 62.23 -22.86 0)
				(effects
					(font
						(size 1.27 1.27)
						(thickness 0.15)
					)
					(justify left bottom)
					(hide yes)
				)
			)
			(property "ki_locked" ""
				(at 0 0 0)
				(effects
					(font
						(size 1.27 1.27)
					)
				)
			)
			(property "ki_keywords" "HORIZONTAL, SMT, MEMORY, CONNECTOR, DDR"
				(at 0 0 0)
				(effects
					(font
						(size 1.27 1.27)
					)
					(hide yes)
				)
			)
			(symbol "Bus_DDR4_SODIMM_CUSTOM_Jetson-Orin-H9.2mm-socket_1_1"
				(rectangle
					(start 3.81 5.08)
					(end 44.45 -30.48)
					(stroke
						(width 0.254)
						(type default)
					)
					(fill
						(type background)
					)
				)
				(text "1.8V Bidir "
					(at 26.67 -1.27 0)
					(effects
						(font
							(size 0.635 0.635)
							(thickness 0.15)
						)
						(justify right)
					)
				)
				(text "1.8V Bidir "
					(at 31.75 -3.81 0)
					(effects
						(font
							(size 0.635 0.635)
							(thickness 0.15)
						)
						(justify right)
					)
				)
				(text "1.8V CMOS Output"
					(at 31.115 -20.32 0)
					(effects
						(font
							(size 0.635 0.635)
							(thickness 0.15)
						)
						(justify right)
					)
				)
				(text "1.8V-5.5V Input"
					(at 15.24 -6.35 0)
					(effects
						(font
							(size 0.635 0.635)
							(thickness 0.15)
						)
						(justify left)
					)
				)
				(text "100k PU to 1.8V Input "
					(at 31.75 -17.78 0)
					(effects
						(font
							(size 0.635 0.635)
							(thickness 0.15)
						)
						(justify right)
					)
				)
				(text "1k PU to 1.8V Output "
					(at 31.75 -24.13 0)
					(effects
						(font
							(size 0.635 0.635)
							(thickness 0.15)
						)
						(justify right)
					)
				)
				(text "5.0V to 20V"
					(at 11.43 0 0)
					(effects
						(font
							(size 0.635 0.635)
							(thickness 0.15)
						)
						(justify left)
					)
				)
				(text "5V w/ PD Analog Input"
					(at 31.115 -11.43 0)
					(effects
						(font
							(size 0.635 0.635)
							(thickness 0.15)
						)
						(justify right)
					)
				)
				(text "Floating"
					(at 26.67 2.54 0)
					(effects
						(font
							(size 0.635 0.635)
							(thickness 0.15)
						)
						(justify right)
					)
				)
				(text "PU to 1.8V Bidir "
					(at 31.75 -13.97 0)
					(effects
						(font
							(size 0.635 0.635)
							(thickness 0.15)
						)
						(justify right)
					)
				)
				(text "PU to 1.8V Input"
					(at 26.67 -27.94 0)
					(effects
						(font
							(size 0.635 0.635)
							(thickness 0.15)
						)
						(justify right)
					)
				)
				(text "PU to VDD_IN Output"
					(at 27.94 -8.89 0)
					(effects
						(font
							(size 0.635 0.635)
							(thickness 0.15)
						)
						(justify right)
					)
				)
				(pin passive line
					(at 0 -27.94 0)
					(length 3.81)
					(name "GND"
						(effects
							(font
								(size 1.27 1.27)
							)
						)
					)
					(number "1"
						(effects
							(font
								(size 1.27 1.27)
							)
						)
					)
				)
				(pin passive line
					(at 0 -27.94 0)
					(length 3.81) hide
					(name "GND"
						(effects
							(font
								(size 1.27 1.27)
							)
						)
					)
					(number "102"
						(effects
							(font
								(size 1.27 1.27)
							)
						)
					)
				)
				(pin passive line
					(at 0 -27.94 0)
					(length 3.81) hide
					(name "GND"
						(effects
							(font
								(size 1.27 1.27)
							)
						)
					)
					(number "107"
						(effects
							(font
								(size 1.27 1.27)
							)
						)
					)
				)
				(pin passive line
					(at 0 -27.94 0)
					(length 3.81) hide
					(name "GND"
						(effects
							(font
								(size 1.27 1.27)
							)
						)
					)
					(number "113"
						(effects
							(font
								(size 1.27 1.27)
							)
						)
					)
				)
				(pin passive line
					(at 0 -27.94 0)
					(length 3.81) hide
					(name "GND"
						(effects
							(font
								(size 1.27 1.27)
							)
						)
					)
					(number "119"
						(effects
							(font
								(size 1.27 1.27)
							)
						)
					)
				)
				(pin passive line
					(at 0 -27.94 0)
					(length 3.81) hide
					(name "GND"
						(effects
							(font
								(size 1.27 1.27)
							)
						)
					)
					(number "125"
						(effects
							(font
								(size 1.27 1.27)
							)
						)
					)
				)
				(pin passive line
					(at 0 -27.94 0)
					(length 3.81) hide
					(name "GND"
						(effects
							(font
								(size 1.27 1.27)
							)
						)
					)
					(number "129"
						(effects
							(font
								(size 1.27 1.27)
							)
						)
					)
				)
				(pin passive line
					(at 0 -27.94 0)
					(length 3.81) hide
					(name "GND"
						(effects
							(font
								(size 1.27 1.27)
							)
						)
					)
					(number "13"
						(effects
							(font
								(size 1.27 1.27)
							)
						)
					)
				)
				(pin passive line
					(at 0 -27.94 0)
					(length 3.81) hide
					(name "GND"
						(effects
							(font
								(size 1.27 1.27)
							)
						)
					)
					(number "132"
						(effects
							(font
								(size 1.27 1.27)
							)
						)
					)
				)
				(pin passive line
					(at 0 -27.94 0)
					(length 3.81) hide
					(name "GND"
						(effects
							(font
								(size 1.27 1.27)
							)
						)
					)
					(number "135"
						(effects
							(font
								(size 1.27 1.27)
							)
						)
					)
				)
				(pin passive line
					(at 0 -27.94 0)
					(length 3.81) hide
					(name "GND"
						(effects
							(font
								(size 1.27 1.27)
							)
						)
					)
					(number "138"
						(effects
							(font
								(size 1.27 1.27)
							)
						)
					)
				)
				(pin passive line
					(at 0 -27.94 0)
					(length 3.81) hide
					(name "GND"
						(effects
							(font
								(size 1.27 1.27)
							)
						)
					)
					(number "14"
						(effects
							(font
								(size 1.27 1.27)
							)
						)
					)
				)
				(pin passive line
					(at 0 -27.94 0)
					(length 3.81) hide
					(name "GND"
						(effects
							(font
								(size 1.27 1.27)
							)
						)
					)
					(number "141"
						(effects
							(font
								(size 1.27 1.27)
							)
						)
					)
				)
				(pin passive line
					(at 0 -27.94 0)
					(length 3.81) hide
					(name "GND"
						(effects
							(font
								(size 1.27 1.27)
							)
						)
					)
					(number "144"
						(effects
							(font
								(size 1.27 1.27)
							)
						)
					)
				)
				(pin passive line
					(at 0 -27.94 0)
					(length 3.81) hide
					(name "GND"
						(effects
							(font
								(size 1.27 1.27)
							)
						)
					)
					(number "146"
						(effects
							(font
								(size 1.27 1.27)
							)
						)
					)
				)
				(pin passive line
					(at 0 -27.94 0)
					(length 3.81) hide
					(name "GND"
						(effects
							(font
								(size 1.27 1.27)
							)
						)
					)
					(number "147"
						(effects
							(font
								(size 1.27 1.27)
							)
						)
					)
				)
				(pin passive line
					(at 0 -27.94 0)
					(length 3.81) hide
					(name "GND"
						(effects
							(font
								(size 1.27 1.27)
							)
						)
					)
					(number "152"
						(effects
							(font
								(size 1.27 1.27)
							)
						)
					)
				)
				(pin passive line
					(at 0 -27.94 0)
					(length 3.81) hide
					(name "GND"
						(effects
							(font
								(size 1.27 1.27)
							)
						)
					)
					(number "153"
						(effects
							(font
								(size 1.27 1.27)
							)
						)
					)
				)
				(pin passive line
					(at 0 -27.94 0)
					(length 3.81) hide
					(name "GND"
						(effects
							(font
								(size 1.27 1.27)
							)
						)
					)
					(number "158"
						(effects
							(font
								(size 1.27 1.27)
							)
						)
					)
				)
				(pin passive line
					(at 0 -27.94 0)
					(length 3.81) hide
					(name "GND"
						(effects
							(font
								(size 1.27 1.27)
							)
						)
					)
					(number "159"
						(effects
							(font
								(size 1.27 1.27)
							)
						)
					)
				)
				(pin passive line
					(at 0 -27.94 0)
					(length 3.81) hide
					(name "GND"
						(effects
							(font
								(size 1.27 1.27)
							)
						)
					)
					(number "164"
						(effects
							(font
								(size 1.27 1.27)
							)
						)
					)
				)
				(pin passive line
					(at 0 -27.94 0)
					(length 3.81) hide
					(name "GND"
						(effects
							(font
								(size 1.27 1.27)
							)
						)
					)
					(number "165"
						(effects
							(font
								(size 1.27 1.27)
							)
						)
					)
				)
				(pin passive line
					(at 0 -27.94 0)
					(length 3.81) hide
					(name "GND"
						(effects
							(font
								(size 1.27 1.27)
							)
						)
					)
					(number "170"
						(effects
							(font
								(size 1.27 1.27)
							)
						)
					)
				)
				(pin passive line
					(at 0 -27.94 0)
					(length 3.81) hide
					(name "GND"
						(effects
							(font
								(size 1.27 1.27)
							)
						)
					)
					(number "171"
						(effects
							(font
								(size 1.27 1.27)
							)
						)
					)
				)
				(pin passive line
					(at 0 -27.94 0)
					(length 3.81) hide
					(name "GND"
						(effects
							(font
								(size 1.27 1.27)
							)
						)
					)
					(number "176"
						(effects
							(font
								(size 1.27 1.27)
							)
						)
					)
				)
				(pin passive line
					(at 0 -27.94 0)
					(length 3.81) hide
					(name "GND"
						(effects
							(font
								(size 1.27 1.27)
							)
						)
					)
					(number "177"
						(effects
							(font
								(size 1.27 1.27)
							)
						)
					)
				)
				(pin passive line
					(at 48.26 -20.32 180)
					(length 3.81)
					(name "~{MOD_SLEEP}"
						(effects
							(font
								(size 1.27 1.27)
							)
						)
					)
					(number "178"
						(effects
							(font
								(size 1.27 1.27)
							)
						)
					)
				)
				(pin passive line
					(at 0 -27.94 0)
					(length 3.81) hide
					(name "GND"
						(effects
							(font
								(size 1.27 1.27)
							)
						)
					)
					(number "19"
						(effects
							(font
								(size 1.27 1.27)
							)
						)
					)
				)
				(pin passive line
					(at 0 -27.94 0)
					(length 3.81) hide
					(name "GND"
						(effects
							(font
								(size 1.27 1.27)
							)
						)
					)
					(number "2"
						(effects
							(font
								(size 1.27 1.27)
							)
						)
					)
				)
				(pin passive line
					(at 0 -27.94 0)
					(length 3.81) hide
					(name "GND"
						(effects
							(font
								(size 1.27 1.27)
							)
						)
					)
					(number "20"
						(effects
							(font
								(size 1.27 1.27)
							)
						)
					)
				)
				(pin passive line
					(at 0 -27.94 0)
					(length 3.81) hide
					(name "GND"
						(effects
							(font
								(size 1.27 1.27)
							)
						)
					)
					(number "200"
						(effects
							(font
								(size 1.27 1.27)
							)
						)
					)
				)
				(pin passive line
					(at 0 -27.94 0)
					(length 3.81) hide
					(name "GND"
						(effects
							(font
								(size 1.27 1.27)
							)
						)
					)
					(number "201"
						(effects
							(font
								(size 1.27 1.27)
							)
						)
					)
				)
				(pin passive line
					(at 48.26 -1.27 180)
					(length 3.81)
					(name "Fan_Tach/GPIO08"
						(effects
							(font
								(size 1.27 1.27)
							)
						)
					)
					(number "208"
						(effects
							(font
								(size 1.27 1.27)
							)
						)
					)
					(alternate "GPIO08" passive line)
					(alternate "GPIO08(Fan_Tach)" passive line)
				)
				(pin passive line
					(at 48.26 -24.13 180)
					(length 3.81)
					(name "CLK_32K_OUT"
						(effects
							(font
								(size 1.27 1.27)
							)
						)
					)
					(number "210"
						(effects
							(font
								(size 1.27 1.27)
							)
						)
					)
				)
				(pin passive line
					(at 48.26 -27.94 180)
					(length 3.81)
					(name "~{FORCE_RECOVERY}"
						(effects
							(font
								(size 1.27 1.27)
							)
						)
					)
					(number "214"
						(effects
							(font
								(size 1.27 1.27)
							)
						)
					)
				)
				(pin passive line
					(at 48.26 2.54 180)
					(length 3.81)
					(name "GND(MODULE_ID)"
						(effects
							(font
								(size 1.27 1.27)
							)
						)
					)
					(number "217"
						(effects
							(font
								(size 1.27 1.27)
							)
						)
					)
				)
				(pin passive line
					(at 48.26 -3.81 180)
					(length 3.81)
					(name "GPIO14/PWM"
						(effects
							(font
								(size 1.27 1.27)
							)
						)
					)
					(number "230"
						(effects
							(font
								(size 1.27 1.27)
							)
						)
					)
					(alternate "GPIO14" passive line)
					(alternate "GPIO14(PWM)" passive line)
				)
				(pin passive line
					(at 0 -27.94 0)
					(length 3.81) hide
					(name "GND"
						(effects
							(font
								(size 1.27 1.27)
							)
						)
					)
					(number "231"
						(effects
							(font
								(size 1.27 1.27)
							)
						)
					)
				)
				(pin passive line
					(at 48.26 -8.89 180)
					(length 3.81)
					(name "~{SHUTDOWN_REQ}"
						(effects
							(font
								(size 1.27 1.27)
							)
						)
					)
					(number "233"
						(effects
							(font
								(size 1.27 1.27)
							)
						)
					)
				)
				(pin passive line
					(at 0 -6.35 0)
					(length 3.81)
					(name "PMIC_BBAT"
						(effects
							(font
								(size 1.27 1.27)
							)
						)
					)
					(number "235"
						(effects
							(font
								(size 1.27 1.27)
							)
						)
					)
				)
				(pin passive line
					(at 48.26 -11.43 180)
					(length 3.81)
					(name "POWER_EN"
						(effects
							(font
								(size 1.27 1.27)
							)
						)
					)
					(number "237"
						(effects
							(font
								(size 1.27 1.27)
							)
						)
					)
				)
				(pin passive line
					(at 48.26 -13.97 180)
					(length 3.81)
					(name "~{SYS_RESET}"
						(effects
							(font
								(size 1.27 1.27)
							)
						)
					)
					(number "239"
						(effects
							(font
								(size 1.27 1.27)
							)
						)
					)
				)
				(pin passive line
					(at 48.26 -17.78 180)
					(length 3.81)
					(name "SLEEP/~{WAKE}"
						(effects
							(font
								(size 1.27 1.27)
							)
						)
					)
					(number "240"
						(effects
							(font
								(size 1.27 1.27)
							)
						)
					)
				)
				(pin passive line
					(at 0 -27.94 0)
					(length 3.81) hide
					(name "GND"
						(effects
							(font
								(size 1.27 1.27)
							)
						)
					)
					(number "241"
						(effects
							(font
								(size 1.27 1.27)
							)
						)
					)
				)
				(pin passive line
					(at 0 -27.94 0)
					(length 3.81) hide
					(name "GND"
						(effects
							(font
								(size 1.27 1.27)
							)
						)
					)
					(number "242"
						(effects
							(font
								(size 1.27 1.27)
							)
						)
					)
				)
				(pin passive line
					(at 0 -27.94 0)
					(length 3.81) hide
					(name "GND"
						(effects
							(font
								(size 1.27 1.27)
							)
						)
					)
					(number "243"
						(effects
							(font
								(size 1.27 1.27)
							)
						)
					)
				)
				(pin passive line
					(at 0 -27.94 0)
					(length 3.81) hide
					(name "GND"
						(effects
							(font
								(size 1.27 1.27)
							)
						)
					)
					(number "244"
						(effects
							(font
								(size 1.27 1.27)
							)
						)
					)
				)
				(pin passive line
					(at 0 -27.94 0)
					(length 3.81) hide
					(name "GND"
						(effects
							(font
								(size 1.27 1.27)
							)
						)
					)
					(number "245"
						(effects
							(font
								(size 1.27 1.27)
							)
						)
					)
				)
				(pin passive line
					(at 0 -27.94 0)
					(length 3.81) hide
					(name "GND"
						(effects
							(font
								(size 1.27 1.27)
							)
						)
					)
					(number "246"
						(effects
							(font
								(size 1.27 1.27)
							)
						)
					)
				)
				(pin passive line
					(at 0 -27.94 0)
					(length 3.81) hide
					(name "GND"
						(effects
							(font
								(size 1.27 1.27)
							)
						)
					)
					(number "247"
						(effects
							(font
								(size 1.27 1.27)
							)
						)
					)
				)
				(pin passive line
					(at 0 -27.94 0)
					(length 3.81) hide
					(name "GND"
						(effects
							(font
								(size 1.27 1.27)
							)
						)
					)
					(number "248"
						(effects
							(font
								(size 1.27 1.27)
							)
						)
					)
				)
				(pin passive line
					(at 0 -27.94 0)
					(length 3.81) hide
					(name "GND"
						(effects
							(font
								(size 1.27 1.27)
							)
						)
					)
					(number "249"
						(effects
							(font
								(size 1.27 1.27)
							)
						)
					)
				)
				(pin passive line
					(at 0 -27.94 0)
					(length 3.81) hide
					(name "GND"
						(effects
							(font
								(size 1.27 1.27)
							)
						)
					)
					(number "25"
						(effects
							(font
								(size 1.27 1.27)
							)
						)
					)
				)
				(pin passive line
					(at 0 -27.94 0)
					(length 3.81) hide
					(name "GND"
						(effects
							(font
								(size 1.27 1.27)
							)
						)
					)
					(number "250"
						(effects
							(font
								(size 1.27 1.27)
							)
						)
					)
				)
				(pin passive line
					(at 0 0 0)
					(length 3.81)
					(name "VDD_IN"
						(effects
							(font
								(size 1.27 1.27)
							)
						)
					)
					(number "251"
						(effects
							(font
								(size 1.27 1.27)
							)
						)
					)
				)
				(pin passive line
					(at 0 0 0)
					(length 3.81) hide
					(name "VDD_IN"
						(effects
							(font
								(size 1.27 1.27)
							)
						)
					)
					(number "252"
						(effects
							(font
								(size 1.27 1.27)
							)
						)
					)
				)
				(pin passive line
					(at 0 0 0)
					(length 3.81) hide
					(name "VDD_IN"
						(effects
							(font
								(size 1.27 1.27)
							)
						)
					)
					(number "253"
						(effects
							(font
								(size 1.27 1.27)
							)
						)
					)
				)
				(pin passive line
					(at 0 0 0)
					(length 3.81) hide
					(name "VDD_IN"
						(effects
							(font
								(size 1.27 1.27)
							)
						)
					)
					(number "254"
						(effects
							(font
								(size 1.27 1.27)
							)
						)
					)
				)
				(pin passive line
					(at 0 0 0)
					(length 3.81) hide
					(name "VDD_IN"
						(effects
							(font
								(size 1.27 1.27)
							)
						)
					)
					(number "255"
						(effects
							(font
								(size 1.27 1.27)
							)
						)
					)
				)
				(pin passive line
					(at 0 0 0)
					(length 3.81) hide
					(name "VDD_IN"
						(effects
							(font
								(size 1.27 1.27)
							)
						)
					)
					(number "256"
						(effects
							(font
								(size 1.27 1.27)
							)
						)
					)
				)
				(pin passive line
					(at 0 0 0)
					(length 3.81) hide
					(name "VDD_IN"
						(effects
							(font
								(size 1.27 1.27)
							)
						)
					)
					(number "257"
						(effects
							(font
								(size 1.27 1.27)
							)
						)
					)
				)
				(pin passive line
					(at 0 0 0)
					(length 3.81) hide
					(name "VDD_IN"
						(effects
							(font
								(size 1.27 1.27)
							)
						)
					)
					(number "258"
						(effects
							(font
								(size 1.27 1.27)
							)
						)
					)
				)
				(pin passive line
					(at 0 0 0)
					(length 3.81) hide
					(name "VDD_IN"
						(effects
							(font
								(size 1.27 1.27)
							)
						)
					)
					(number "259"
						(effects
							(font
								(size 1.27 1.27)
							)
						)
					)
				)
				(pin passive line
					(at 0 -27.94 0)
					(length 3.81) hide
					(name "GND"
						(effects
							(font
								(size 1.27 1.27)
							)
						)
					)
					(number "26"
						(effects
							(font
								(size 1.27 1.27)
							)
						)
					)
				)
				(pin passive line
					(at 0 0 0)
					(length 3.81) hide
					(name "VDD_IN"
						(effects
							(font
								(size 1.27 1.27)
							)
						)
					)
					(number "260"
						(effects
							(font
								(size 1.27 1.27)
							)
						)
					)
				)
				(pin passive line
					(at 0 -20.32 0)
					(length 3.81)
					(name "MP"
						(effects
							(font
								(size 1.27 1.27)
							)
						)
					)
					(number "261"
						(effects
							(font
								(size 1.27 1.27)
							)
						)
					)
				)
				(pin passive line
					(at 0 -22.86 0)
					(length 3.81)
					(name "MP"
						(effects
							(font
								(size 1.27 1.27)
							)
						)
					)
					(number "262"
						(effects
							(font
								(size 1.27 1.27)
							)
						)
					)
				)
				(pin passive line
					(at 0 -27.94 0)
					(length 3.81) hide
					(name "GND"
						(effects
							(font
								(size 1.27 1.27)
							)
						)
					)
					(number "31"
						(effects
							(font
								(size 1.27 1.27)
							)
						)
					)
				)
				(pin passive line
					(at 0 -27.94 0)
					(length 3.81) hide
					(name "GND"
						(effects
							(font
								(size 1.27 1.27)
							)
						)
					)
					(number "32"
						(effects
							(font
								(size 1.27 1.27)
							)
						)
					)
				)
				(pin passive line
					(at 0 -27.94 0)
					(length 3.81) hide
					(name "GND"
						(effects
							(font
								(size 1.27 1.27)
							)
						)
					)
					(number "37"
						(effects
							(font
								(size 1.27 1.27)
							)
						)
					)
				)
				(pin passive line
					(at 0 -27.94 0)
					(length 3.81) hide
					(name "GND"
						(effects
							(font
								(size 1.27 1.27)
							)
						)
					)
					(number "38"
						(effects
							(font
								(size 1.27 1.27)
							)
						)
					)
				)
				(pin passive line
					(at 0 -27.94 0)
					(length 3.81) hide
					(name "GND"
						(effects
							(font
								(size 1.27 1.27)
							)
						)
					)
					(number "43"
						(effects
							(font
								(size 1.27 1.27)
							)
						)
					)
				)
				(pin passive line
					(at 0 -27.94 0)
					(length 3.81) hide
					(name "GND"
						(effects
							(font
								(size 1.27 1.27)
							)
						)
					)
					(number "44"
						(effects
							(font
								(size 1.27 1.27)
							)
						)
					)
				)
				(pin passive line
					(at 0 -27.94 0)
					(length 3.81) hide
					(name "GND"
						(effects
							(font
								(size 1.27 1.27)
							)
						)
					)
					(number "49"
						(effects
							(font
								(size 1.27 1.27)
							)
						)
					)
				)
				(pin passive line
					(at 0 -27.94 0)
					(length 3.81) hide
					(name "GND"
						(effects
							(font
								(size 1.27 1.27)
							)
						)
					)
					(number "50"
						(effects
							(font
								(size 1.27 1.27)
							)
						)
					)
				)
				(pin passive line
					(at 0 -27.94 0)
					(length 3.81) hide
					(name "GND"
						(effects
							(font
								(size 1.27 1.27)
							)
						)
					)
					(number "55"
						(effects
							(font
								(size 1.27 1.27)
							)
						)
					)
				)
				(pin passive line
					(at 0 -27.94 0)
					(length 3.81) hide
					(name "GND"
						(effects
							(font
								(size 1.27 1.27)
							)
						)
					)
					(number "56"
						(effects
							(font
								(size 1.27 1.27)
							)
						)
					)
				)
				(pin passive line
					(at 0 -27.94 0)
					(length 3.81) hide
					(name "GND"
						(effects
							(font
								(size 1.27 1.27)
							)
						)
					)
					(number "61"
						(effects
							(font
								(size 1.27 1.27)
							)
						)
					)
				)
				(pin passive line
					(at 0 -27.94 0)
					(length 3.81) hide
					(name "GND"
						(effects
							(font
								(size 1.27 1.27)
							)
						)
					)
					(number "62"
						(effects
							(font
								(size 1.27 1.27)
							)
						)
					)
				)
				(pin passive line
					(at 0 -27.94 0)
					(length 3.81) hide
					(name "GND"
						(effects
							(font
								(size 1.27 1.27)
							)
						)
					)
					(number "67"
						(effects
							(font
								(size 1.27 1.27)
							)
						)
					)
				)
				(pin passive line
					(at 0 -27.94 0)
					(length 3.81) hide
					(name "GND"
						(effects
							(font
								(size 1.27 1.27)
							)
						)
					)
					(number "68"
						(effects
							(font
								(size 1.27 1.27)
							)
						)
					)
				)
				(pin passive line
					(at 0 -27.94 0)
					(length 3.81) hide
					(name "GND"
						(effects
							(font
								(size 1.27 1.27)
							)
						)
					)
					(number "7"
						(effects
							(font
								(size 1.27 1.27)
							)
						)
					)
				)
				(pin passive line
					(at 0 -27.94 0)
					(length 3.81) hide
					(name "GND"
						(effects
							(font
								(size 1.27 1.27)
							)
						)
					)
					(number "73"
						(effects
							(font
								(size 1.27 1.27)
							)
						)
					)
				)
				(pin passive line
					(at 0 -27.94 0)
					(length 3.81) hide
					(name "GND"
						(effects
							(font
								(size 1.27 1.27)
							)
						)
					)
					(number "74"
						(effects
							(font
								(size 1.27 1.27)
							)
						)
					)
				)
				(pin passive line
					(at 0 -27.94 0)
					(length 3.81) hide
					(name "GND"
						(effects
							(font
								(size 1.27 1.27)
							)
						)
					)
					(number "79"
						(effects
							(font
								(size 1.27 1.27)
							)
						)
					)
				)
				(pin passive line
					(at 0 -27.94 0)
					(length 3.81) hide
					(name "GND"
						(effects
							(font
								(size 1.27 1.27)
							)
						)
					)
					(number "8"
						(effects
							(font
								(size 1.27 1.27)
							)
						)
					)
				)
				(pin passive line
					(at 0 -27.94 0)
					(length 3.81) hide
					(name "GND"
						(effects
							(font
								(size 1.27 1.27)
							)
						)
					)
					(number "80"
						(effects
							(font
								(size 1.27 1.27)
							)
						)
					)
				)
				(pin passive line
					(at 0 -27.94 0)
					(length 3.81) hide
					(name "GND"
						(effects
							(font
								(size 1.27 1.27)
							)
						)
					)
					(number "85"
						(effects
							(font
								(size 1.27 1.27)
							)
						)
					)
				)
				(pin passive line
					(at 0 -27.94 0)
					(length 3.81) hide
					(name "GND"
						(effects
							(font
								(size 1.27 1.27)
							)
						)
					)
					(number "86"
						(effects
							(font
								(size 1.27 1.27)
							)
						)
					)
				)
			)
			(symbol "Bus_DDR4_SODIMM_CUSTOM_Jetson-Orin-H9.2mm-socket_2_1"
				(polyline
					(pts
						(xy 3.81 -88.9) (xy 35.56 -88.9)
					)
					(stroke
						(width 0.254)
						(type default)
					)
					(fill
						(type background)
					)
				)
				(polyline
					(pts
						(xy 18.415 -83.185) (xy 18.415 -86.995)
					)
					(stroke
						(width 0.254)
						(type default)
					)
					(fill
						(type background)
					)
				)
				(polyline
					(pts
						(xy 18.415 -70.485) (xy 18.415 -79.375)
					)
					(stroke
						(width 0.254)
						(type default)
					)
					(fill
						(type background)
					)
				)
				(polyline
					(pts
						(xy 18.415 0.635) (xy 18.415 -66.675)
					)
					(stroke
						(width 0.254)
						(type default)
					)
					(fill
						(type background)
					)
				)
				(rectangle
					(start 3.81 2.54)
					(end 35.56 -106.68)
					(stroke
						(width 0.254)
						(type default)
					)
					(fill
						(type background)
					)
				)
				(arc
					(start 17.78 -87.63)
					(mid 18.2298 -87.4448)
					(end 18.415 -86.995)
					(stroke
						(width 0.254)
						(type default)
					)
					(fill
						(type background)
					)
				)
				(arc
					(start 17.78 -80.01)
					(mid 18.2298 -79.8248)
					(end 18.415 -79.375)
					(stroke
						(width 0.254)
						(type default)
					)
					(fill
						(type background)
					)
				)
				(arc
					(start 17.78 -67.31)
					(mid 18.2298 -67.1248)
					(end 18.415 -66.675)
					(stroke
						(width 0.254)
						(type default)
					)
					(fill
						(type background)
					)
				)
				(arc
					(start 18.415 -83.185)
					(mid 18.229 -82.736)
					(end 17.78 -82.55)
					(stroke
						(width 0.254)
						(type default)
					)
					(fill
						(type background)
					)
				)
				(arc
					(start 18.415 -70.485)
					(mid 18.229 -70.036)
					(end 17.78 -69.85)
					(stroke
						(width 0.254)
						(type default)
					)
					(fill
						(type background)
					)
				)
				(arc
					(start 18.415 0.635)
					(mid 18.229 1.084)
					(end 17.78 1.27)
					(stroke
						(width 0.254)
						(type default)
					)
					(fill
						(type background)
					)
				)
				(text "1.8V Bidir"
					(at 19.05 -76.2 0)
					(effects
						(font
							(size 1.27 1.27)
							(thickness 0.15)
						)
						(justify left bottom)
					)
				)
				(text "3.3V PU Bidir"
					(at 19.05 -86.36 0)
					(effects
						(font
							(size 1.27 1.27)
							(thickness 0.15)
						)
						(justify left bottom)
					)
				)
				(text "MIPI Input"
					(at 19.05 -33.02 0)
					(effects
						(font
							(size 1.27 1.27)
							(thickness 0.15)
						)
						(justify left bottom)
					)
				)
				(text "RSVD"
					(at 29.21 -91.44 0)
					(effects
						(font
							(size 1.27 1.27)
							(thickness 0.15)
						)
						(justify left bottom)
					)
				)
				(pin passive line
					(at 0 -2.54 0)
					(length 3.81)
					(name "CSI0_CLK_N"
						(effects
							(font
								(size 1.27 1.27)
							)
						)
					)
					(number "10"
						(effects
							(font
								(size 1.27 1.27)
							)
						)
					)
				)
				(pin passive line
					(at 0 -17.78 0)
					(length 3.81)
					(name "CSI1_CLK_P"
						(effects
							(font
								(size 1.27 1.27)
							)
						)
					)
					(number "11"
						(effects
							(font
								(size 1.27 1.27)
							)
						)
					)
				)
				(pin passive line
					(at 0 -78.74 0)
					(length 3.81)
					(name "CAM0_PWDN"
						(effects
							(font
								(size 1.27 1.27)
							)
						)
					)
					(number "114"
						(effects
							(font
								(size 1.27 1.27)
							)
						)
					)
				)
				(pin passive line
					(at 0 -76.2 0)
					(length 3.81)
					(name "CAM0_MCLK"
						(effects
							(font
								(size 1.27 1.27)
							)
						)
					)
					(number "116"
						(effects
							(font
								(size 1.27 1.27)
							)
						)
					)
				)
				(pin passive line
					(at 0 0 0)
					(length 3.81)
					(name "CSI0_CLK_P"
						(effects
							(font
								(size 1.27 1.27)
							)
						)
					)
					(number "12"
						(effects
							(font
								(size 1.27 1.27)
							)
						)
					)
				)
				(pin passive line
					(at 0 -73.66 0)
					(length 3.81)
					(name "CAM1_PWDN"
						(effects
							(font
								(size 1.27 1.27)
							)
						)
					)
					(number "120"
						(effects
							(font
								(size 1.27 1.27)
							)
						)
					)
				)
				(pin passive line
					(at 0 -71.12 0)
					(length 3.81)
					(name "CAM1_MCLK"
						(effects
							(font
								(size 1.27 1.27)
							)
						)
					)
					(number "122"
						(effects
							(font
								(size 1.27 1.27)
							)
						)
					)
				)
				(pin passive line
					(at 0 -30.48 0)
					(length 3.81)
					(name "CSI1_D1_N"
						(effects
							(font
								(size 1.27 1.27)
							)
						)
					)
					(number "15"
						(effects
							(font
								(size 1.27 1.27)
							)
						)
					)
				)
				(pin passive line
					(at 0 -12.7 0)
					(length 3.81)
					(name "CSI0_D1_N"
						(effects
							(font
								(size 1.27 1.27)
							)
						)
					)
					(number "16"
						(effects
							(font
								(size 1.27 1.27)
							)
						)
					)
				)
				(pin passive line
					(at 0 -27.94 0)
					(length 3.81)
					(name "CSI1_D1_P"
						(effects
							(font
								(size 1.27 1.27)
							)
						)
					)
					(number "17"
						(effects
							(font
								(size 1.27 1.27)
							)
						)
					)
				)
				(pin passive line
					(at 0 -10.16 0)
					(length 3.81)
					(name "CSI0_D1_P"
						(effects
							(font
								(size 1.27 1.27)
							)
						)
					)
					(number "18"
						(effects
							(font
								(size 1.27 1.27)
							)
						)
					)
				)
				(pin passive line
					(at 0 -59.69 0)
					(length 3.81)
					(name "CSI3_D0_N"
						(effects
							(font
								(size 1.27 1.27)
							)
						)
					)
					(number "21"
						(effects
							(font
								(size 1.27 1.27)
							)
						)
					)
				)
				(pin passive line
					(at 0 -83.82 0)
					(length 3.81)
					(name "CAM_I2C_SCL"
						(effects
							(font
								(size 1.27 1.27)
							)
						)
					)
					(number "213"
						(effects
							(font
								(size 1.27 1.27)
							)
						)
					)
				)
				(pin passive line
					(at 0 -86.36 0)
					(length 3.81)
					(name "CAM_I2C_SDA"
						(effects
							(font
								(size 1.27 1.27)
							)
						)
					)
					(number "215"
						(effects
							(font
								(size 1.27 1.27)
							)
						)
					)
				)
				(pin passive line
					(at 0 -43.18 0)
					(length 3.81)
					(name "CSI2_D0_N"
						(effects
							(font
								(size 1.27 1.27)
							)
						)
					)
					(number "22"
						(effects
							(font
								(size 1.27 1.27)
							)
						)
					)
				)
				(pin passive line
					(at 0 -57.15 0)
					(length 3.81)
					(name "CSI3_D0_P"
						(effects
							(font
								(size 1.27 1.27)
							)
						)
					)
					(number "23"
						(effects
							(font
								(size 1.27 1.27)
							)
						)
					)
				)
				(pin passive line
					(at 0 -40.64 0)
					(length 3.81)
					(name "CSI2_D0_P"
						(effects
							(font
								(size 1.27 1.27)
							)
						)
					)
					(number "24"
						(effects
							(font
								(size 1.27 1.27)
							)
						)
					)
				)
				(pin passive line
					(at 0 -54.61 0)
					(length 3.81)
					(name "CSI3_CLK_N"
						(effects
							(font
								(size 1.27 1.27)
							)
						)
					)
					(number "27"
						(effects
							(font
								(size 1.27 1.27)
							)
						)
					)
				)
				(pin passive line
					(at 0 -38.1 0)
					(length 3.81)
					(name "CSI2_CLK_N"
						(effects
							(font
								(size 1.27 1.27)
							)
						)
					)
					(number "28"
						(effects
							(font
								(size 1.27 1.27)
							)
						)
					)
				)
				(pin passive line
					(at 0 -52.07 0)
					(length 3.81)
					(name "CSI3_CLK_P"
						(effects
							(font
								(size 1.27 1.27)
							)
						)
					)
					(number "29"
						(effects
							(font
								(size 1.27 1.27)
							)
						)
					)
				)
				(pin passive line
					(at 0 -25.4 0)
					(length 3.81)
					(name "CSI1_D0_N"
						(effects
							(font
								(size 1.27 1.27)
							)
						)
					)
					(number "3"
						(effects
							(font
								(size 1.27 1.27)
							)
						)
					)
				)
				(pin passive line
					(at 0 -35.56 0)
					(length 3.81)
					(name "CSI2_CLK_P"
						(effects
							(font
								(size 1.27 1.27)
							)
						)
					)
					(number "30"
						(effects
							(font
								(size 1.27 1.27)
							)
						)
					)
				)
				(pin passive line
					(at 0 -64.77 0)
					(length 3.81)
					(name "CSI3_D1_N"
						(effects
							(font
								(size 1.27 1.27)
							)
						)
					)
					(number "33"
						(effects
							(font
								(size 1.27 1.27)
							)
						)
					)
				)
				(pin passive line
					(at 0 -48.26 0)
					(length 3.81)
					(name "CSI2_D1_N"
						(effects
							(font
								(size 1.27 1.27)
							)
						)
					)
					(number "34"
						(effects
							(font
								(size 1.27 1.27)
							)
						)
					)
				)
				(pin passive line
					(at 0 -62.23 0)
					(length 3.81)
					(name "CSI3_D1_P"
						(effects
							(font
								(size 1.27 1.27)
							)
						)
					)
					(number "35"
						(effects
							(font
								(size 1.27 1.27)
							)
						)
					)
				)
				(pin passive line
					(at 0 -45.72 0)
					(length 3.81)
					(name "CSI2_D1_P"
						(effects
							(font
								(size 1.27 1.27)
							)
						)
					)
					(number "36"
						(effects
							(font
								(size 1.27 1.27)
							)
						)
					)
				)
				(pin passive line
					(at 0 -7.62 0)
					(length 3.81)
					(name "CSI0_D0_N"
						(effects
							(font
								(size 1.27 1.27)
							)
						)
					)
					(number "4"
						(effects
							(font
								(size 1.27 1.27)
							)
						)
					)
				)
				(pin passive line
					(at 0 -22.86 0)
					(length 3.81)
					(name "CSI1_D0_P"
						(effects
							(font
								(size 1.27 1.27)
							)
						)
					)
					(number "5"
						(effects
							(font
								(size 1.27 1.27)
							)
						)
					)
				)
				(pin passive line
					(at 0 -5.08 0)
					(length 3.81)
					(name "CSI0_D0_P"
						(effects
							(font
								(size 1.27 1.27)
							)
						)
					)
					(number "6"
						(effects
							(font
								(size 1.27 1.27)
							)
						)
					)
				)
				(pin passive line
					(at 0 -93.98 0)
					(length 3.81)
					(name "DSI_D0_N"
						(effects
							(font
								(size 1.27 1.27)
							)
						)
					)
					(number "70"
						(effects
							(font
								(size 1.27 1.27)
							)
						)
					)
				)
				(pin passive line
					(at 0 -91.44 0)
					(length 3.81)
					(name "DSI_D0_P"
						(effects
							(font
								(size 1.27 1.27)
							)
						)
					)
					(number "72"
						(effects
							(font
								(size 1.27 1.27)
							)
						)
					)
				)
				(pin passive line
					(at 0 -99.06 0)
					(length 3.81)
					(name "DSI_CLK_N"
						(effects
							(font
								(size 1.27 1.27)
							)
						)
					)
					(number "76"
						(effects
							(font
								(size 1.27 1.27)
							)
						)
					)
				)
				(pin passive line
					(at 0 -96.52 0)
					(length 3.81)
					(name "DSI_CLK_P"
						(effects
							(font
								(size 1.27 1.27)
							)
						)
					)
					(number "78"
						(effects
							(font
								(size 1.27 1.27)
							)
						)
					)
				)
				(pin passive line
					(at 0 -104.14 0)
					(length 3.81)
					(name "DSI_D1_N"
						(effects
							(font
								(size 1.27 1.27)
							)
						)
					)
					(number "82"
						(effects
							(font
								(size 1.27 1.27)
							)
						)
					)
				)
				(pin passive line
					(at 0 -101.6 0)
					(length 3.81)
					(name "DSI_D1_P"
						(effects
							(font
								(size 1.27 1.27)
							)
						)
					)
					(number "84"
						(effects
							(font
								(size 1.27 1.27)
							)
						)
					)
				)
				(pin passive line
					(at 0 -20.32 0)
					(length 3.81)
					(name "CSI1_CLK_N"
						(effects
							(font
								(size 1.27 1.27)
							)
						)
					)
					(number "9"
						(effects
							(font
								(size 1.27 1.27)
							)
						)
					)
				)
			)
			(symbol "Bus_DDR4_SODIMM_CUSTOM_Jetson-Orin-H9.2mm-socket_3_1"
				(polyline
					(pts
						(xy 17.145 -111.12) (xy 17.145 -114.93)
					)
					(stroke
						(width 0.254)
						(type default)
					)
					(fill
						(type background)
					)
				)
				(polyline
					(pts
						(xy 17.145 -98.425) (xy 17.145 -107.315)
					)
					(stroke
						(width 0.254)
						(type default)
					)
					(fill
						(type background)
					)
				)
				(polyline
					(pts
						(xy 17.145 -85.725) (xy 17.145 -94.615)
					)
					(stroke
						(width 0.254)
						(type default)
					)
					(fill
						(type background)
					)
				)
				(polyline
					(pts
						(xy 17.145 -70.485) (xy 17.145 -81.92)
					)
					(stroke
						(width 0.254)
						(type default)
					)
					(fill
						(type background)
					)
				)
				(polyline
					(pts
						(xy 17.145 -55.24) (xy 17.145 -66.675)
					)
					(stroke
						(width 0.254)
						(type default)
					)
					(fill
						(type background)
					)
				)
				(polyline
					(pts
						(xy 17.145 -47.62) (xy 17.145 -51.43)
					)
					(stroke
						(width 0.254)
						(type default)
					)
					(fill
						(type background)
					)
				)
				(polyline
					(pts
						(xy 17.145 -40.005) (xy 17.145 -43.815)
					)
					(stroke
						(width 0.254)
						(type default)
					)
					(fill
						(type background)
					)
				)
				(polyline
					(pts
						(xy 17.145 -32.38) (xy 17.145 -36.19)
					)
					(stroke
						(width 0.254)
						(type default)
					)
					(fill
						(type background)
					)
				)
				(polyline
					(pts
						(xy 17.145 -24.765) (xy 17.145 -28.575)
					)
					(stroke
						(width 0.254)
						(type default)
					)
					(fill
						(type background)
					)
				)
				(polyline
					(pts
						(xy 17.145 -12.065) (xy 17.145 -20.955)
					)
					(stroke
						(width 0.254)
						(type default)
					)
					(fill
						(type background)
					)
				)
				(polyline
					(pts
						(xy 17.145 0.64) (xy 17.145 -8.25)
					)
					(stroke
						(width 0.254)
						(type default)
					)
					(fill
						(type background)
					)
				)
				(rectangle
					(start 3.81 3.81)
					(end 35.56 -116.84)
					(stroke
						(width 0.254)
						(type default)
					)
					(fill
						(type background)
					)
				)
				(arc
					(start 16.51 -115.57)
					(mid 16.9598 -115.3848)
					(end 17.145 -114.935)
					(stroke
						(width 0.254)
						(type default)
					)
					(fill
						(type background)
					)
				)
				(arc
					(start 16.51 -107.95)
					(mid 16.9598 -107.7648)
					(end 17.145 -107.315)
					(stroke
						(width 0.254)
						(type default)
					)
					(fill
						(type background)
					)
				)
				(arc
					(start 16.51 -95.25)
					(mid 16.9598 -95.0648)
					(end 17.145 -94.615)
					(stroke
						(width 0.254)
						(type default)
					)
					(fill
						(type background)
					)
				)
				(arc
					(start 16.51 -82.55)
					(mid 16.9598 -82.3648)
					(end 17.145 -81.915)
					(stroke
						(width 0.254)
						(type default)
					)
					(fill
						(type background)
					)
				)
				(arc
					(start 16.51 -67.305)
					(mid 16.959 -67.119)
					(end 17.145 -66.67)
					(stroke
						(width 0.254)
						(type default)
					)
					(fill
						(type background)
					)
				)
				(arc
					(start 16.51 -52.065)
					(mid 16.959 -51.879)
					(end 17.145 -51.43)
					(stroke
						(width 0.254)
						(type default)
					)
					(fill
						(type background)
					)
				)
				(arc
					(start 16.51 -44.45)
					(mid 16.9598 -44.2648)
					(end 17.145 -43.815)
					(stroke
						(width 0.254)
						(type default)
					)
					(fill
						(type background)
					)
				)
				(arc
					(start 16.51 -36.825)
					(mid 16.959 -36.639)
					(end 17.145 -36.19)
					(stroke
						(width 0.254)
						(type default)
					)
					(fill
						(type background)
					)
				)
				(arc
					(start 16.51 -29.21)
					(mid 16.9598 -29.0248)
					(end 17.145 -28.575)
					(stroke
						(width 0.254)
						(type default)
					)
					(fill
						(type background)
					)
				)
				(arc
					(start 16.51 -21.59)
					(mid 16.9598 -21.4048)
					(end 17.145 -20.955)
					(stroke
						(width 0.254)
						(type default)
					)
					(fill
						(type background)
					)
				)
				(arc
					(start 16.51 -8.885)
					(mid 16.959 -8.699)
					(end 17.145 -8.25)
					(stroke
						(width 0.254)
						(type default)
					)
					(fill
						(type background)
					)
				)
				(arc
					(start 17.145 -111.12)
					(mid 16.959 -110.671)
					(end 16.51 -110.485)
					(stroke
						(width 0.254)
						(type default)
					)
					(fill
						(type background)
					)
				)
				(arc
					(start 17.145 -98.425)
					(mid 16.959 -97.976)
					(end 16.51 -97.79)
					(stroke
						(width 0.254)
						(type default)
					)
					(fill
						(type background)
					)
				)
				(arc
					(start 17.145 -85.725)
					(mid 16.959 -85.276)
					(end 16.51 -85.09)
					(stroke
						(width 0.254)
						(type default)
					)
					(fill
						(type background)
					)
				)
				(arc
					(start 17.145 -70.485)
					(mid 16.959 -70.036)
					(end 16.51 -69.85)
					(stroke
						(width 0.254)
						(type default)
					)
					(fill
						(type background)
					)
				)
				(arc
					(start 17.145 -55.24)
					(mid 16.959 -54.791)
					(end 16.51 -54.605)
					(stroke
						(width 0.254)
						(type default)
					)
					(fill
						(type background)
					)
				)
				(arc
					(start 17.145 -47.62)
					(mid 16.959 -47.171)
					(end 16.51 -46.985)
					(stroke
						(width 0.254)
						(type default)
					)
					(fill
						(type background)
					)
				)
				(arc
					(start 17.145 -40.005)
					(mid 16.959 -39.556)
					(end 16.51 -39.37)
					(stroke
						(width 0.254)
						(type default)
					)
					(fill
						(type background)
					)
				)
				(arc
					(start 17.145 -32.38)
					(mid 16.959 -31.931)
					(end 16.51 -31.745)
					(stroke
						(width 0.254)
						(type default)
					)
					(fill
						(type background)
					)
				)
				(arc
					(start 17.145 -24.765)
					(mid 16.959 -24.316)
					(end 16.51 -24.13)
					(stroke
						(width 0.254)
						(type default)
					)
					(fill
						(type background)
					)
				)
				(arc
					(start 17.145 -12.065)
					(mid 16.959 -11.616)
					(end 16.51 -11.43)
					(stroke
						(width 0.254)
						(type default)
					)
					(fill
						(type background)
					)
				)
				(arc
					(start 17.145 0.64)
					(mid 16.959 1.089)
					(end 16.51 1.275)
					(stroke
						(width 0.254)
						(type default)
					)
					(fill
						(type background)
					)
				)
				(text "1.8V CMOS"
					(at 17.78 -104.14 0)
					(effects
						(font
							(size 1.27 1.27)
							(thickness 0.15)
						)
						(justify left bottom)
					)
				)
				(text "1.8V CMOS"
					(at 17.78 -91.44 0)
					(effects
						(font
							(size 1.27 1.27)
							(thickness 0.15)
						)
						(justify left bottom)
					)
				)
				(text "1.8V CMOS"
					(at 17.78 -76.2 0)
					(effects
						(font
							(size 1.27 1.27)
							(thickness 0.15)
						)
						(justify left bottom)
					)
				)
				(text "1.8V CMOS"
					(at 17.78 -60.96 0)
					(effects
						(font
							(size 1.27 1.27)
							(thickness 0.15)
						)
						(justify left bottom)
					)
				)
				(text "1.8V CMOS"
					(at 17.78 -27.94 0)
					(effects
						(font
							(size 1.27 1.27)
							(thickness 0.15)
						)
						(justify left bottom)
					)
				)
				(text "1.8V CMOS"
					(at 17.78 -17.78 0)
					(effects
						(font
							(size 1.27 1.27)
							(thickness 0.15)
						)
						(justify left bottom)
					)
				)
				(text "1.8V CMOS"
					(at 17.78 -5.08 0)
					(effects
						(font
							(size 1.27 1.27)
							(thickness 0.15)
						)
						(justify left bottom)
					)
				)
				(text "1.8V PU Bidir"
					(at 17.78 -50.8 0)
					(effects
						(font
							(size 1.27 1.27)
							(thickness 0.15)
						)
						(justify left bottom)
					)
				)
				(text "3.3V CMOS"
					(at 17.78 -114.3 0)
					(effects
						(font
							(size 1.27 1.27)
							(thickness 0.15)
						)
						(justify left bottom)
					)
				)
				(text "3.3V PU Bidir"
					(at 17.78 -43.18 0)
					(effects
						(font
							(size 1.27 1.27)
							(thickness 0.15)
						)
						(justify left bottom)
					)
				)
				(text "3.3V PU Bidir"
					(at 17.78 -35.56 0)
					(effects
						(font
							(size 1.27 1.27)
							(thickness 0.15)
						)
						(justify left bottom)
					)
				)
				(pin passive line
					(at 0 -7.62 0)
					(length 3.81)
					(name "UART0_RXD"
						(effects
							(font
								(size 1.27 1.27)
							)
						)
					)
					(number "101"
						(effects
							(font
								(size 1.27 1.27)
							)
						)
					)
				)
				(pin passive line
					(at 0 0 0)
					(length 3.81)
					(name "~{UART0_RTS}"
						(effects
							(font
								(size 1.27 1.27)
							)
						)
					)
					(number "103"
						(effects
							(font
								(size 1.27 1.27)
							)
						)
					)
				)
				(pin passive line
					(at 0 -73.66 0)
					(length 3.81)
					(name "SPI1_MOSI"
						(effects
							(font
								(size 1.27 1.27)
							)
						)
					)
					(number "104"
						(effects
							(font
								(size 1.27 1.27)
							)
						)
					)
				)
				(pin passive line
					(at 0 -2.54 0)
					(length 3.81)
					(name "~{UART0_CTS}"
						(effects
							(font
								(size 1.27 1.27)
							)
						)
					)
					(number "105"
						(effects
							(font
								(size 1.27 1.27)
							)
						)
					)
				)
				(pin passive line
					(at 0 -71.12 0)
					(length 3.81)
					(name "SPI1_SCK"
						(effects
							(font
								(size 1.27 1.27)
							)
						)
					)
					(number "106"
						(effects
							(font
								(size 1.27 1.27)
							)
						)
					)
				)
				(pin passive line
					(at 0 -76.2 0)
					(length 3.81)
					(name "SPI1_MISO"
						(effects
							(font
								(size 1.27 1.27)
							)
						)
					)
					(number "108"
						(effects
							(font
								(size 1.27 1.27)
							)
						)
					)
				)
				(pin passive line
					(at 0 -78.74 0)
					(length 3.81)
					(name "~{SPI1_CS0}"
						(effects
							(font
								(size 1.27 1.27)
							)
						)
					)
					(number "110"
						(effects
							(font
								(size 1.27 1.27)
							)
						)
					)
				)
				(pin passive line
					(at 0 -81.28 0)
					(length 3.81)
					(name "~{SPI1_CS1}"
						(effects
							(font
								(size 1.27 1.27)
							)
						)
					)
					(number "112"
						(effects
							(font
								(size 1.27 1.27)
							)
						)
					)
				)
				(pin passive line
					(at 0 -111.76 0)
					(length 3.81)
					(name "CAN_RX"
						(effects
							(font
								(size 1.27 1.27)
							)
						)
					)
					(number "143"
						(effects
							(font
								(size 1.27 1.27)
							)
						)
					)
				)
				(pin passive line
					(at 0 -114.3 0)
					(length 3.81)
					(name "CAN_TX"
						(effects
							(font
								(size 1.27 1.27)
							)
						)
					)
					(number "145"
						(effects
							(font
								(size 1.27 1.27)
							)
						)
					)
				)
				(pin passive line
					(at 0 -33.02 0)
					(length 3.81)
					(name "I2C0_SCL"
						(effects
							(font
								(size 1.27 1.27)
							)
						)
					)
					(number "185"
						(effects
							(font
								(size 1.27 1.27)
							)
						)
					)
				)
				(pin passive line
					(at 0 -35.56 0)
					(length 3.81)
					(name "I2C0_SDA"
						(effects
							(font
								(size 1.27 1.27)
							)
						)
					)
					(number "187"
						(effects
							(font
								(size 1.27 1.27)
							)
						)
					)
				)
				(pin passive line
					(at 0 -40.64 0)
					(length 3.81)
					(name "I2C1_SCL"
						(effects
							(font
								(size 1.27 1.27)
							)
						)
					)
					(number "189"
						(effects
							(font
								(size 1.27 1.27)
							)
						)
					)
				)
				(pin passive line
					(at 0 -43.18 0)
					(length 3.81)
					(name "I2C1_SDA"
						(effects
							(font
								(size 1.27 1.27)
							)
						)
					)
					(number "191"
						(effects
							(font
								(size 1.27 1.27)
							)
						)
					)
				)
				(pin passive line
					(at 0 -88.9 0)
					(length 3.81)
					(name "I2S0_DOUT"
						(effects
							(font
								(size 1.27 1.27)
							)
						)
					)
					(number "193"
						(effects
							(font
								(size 1.27 1.27)
							)
						)
					)
				)
				(pin passive line
					(at 0 -91.44 0)
					(length 3.81)
					(name "I2S0_DIN"
						(effects
							(font
								(size 1.27 1.27)
							)
						)
					)
					(number "195"
						(effects
							(font
								(size 1.27 1.27)
							)
						)
					)
				)
				(pin passive line
					(at 0 -93.98 0)
					(length 3.81)
					(name "I2S0_FS"
						(effects
							(font
								(size 1.27 1.27)
							)
						)
					)
					(number "197"
						(effects
							(font
								(size 1.27 1.27)
							)
						)
					)
				)
				(pin passive line
					(at 0 -86.36 0)
					(length 3.81)
					(name "I2S0_SCLK"
						(effects
							(font
								(size 1.27 1.27)
							)
						)
					)
					(number "199"
						(effects
							(font
								(size 1.27 1.27)
							)
						)
					)
				)
				(pin passive line
					(at 0 -17.78 0)
					(length 3.81)
					(name "UART1_TXD"
						(effects
							(font
								(size 1.27 1.27)
							)
						)
					)
					(number "203"
						(effects
							(font
								(size 1.27 1.27)
							)
						)
					)
				)
				(pin passive line
					(at 0 -20.32 0)
					(length 3.81)
					(name "UART1_RXD"
						(effects
							(font
								(size 1.27 1.27)
							)
						)
					)
					(number "205"
						(effects
							(font
								(size 1.27 1.27)
							)
						)
					)
				)
				(pin passive line
					(at 0 -12.7 0)
					(length 3.81)
					(name "~{UART1_RTS}"
						(effects
							(font
								(size 1.27 1.27)
							)
						)
					)
					(number "207"
						(effects
							(font
								(size 1.27 1.27)
							)
						)
					)
				)
				(pin passive line
					(at 0 -15.24 0)
					(length 3.81)
					(name "~{UART1_CTS}"
						(effects
							(font
								(size 1.27 1.27)
							)
						)
					)
					(number "209"
						(effects
							(font
								(size 1.27 1.27)
							)
						)
					)
				)
				(pin passive line
					(at 0 -101.6 0)
					(length 3.81)
					(name "I2S1_DOUT"
						(effects
							(font
								(size 1.27 1.27)
							)
						)
					)
					(number "220"
						(effects
							(font
								(size 1.27 1.27)
							)
						)
					)
				)
				(pin passive line
					(at 0 -104.14 0)
					(length 3.81)
					(name "I2S1_DIN"
						(effects
							(font
								(size 1.27 1.27)
							)
						)
					)
					(number "222"
						(effects
							(font
								(size 1.27 1.27)
							)
						)
					)
				)
				(pin passive line
					(at 0 -106.68 0)
					(length 3.81)
					(name "I2S1_FS"
						(effects
							(font
								(size 1.27 1.27)
							)
						)
					)
					(number "224"
						(effects
							(font
								(size 1.27 1.27)
							)
						)
					)
				)
				(pin passive line
					(at 0 -99.06 0)
					(length 3.81)
					(name "I2S1_SCLK"
						(effects
							(font
								(size 1.27 1.27)
							)
						)
					)
					(number "226"
						(effects
							(font
								(size 1.27 1.27)
							)
						)
					)
				)
				(pin passive line
					(at 0 -46.99 0)
					(length 3.81)
					(name "I2C2_SCL"
						(effects
							(font
								(size 1.27 1.27)
							)
						)
					)
					(number "232"
						(effects
							(font
								(size 1.27 1.27)
							)
						)
					)
				)
				(pin passive line
					(at 0 -49.53 0)
					(length 3.81)
					(name "I2C2_SDA"
						(effects
							(font
								(size 1.27 1.27)
							)
						)
					)
					(number "234"
						(effects
							(font
								(size 1.27 1.27)
							)
						)
					)
				)
				(pin passive line
					(at 0 -25.4 0)
					(length 3.81)
					(name "UART2_TXD"
						(effects
							(font
								(size 1.27 1.27)
							)
						)
					)
					(number "236"
						(effects
							(font
								(size 1.27 1.27)
							)
						)
					)
				)
				(pin passive line
					(at 0 -27.94 0)
					(length 3.81)
					(name "UART2_RXD"
						(effects
							(font
								(size 1.27 1.27)
							)
						)
					)
					(number "238"
						(effects
							(font
								(size 1.27 1.27)
							)
						)
					)
				)
				(pin passive line
					(at 0 -58.42 0)
					(length 3.81)
					(name "SPI0_MOSI"
						(effects
							(font
								(size 1.27 1.27)
							)
						)
					)
					(number "89"
						(effects
							(font
								(size 1.27 1.27)
							)
						)
					)
				)
				(pin passive line
					(at 0 -55.88 0)
					(length 3.81)
					(name "SPI0_SCK"
						(effects
							(font
								(size 1.27 1.27)
							)
						)
					)
					(number "91"
						(effects
							(font
								(size 1.27 1.27)
							)
						)
					)
				)
				(pin passive line
					(at 0 -60.96 0)
					(length 3.81)
					(name "SPI0_MISO"
						(effects
							(font
								(size 1.27 1.27)
							)
						)
					)
					(number "93"
						(effects
							(font
								(size 1.27 1.27)
							)
						)
					)
				)
				(pin passive line
					(at 0 -63.5 0)
					(length 3.81)
					(name "~{SPI0_CS0}"
						(effects
							(font
								(size 1.27 1.27)
							)
						)
					)
					(number "95"
						(effects
							(font
								(size 1.27 1.27)
							)
						)
					)
				)
				(pin passive line
					(at 0 -66.04 0)
					(length 3.81)
					(name "~{SPI0_CS1}"
						(effects
							(font
								(size 1.27 1.27)
							)
						)
					)
					(number "97"
						(effects
							(font
								(size 1.27 1.27)
							)
						)
					)
				)
				(pin passive line
					(at 0 -5.08 0)
					(length 3.81)
					(name "UART0_TXD"
						(effects
							(font
								(size 1.27 1.27)
							)
						)
					)
					(number "99"
						(effects
							(font
								(size 1.27 1.27)
							)
						)
					)
				)
			)
			(symbol "Bus_DDR4_SODIMM_CUSTOM_Jetson-Orin-H9.2mm-socket_4_1"
				(rectangle
					(start 3.81 2.54)
					(end 35.56 -64.77)
					(stroke
						(width 0.254)
						(type default)
					)
					(fill
						(type background)
					)
				)
				(arc
					(start 12.7 -1.27)
					(mid 12.886 -1.719)
					(end 13.335 -1.905)
					(stroke
						(width 0.254)
						(type default)
					)
					(fill
						(type background)
					)
				)
				(text "1.8V OD Bidir, 3.3V Tolerant"
					(at 13.97 -2.54 0)
					(effects
						(font
							(size 0.635 0.635)
							(thickness 0.15)
						)
						(justify left bottom)
					)
				)
				(pin passive line
					(at 0 -49.53 0)
					(length 3.81)
					(name "USB0_D_N"
						(effects
							(font
								(size 1.27 1.27)
							)
						)
					)
					(number "109"
						(effects
							(font
								(size 1.27 1.27)
							)
						)
					)
				)
				(pin passive line
					(at 0 -46.99 0)
					(length 3.81)
					(name "USB0_D_P"
						(effects
							(font
								(size 1.27 1.27)
							)
						)
					)
					(number "111"
						(effects
							(font
								(size 1.27 1.27)
							)
						)
					)
				)
				(pin passive line
					(at 0 -55.88 0)
					(length 3.81)
					(name "USB1_D_N"
						(effects
							(font
								(size 1.27 1.27)
							)
						)
					)
					(number "115"
						(effects
							(font
								(size 1.27 1.27)
							)
						)
					)
				)
				(pin passive line
					(at 0 -53.34 0)
					(length 3.81)
					(name "USB1_D_P"
						(effects
							(font
								(size 1.27 1.27)
							)
						)
					)
					(number "117"
						(effects
							(font
								(size 1.27 1.27)
							)
						)
					)
				)
				(pin passive line
					(at 0 -62.23 0)
					(length 3.81)
					(name "USB2_D_N"
						(effects
							(font
								(size 1.27 1.27)
							)
						)
					)
					(number "121"
						(effects
							(font
								(size 1.27 1.27)
							)
						)
					)
				)
				(pin passive line
					(at 0 -59.69 0)
					(length 3.81)
					(name "USB2_D_P"
						(effects
							(font
								(size 1.27 1.27)
							)
						)
					)
					(number "123"
						(effects
							(font
								(size 1.27 1.27)
							)
						)
					)
				)
				(pin passive line
					(at 0 -13.97 0)
					(length 3.81)
					(name "USBSS0_RX_N"
						(effects
							(font
								(size 1.27 1.27)
							)
						)
					)
					(number "161"
						(effects
							(font
								(size 1.27 1.27)
							)
						)
					)
				)
				(pin passive line
					(at 0 -11.43 0)
					(length 3.81)
					(name "USBSS0_RX_P"
						(effects
							(font
								(size 1.27 1.27)
							)
						)
					)
					(number "163"
						(effects
							(font
								(size 1.27 1.27)
							)
						)
					)
				)
				(pin passive line
					(at 0 -7.62 0)
					(length 3.81)
					(name "USBSS0_TX_N"
						(effects
							(font
								(size 1.27 1.27)
							)
						)
					)
					(number "166"
						(effects
							(font
								(size 1.27 1.27)
							)
						)
					)
				)
				(pin passive line
					(at 0 -5.08 0)
					(length 3.81)
					(name "USBSS0_TX_P"
						(effects
							(font
								(size 1.27 1.27)
							)
						)
					)
					(number "168"
						(effects
							(font
								(size 1.27 1.27)
							)
						)
					)
				)
				(pin passive line
					(at 0 -27.94 0)
					(length 3.81)
					(name "USBSS1_RX_N"
						(effects
							(font
								(size 1.27 1.27)
							)
						)
					)
					(number "39"
						(effects
							(font
								(size 1.27 1.27)
							)
						)
					)
				)
				(pin passive line
					(at 0 -25.4 0)
					(length 3.81)
					(name "USBSS1_RX_P"
						(effects
							(font
								(size 1.27 1.27)
							)
						)
					)
					(number "41"
						(effects
							(font
								(size 1.27 1.27)
							)
						)
					)
				)
				(pin passive line
					(at 0 -21.59 0)
					(length 3.81)
					(name "USBSS1_TX_N"
						(effects
							(font
								(size 1.27 1.27)
							)
						)
					)
					(number "45"
						(effects
							(font
								(size 1.27 1.27)
							)
						)
					)
				)
				(pin passive line
					(at 0 -19.05 0)
					(length 3.81)
					(name "USBSS1_TX_P"
						(effects
							(font
								(size 1.27 1.27)
							)
						)
					)
					(number "47"
						(effects
							(font
								(size 1.27 1.27)
							)
						)
					)
				)
				(pin passive line
					(at 0 -41.91 0)
					(length 3.81)
					(name "USBSS2_RX_N"
						(effects
							(font
								(size 1.27 1.27)
							)
						)
					)
					(number "51"
						(effects
							(font
								(size 1.27 1.27)
							)
						)
					)
				)
				(pin passive line
					(at 0 -39.37 0)
					(length 3.81)
					(name "USBSS2_RX_P"
						(effects
							(font
								(size 1.27 1.27)
							)
						)
					)
					(number "53"
						(effects
							(font
								(size 1.27 1.27)
							)
						)
					)
				)
				(pin passive line
					(at 0 -35.56 0)
					(length 3.81)
					(name "USBSS2_TX_N"
						(effects
							(font
								(size 1.27 1.27)
							)
						)
					)
					(number "57"
						(effects
							(font
								(size 1.27 1.27)
							)
						)
					)
				)
				(pin passive line
					(at 0 -33.02 0)
					(length 3.81)
					(name "USBSS2_TX_P"
						(effects
							(font
								(size 1.27 1.27)
							)
						)
					)
					(number "59"
						(effects
							(font
								(size 1.27 1.27)
							)
						)
					)
				)
				(pin passive line
					(at 0 0 0)
					(length 3.81)
					(name "USB_VBUS_EN0/GPIO00"
						(effects
							(font
								(size 1.27 1.27)
							)
						)
					)
					(number "87"
						(effects
							(font
								(size 1.27 1.27)
							)
						)
					)
					(alternate "GPIO00" passive line)
					(alternate "GPIO00(USB_VBUS_EN0)" passive line)
				)
			)
			(symbol "Bus_DDR4_SODIMM_CUSTOM_Jetson-Orin-H9.2mm-socket_5_1"
				(polyline
					(pts
						(xy 3.81 -38.1) (xy 35.56 -38.1)
					)
					(stroke
						(width 0.254)
						(type default)
					)
					(fill
						(type background)
					)
				)
				(rectangle
					(start 3.81 2.54)
					(end 35.56 -48.26)
					(stroke
						(width 0.254)
						(type default)
					)
					(fill
						(type background)
					)
				)
				(text "1.8V Input"
					(at 15.24 -2.54 0)
					(effects
						(font
							(size 0.635 0.635)
							(thickness 0.15)
						)
						(justify left)
					)
				)
				(text "1k PU to 1.8V Bidir"
					(at 15.24 0 0)
					(effects
						(font
							(size 0.635 0.635)
							(thickness 0.15)
						)
						(justify left)
					)
				)
				(text "RSVD"
					(at 29.21 -40.64 0)
					(effects
						(font
							(size 1.27 1.27)
							(thickness 0.15)
						)
						(justify left bottom)
					)
				)
				(pin passive line
					(at 0 -7.62 0)
					(length 3.81)
					(name "DP1_AUX_P"
						(effects
							(font
								(size 1.27 1.27)
							)
						)
					)
					(number "100"
						(effects
							(font
								(size 1.27 1.27)
							)
						)
					)
				)
				(pin passive line
					(at 0 -16.51 0)
					(length 3.81)
					(name "DP1_TXD0_N"
						(effects
							(font
								(size 1.27 1.27)
							)
						)
					)
					(number "63"
						(effects
							(font
								(size 1.27 1.27)
							)
						)
					)
				)
				(pin passive line
					(at 0 -13.97 0)
					(length 3.81)
					(name "DP1_TXD0_P"
						(effects
							(font
								(size 1.27 1.27)
							)
						)
					)
					(number "65"
						(effects
							(font
								(size 1.27 1.27)
							)
						)
					)
				)
				(pin passive line
					(at 0 -22.86 0)
					(length 3.81)
					(name "DP1_TXD1_N"
						(effects
							(font
								(size 1.27 1.27)
							)
						)
					)
					(number "69"
						(effects
							(font
								(size 1.27 1.27)
							)
						)
					)
				)
				(pin passive line
					(at 0 -20.32 0)
					(length 3.81)
					(name "DP1_TXD1_P"
						(effects
							(font
								(size 1.27 1.27)
							)
						)
					)
					(number "71"
						(effects
							(font
								(size 1.27 1.27)
							)
						)
					)
				)
				(pin passive line
					(at 0 -29.21 0)
					(length 3.81)
					(name "DP1_TXD2_N"
						(effects
							(font
								(size 1.27 1.27)
							)
						)
					)
					(number "75"
						(effects
							(font
								(size 1.27 1.27)
							)
						)
					)
				)
				(pin passive line
					(at 0 -26.67 0)
					(length 3.81)
					(name "DP1_TXD2_P"
						(effects
							(font
								(size 1.27 1.27)
							)
						)
					)
					(number "77"
						(effects
							(font
								(size 1.27 1.27)
							)
						)
					)
				)
				(pin passive line
					(at 0 -35.56 0)
					(length 3.81)
					(name "DP1_TXD3_N"
						(effects
							(font
								(size 1.27 1.27)
							)
						)
					)
					(number "81"
						(effects
							(font
								(size 1.27 1.27)
							)
						)
					)
				)
				(pin passive line
					(at 0 -33.02 0)
					(length 3.81)
					(name "DP1_TXD3_P"
						(effects
							(font
								(size 1.27 1.27)
							)
						)
					)
					(number "83"
						(effects
							(font
								(size 1.27 1.27)
							)
						)
					)
				)
				(pin passive line
					(at 0 -40.64 0)
					(length 3.81)
					(name "DP0_HPD"
						(effects
							(font
								(size 1.27 1.27)
							)
						)
					)
					(number "88"
						(effects
							(font
								(size 1.27 1.27)
							)
						)
					)
				)
				(pin passive line
					(at 0 -45.72 0)
					(length 3.81)
					(name "DP0_AUX_N"
						(effects
							(font
								(size 1.27 1.27)
							)
						)
					)
					(number "90"
						(effects
							(font
								(size 1.27 1.27)
							)
						)
					)
				)
				(pin passive line
					(at 0 -43.18 0)
					(length 3.81)
					(name "DP0_AUX_P"
						(effects
							(font
								(size 1.27 1.27)
							)
						)
					)
					(number "92"
						(effects
							(font
								(size 1.27 1.27)
							)
						)
					)
				)
				(pin passive line
					(at 0 0 0)
					(length 3.81)
					(name "HDMI_CEC"
						(effects
							(font
								(size 1.27 1.27)
							)
						)
					)
					(number "94"
						(effects
							(font
								(size 1.27 1.27)
							)
						)
					)
				)
				(pin passive line
					(at 0 -2.54 0)
					(length 3.81)
					(name "DP1_HPD"
						(effects
							(font
								(size 1.27 1.27)
							)
						)
					)
					(number "96"
						(effects
							(font
								(size 1.27 1.27)
							)
						)
					)
				)
				(pin passive line
					(at 0 -10.16 0)
					(length 3.81)
					(name "DP1_AUX_N"
						(effects
							(font
								(size 1.27 1.27)
							)
						)
					)
					(number "98"
						(effects
							(font
								(size 1.27 1.27)
							)
						)
					)
				)
			)
			(symbol "Bus_DDR4_SODIMM_CUSTOM_Jetson-Orin-H9.2mm-socket_6_1"
				(polyline
					(pts
						(xy 19.05 -130.81) (xy 19.05 -110.49)
					)
					(stroke
						(width 0.254)
						(type default)
					)
					(fill
						(type none)
					)
				)
				(polyline
					(pts
						(xy 19.05 -106.68) (xy 19.05 -86.36)
					)
					(stroke
						(width 0.254)
						(type default)
					)
					(fill
						(type none)
					)
				)
				(polyline
					(pts
						(xy 19.05 -82.55) (xy 19.05 -62.23)
					)
					(stroke
						(width 0.254)
						(type default)
					)
					(fill
						(type none)
					)
				)
				(polyline
					(pts
						(xy 19.05 -58.42) (xy 19.05 -2.54)
					)
					(stroke
						(width 0.254)
						(type default)
					)
					(fill
						(type none)
					)
				)
				(rectangle
					(start 3.81 2.54)
					(end 35.56 -133.35)
					(stroke
						(width 0.254)
						(type default)
					)
					(fill
						(type background)
					)
				)
				(arc
					(start 17.78 -132.08)
					(mid 18.678 -131.708)
					(end 19.05 -130.81)
					(stroke
						(width 0.254)
						(type default)
					)
					(fill
						(type none)
					)
				)
				(arc
					(start 17.78 -107.95)
					(mid 18.678 -107.578)
					(end 19.05 -106.68)
					(stroke
						(width 0.254)
						(type default)
					)
					(fill
						(type none)
					)
				)
				(arc
					(start 17.78 -83.82)
					(mid 18.678 -83.448)
					(end 19.05 -82.55)
					(stroke
						(width 0.254)
						(type default)
					)
					(fill
						(type none)
					)
				)
				(arc
					(start 17.78 -59.69)
					(mid 18.678 -59.318)
					(end 19.05 -58.42)
					(stroke
						(width 0.254)
						(type default)
					)
					(fill
						(type none)
					)
				)
				(arc
					(start 19.05 -110.49)
					(mid 18.678 -109.592)
					(end 17.78 -109.22)
					(stroke
						(width 0.254)
						(type default)
					)
					(fill
						(type none)
					)
				)
				(arc
					(start 19.05 -86.36)
					(mid 18.678 -85.462)
					(end 17.78 -85.09)
					(stroke
						(width 0.254)
						(type default)
					)
					(fill
						(type none)
					)
				)
				(arc
					(start 19.05 -62.23)
					(mid 18.678 -61.332)
					(end 17.78 -60.96)
					(stroke
						(width 0.254)
						(type default)
					)
					(fill
						(type none)
					)
				)
				(arc
					(start 19.05 -2.54)
					(mid 18.678 -1.642)
					(end 17.78 -1.27)
					(stroke
						(width 0.254)
						(type default)
					)
					(fill
						(type none)
					)
				)
				(text "47k PU to 3.3V"
					(at 16.51 0 0)
					(effects
						(font
							(size 0.635 0.635)
							(thickness 0.15)
						)
						(justify left bottom)
					)
				)
				(text "PCIe0"
					(at 20.32 -31.75 0)
					(effects
						(font
							(size 1.27 1.27)
							(thickness 0.15)
						)
						(justify left bottom)
					)
				)
				(text "PCIe1"
					(at 20.32 -73.66 0)
					(effects
						(font
							(size 1.27 1.27)
							(thickness 0.15)
						)
						(justify left bottom)
					)
				)
				(text "PCIe2"
					(at 20.32 -97.79 0)
					(effects
						(font
							(size 1.27 1.27)
							(thickness 0.15)
						)
						(justify left bottom)
					)
				)
				(text "PCIe3/PCIe2"
					(at 20.32 -121.92 0)
					(effects
						(font
							(size 1.27 1.27)
							(thickness 0.15)
						)
						(justify left bottom)
					)
				)
				(pin passive line
					(at 0 -24.13 0)
					(length 3.81)
					(name "PCIE0_RX0_N"
						(effects
							(font
								(size 1.27 1.27)
							)
						)
					)
					(number "131"
						(effects
							(font
								(size 1.27 1.27)
							)
						)
					)
				)
				(pin passive line
					(at 0 -21.59 0)
					(length 3.81)
					(name "PCIE0_RX0_P"
						(effects
							(font
								(size 1.27 1.27)
							)
						)
					)
					(number "133"
						(effects
							(font
								(size 1.27 1.27)
							)
						)
					)
				)
				(pin passive line
					(at 0 -19.05 0)
					(length 3.81)
					(name "PCIE0_TX0_N"
						(effects
							(font
								(size 1.27 1.27)
							)
						)
					)
					(number "134"
						(effects
							(font
								(size 1.27 1.27)
							)
						)
					)
				)
				(pin passive line
					(at 0 -16.51 0)
					(length 3.81)
					(name "PCIE0_TX0_P"
						(effects
							(font
								(size 1.27 1.27)
							)
						)
					)
					(number "136"
						(effects
							(font
								(size 1.27 1.27)
							)
						)
					)
				)
				(pin passive line
					(at 0 -35.56 0)
					(length 3.81)
					(name "PCIE0_RX1_N"
						(effects
							(font
								(size 1.27 1.27)
							)
						)
					)
					(number "137"
						(effects
							(font
								(size 1.27 1.27)
							)
						)
					)
				)
				(pin passive line
					(at 0 -33.02 0)
					(length 3.81)
					(name "PCIE0_RX1_P"
						(effects
							(font
								(size 1.27 1.27)
							)
						)
					)
					(number "139"
						(effects
							(font
								(size 1.27 1.27)
							)
						)
					)
				)
				(pin passive line
					(at 0 -30.48 0)
					(length 3.81)
					(name "PCIE0_TX1_N"
						(effects
							(font
								(size 1.27 1.27)
							)
						)
					)
					(number "140"
						(effects
							(font
								(size 1.27 1.27)
							)
						)
					)
				)
				(pin passive line
					(at 0 -27.94 0)
					(length 3.81)
					(name "PCIE0_TX1_P"
						(effects
							(font
								(size 1.27 1.27)
							)
						)
					)
					(number "142"
						(effects
							(font
								(size 1.27 1.27)
							)
						)
					)
				)
				(pin passive line
					(at 0 -41.91 0)
					(length 3.81)
					(name "PCIE0_TX2_N"
						(effects
							(font
								(size 1.27 1.27)
							)
						)
					)
					(number "148"
						(effects
							(font
								(size 1.27 1.27)
							)
						)
					)
				)
				(pin passive line
					(at 0 -46.99 0)
					(length 3.81)
					(name "PCIE0_RX2_N"
						(effects
							(font
								(size 1.27 1.27)
							)
						)
					)
					(number "149"
						(effects
							(font
								(size 1.27 1.27)
							)
						)
					)
				)
				(pin passive line
					(at 0 -39.37 0)
					(length 3.81)
					(name "PCIE0_TX2_P"
						(effects
							(font
								(size 1.27 1.27)
							)
						)
					)
					(number "150"
						(effects
							(font
								(size 1.27 1.27)
							)
						)
					)
				)
				(pin passive line
					(at 0 -44.45 0)
					(length 3.81)
					(name "PCIE0_RX2_P"
						(effects
							(font
								(size 1.27 1.27)
							)
						)
					)
					(number "151"
						(effects
							(font
								(size 1.27 1.27)
							)
						)
					)
				)
				(pin passive line
					(at 0 -53.34 0)
					(length 3.81)
					(name "PCIE0_TX3_N"
						(effects
							(font
								(size 1.27 1.27)
							)
						)
					)
					(number "154"
						(effects
							(font
								(size 1.27 1.27)
							)
						)
					)
				)
				(pin passive line
					(at 0 -58.42 0)
					(length 3.81)
					(name "PCIE0_RX3_N"
						(effects
							(font
								(size 1.27 1.27)
							)
						)
					)
					(number "155"
						(effects
							(font
								(size 1.27 1.27)
							)
						)
					)
				)
				(pin passive line
					(at 0 -50.8 0)
					(length 3.81)
					(name "PCIE0_TX3_P"
						(effects
							(font
								(size 1.27 1.27)
							)
						)
					)
					(number "156"
						(effects
							(font
								(size 1.27 1.27)
							)
						)
					)
				)
				(pin passive line
					(at 0 -55.88 0)
					(length 3.81)
					(name "PCIE0_RX3_P"
						(effects
							(font
								(size 1.27 1.27)
							)
						)
					)
					(number "157"
						(effects
							(font
								(size 1.27 1.27)
							)
						)
					)
				)
				(pin passive line
					(at 0 -12.7 0)
					(length 3.81)
					(name "PCIE0_CLK_N"
						(effects
							(font
								(size 1.27 1.27)
							)
						)
					)
					(number "160"
						(effects
							(font
								(size 1.27 1.27)
							)
						)
					)
				)
				(pin passive line
					(at 0 -10.16 0)
					(length 3.81)
					(name "PCIE0_CLK_P"
						(effects
							(font
								(size 1.27 1.27)
							)
						)
					)
					(number "162"
						(effects
							(font
								(size 1.27 1.27)
							)
						)
					)
				)
				(pin passive line
					(at 0 -82.55 0)
					(length 3.81)
					(name "PCIE1_RX0_N"
						(effects
							(font
								(size 1.27 1.27)
							)
						)
					)
					(number "167"
						(effects
							(font
								(size 1.27 1.27)
							)
						)
					)
				)
				(pin passive line
					(at 0 -80.01 0)
					(length 3.81)
					(name "PCIE1_RX0_P"
						(effects
							(font
								(size 1.27 1.27)
							)
						)
					)
					(number "169"
						(effects
							(font
								(size 1.27 1.27)
							)
						)
					)
				)
				(pin passive line
					(at 0 -77.47 0)
					(length 3.81)
					(name "PCIE1_TX0_N"
						(effects
							(font
								(size 1.27 1.27)
							)
						)
					)
					(number "172"
						(effects
							(font
								(size 1.27 1.27)
							)
						)
					)
				)
				(pin passive line
					(at 0 -71.12 0)
					(length 3.81)
					(name "PCIE1_CLK_N"
						(effects
							(font
								(size 1.27 1.27)
							)
						)
					)
					(number "173"
						(effects
							(font
								(size 1.27 1.27)
							)
						)
					)
				)
				(pin passive line
					(at 0 -74.93 0)
					(length 3.81)
					(name "PCIE1_TX0_P"
						(effects
							(font
								(size 1.27 1.27)
							)
						)
					)
					(number "174"
						(effects
							(font
								(size 1.27 1.27)
							)
						)
					)
				)
				(pin passive line
					(at 0 -68.58 0)
					(length 3.81)
					(name "PCIE1_CLK_P"
						(effects
							(font
								(size 1.27 1.27)
							)
						)
					)
					(number "175"
						(effects
							(font
								(size 1.27 1.27)
							)
						)
					)
				)
				(pin passive line
					(at 0 0 0)
					(length 3.81)
					(name "~{PCIE_WAKE}"
						(effects
							(font
								(size 1.27 1.27)
							)
						)
					)
					(number "179"
						(effects
							(font
								(size 1.27 1.27)
							)
						)
					)
				)
				(pin passive line
					(at 0 -6.35 0)
					(length 3.81)
					(name "~{PCIE0_CLKREQ}"
						(effects
							(font
								(size 1.27 1.27)
							)
						)
					)
					(number "180"
						(effects
							(font
								(size 1.27 1.27)
							)
						)
					)
				)
				(pin passive line
					(at 0 -3.81 0)
					(length 3.81)
					(name "~{PCIE0_RST}"
						(effects
							(font
								(size 1.27 1.27)
							)
						)
					)
					(number "181"
						(effects
							(font
								(size 1.27 1.27)
							)
						)
					)
				)
				(pin passive line
					(at 0 -64.77 0)
					(length 3.81)
					(name "~{PCIE1_CLKREQ}"
						(effects
							(font
								(size 1.27 1.27)
							)
						)
					)
					(number "182"
						(effects
							(font
								(size 1.27 1.27)
							)
						)
					)
				)
				(pin passive line
					(at 0 -62.23 0)
					(length 3.81)
					(name "~{PCIE1_RST}"
						(effects
							(font
								(size 1.27 1.27)
							)
						)
					)
					(number "183"
						(effects
							(font
								(size 1.27 1.27)
							)
						)
					)
				)
				(pin passive line
					(at 0 -86.36 0)
					(length 3.81)
					(name "~{PCIE2_RST}"
						(effects
							(font
								(size 1.27 1.27)
							)
						)
					)
					(number "219"
						(effects
							(font
								(size 1.27 1.27)
							)
						)
					)
				)
				(pin passive line
					(at 0 -88.9 0)
					(length 3.81)
					(name "~{PCIE2_CLKREQ}"
						(effects
							(font
								(size 1.27 1.27)
							)
						)
					)
					(number "221"
						(effects
							(font
								(size 1.27 1.27)
							)
						)
					)
				)
				(pin passive line
					(at 0 -110.49 0)
					(length 3.81)
					(name "~{PCIE3_RST}"
						(effects
							(font
								(size 1.27 1.27)
							)
						)
					)
					(number "223"
						(effects
							(font
								(size 1.27 1.27)
							)
						)
					)
				)
				(pin passive line
					(at 0 -113.03 0)
					(length 3.81)
					(name "~{PCIE3_CLKREQ}"
						(effects
							(font
								(size 1.27 1.27)
							)
						)
					)
					(number "225"
						(effects
							(font
								(size 1.27 1.27)
							)
						)
					)
				)
				(pin passive line
					(at 0 -119.38 0)
					(length 3.81)
					(name "PCIE3_CLK_N"
						(effects
							(font
								(size 1.27 1.27)
							)
						)
					)
					(number "227"
						(effects
							(font
								(size 1.27 1.27)
							)
						)
					)
				)
				(pin passive line
					(at 0 -116.84 0)
					(length 3.81)
					(name "PCIE3_CLK_P"
						(effects
							(font
								(size 1.27 1.27)
							)
						)
					)
					(number "229"
						(effects
							(font
								(size 1.27 1.27)
							)
						)
					)
				)
				(pin passive line
					(at 0 -106.68 0)
					(length 3.81)
					(name "PCIE2_RX0_N"
						(effects
							(font
								(size 1.27 1.27)
							)
						)
					)
					(number "40"
						(effects
							(font
								(size 1.27 1.27)
							)
						)
					)
				)
				(pin passive line
					(at 0 -104.14 0)
					(length 3.81)
					(name "PCIE2_RX0_P"
						(effects
							(font
								(size 1.27 1.27)
							)
						)
					)
					(number "42"
						(effects
							(font
								(size 1.27 1.27)
							)
						)
					)
				)
				(pin passive line
					(at 0 -101.6 0)
					(length 3.81)
					(name "PCIE2_TX0_N"
						(effects
							(font
								(size 1.27 1.27)
							)
						)
					)
					(number "46"
						(effects
							(font
								(size 1.27 1.27)
							)
						)
					)
				)
				(pin passive line
					(at 0 -99.06 0)
					(length 3.81)
					(name "PCIE2_TX0_P"
						(effects
							(font
								(size 1.27 1.27)
							)
						)
					)
					(number "48"
						(effects
							(font
								(size 1.27 1.27)
							)
						)
					)
				)
				(pin passive line
					(at 0 -95.25 0)
					(length 3.81)
					(name "PCIE2_CLK_N"
						(effects
							(font
								(size 1.27 1.27)
							)
						)
					)
					(number "52"
						(effects
							(font
								(size 1.27 1.27)
							)
						)
					)
				)
				(pin passive line
					(at 0 -92.71 0)
					(length 3.81)
					(name "PCIE2_CLK_P"
						(effects
							(font
								(size 1.27 1.27)
							)
						)
					)
					(number "54"
						(effects
							(font
								(size 1.27 1.27)
							)
						)
					)
				)
				(pin passive line
					(at 0 -130.81 0)
					(length 3.81)
					(name "PCIE3_RX0_N"
						(effects
							(font
								(size 1.27 1.27)
							)
						)
					)
					(number "58"
						(effects
							(font
								(size 1.27 1.27)
							)
						)
					)
					(alternate "PCIE2_RX1_N" passive line)
				)
				(pin passive line
					(at 0 -128.27 0)
					(length 3.81)
					(name "PCIE3_RX0_P"
						(effects
							(font
								(size 1.27 1.27)
							)
						)
					)
					(number "60"
						(effects
							(font
								(size 1.27 1.27)
							)
						)
					)
					(alternate "PCIE2_RX1_P" passive line)
				)
				(pin passive line
					(at 0 -125.73 0)
					(length 3.81)
					(name "PCIE3_TX0_N"
						(effects
							(font
								(size 1.27 1.27)
							)
						)
					)
					(number "64"
						(effects
							(font
								(size 1.27 1.27)
							)
						)
					)
					(alternate "PCIE2_TX1_N" passive line)
				)
				(pin passive line
					(at 0 -123.19 0)
					(length 3.81)
					(name "PCIE3_TX0_P"
						(effects
							(font
								(size 1.27 1.27)
							)
						)
					)
					(number "66"
						(effects
							(font
								(size 1.27 1.27)
							)
						)
					)
					(alternate "PCIE2_TX1_P" passive line)
				)
			)
			(symbol "Bus_DDR4_SODIMM_CUSTOM_Jetson-Orin-H9.2mm-socket_7_1"
				(rectangle
					(start 3.81 2.54)
					(end 35.56 -31.75)
					(stroke
						(width 0.254)
						(type default)
					)
					(fill
						(type background)
					)
				)
				(pin passive line
					(at 0 -10.16 0)
					(length 3.81)
					(name "GBE_MDI0_N"
						(effects
							(font
								(size 1.27 1.27)
							)
						)
					)
					(number "184"
						(effects
							(font
								(size 1.27 1.27)
							)
						)
					)
				)
				(pin passive line
					(at 0 -7.62 0)
					(length 3.81)
					(name "GBE_MDI0_P"
						(effects
							(font
								(size 1.27 1.27)
							)
						)
					)
					(number "186"
						(effects
							(font
								(size 1.27 1.27)
							)
						)
					)
				)
				(pin passive line
					(at 0 0 0)
					(length 3.81)
					(name "GBE_LED_LINK"
						(effects
							(font
								(size 1.27 1.27)
							)
						)
					)
					(number "188"
						(effects
							(font
								(size 1.27 1.27)
							)
						)
					)
				)
				(pin passive line
					(at 0 -16.51 0)
					(length 3.81)
					(name "GBE_MDI1_N"
						(effects
							(font
								(size 1.27 1.27)
							)
						)
					)
					(number "190"
						(effects
							(font
								(size 1.27 1.27)
							)
						)
					)
				)
				(pin passive line
					(at 0 -13.97 0)
					(length 3.81)
					(name "GBE_MDI1_P"
						(effects
							(font
								(size 1.27 1.27)
							)
						)
					)
					(number "192"
						(effects
							(font
								(size 1.27 1.27)
							)
						)
					)
				)
				(pin passive line
					(at 0 -2.54 0)
					(length 3.81)
					(name "GBE_LED_ACT"
						(effects
							(font
								(size 1.27 1.27)
							)
						)
					)
					(number "194"
						(effects
							(font
								(size 1.27 1.27)
							)
						)
					)
				)
				(pin passive line
					(at 0 -22.86 0)
					(length 3.81)
					(name "GBE_MDI2_N"
						(effects
							(font
								(size 1.27 1.27)
							)
						)
					)
					(number "196"
						(effects
							(font
								(size 1.27 1.27)
							)
						)
					)
				)
				(pin passive line
					(at 0 -20.32 0)
					(length 3.81)
					(name "GBE_MDI2_P"
						(effects
							(font
								(size 1.27 1.27)
							)
						)
					)
					(number "198"
						(effects
							(font
								(size 1.27 1.27)
							)
						)
					)
				)
				(pin passive line
					(at 0 -29.21 0)
					(length 3.81)
					(name "GBE_MDI3_N"
						(effects
							(font
								(size 1.27 1.27)
							)
						)
					)
					(number "202"
						(effects
							(font
								(size 1.27 1.27)
							)
						)
					)
				)
				(pin passive line
					(at 0 -26.67 0)
					(length 3.81)
					(name "GBE_MDI3_P"
						(effects
							(font
								(size 1.27 1.27)
							)
						)
					)
					(number "204"
						(effects
							(font
								(size 1.27 1.27)
							)
						)
					)
				)
			)
			(symbol "Bus_DDR4_SODIMM_CUSTOM_Jetson-Orin-H9.2mm-socket_8_1"
				(polyline
					(pts
						(xy 23.495 0.635) (xy 23.495 -28.575)
					)
					(stroke
						(width 0.254)
						(type default)
					)
					(fill
						(type background)
					)
				)
				(rectangle
					(start 3.81 2.54)
					(end 35.56 -30.48)
					(stroke
						(width 0.254)
						(type default)
					)
					(fill
						(type background)
					)
				)
				(arc
					(start 22.86 -29.21)
					(mid 23.3098 -29.0248)
					(end 23.495 -28.575)
					(stroke
						(width 0.254)
						(type default)
					)
					(fill
						(type background)
					)
				)
				(arc
					(start 23.495 0.635)
					(mid 23.309 1.084)
					(end 22.86 1.27)
					(stroke
						(width 0.254)
						(type default)
					)
					(fill
						(type background)
					)
				)
				(text "1.8V CMOS"
					(at 24.13 -15.24 0)
					(effects
						(font
							(size 1.27 1.27)
							(thickness 0.15)
						)
						(justify left bottom)
					)
				)
				(pin passive line
					(at 0 0 0)
					(length 3.81)
					(name "GPIO01/CLK"
						(effects
							(font
								(size 1.27 1.27)
							)
						)
					)
					(number "118"
						(effects
							(font
								(size 1.27 1.27)
							)
						)
					)
					(alternate "GPIO01" passive line)
					(alternate "GPIO01(CLK)" passive line)
				)
				(pin passive line
					(at 0 -2.54 0)
					(length 3.81)
					(name "GPIO02"
						(effects
							(font
								(size 1.27 1.27)
							)
						)
					)
					(number "124"
						(effects
							(font
								(size 1.27 1.27)
							)
						)
					)
				)
				(pin passive line
					(at 0 -5.08 0)
					(length 3.81)
					(name "GPIO03"
						(effects
							(font
								(size 1.27 1.27)
							)
						)
					)
					(number "126"
						(effects
							(font
								(size 1.27 1.27)
							)
						)
					)
				)
				(pin passive line
					(at 0 -7.62 0)
					(length 3.81)
					(name "GPIO04"
						(effects
							(font
								(size 1.27 1.27)
							)
						)
					)
					(number "127"
						(effects
							(font
								(size 1.27 1.27)
							)
						)
					)
				)
				(pin passive line
					(at 0 -10.16 0)
					(length 3.81)
					(name "GPIO05"
						(effects
							(font
								(size 1.27 1.27)
							)
						)
					)
					(number "128"
						(effects
							(font
								(size 1.27 1.27)
							)
						)
					)
				)
				(pin passive line
					(at 0 -12.7 0)
					(length 3.81)
					(name "GPIO06"
						(effects
							(font
								(size 1.27 1.27)
							)
						)
					)
					(number "130"
						(effects
							(font
								(size 1.27 1.27)
							)
						)
					)
				)
				(pin passive line
					(at 0 -15.24 0)
					(length 3.81)
					(name "GPIO07/PWM"
						(effects
							(font
								(size 1.27 1.27)
							)
						)
					)
					(number "206"
						(effects
							(font
								(size 1.27 1.27)
							)
						)
					)
					(alternate "GPIO07" passive line)
					(alternate "GPIO07(PWM)" passive line)
				)
				(pin passive line
					(at 0 -17.78 0)
					(length 3.81)
					(name "GPIO09/AUD_MCLK"
						(effects
							(font
								(size 1.27 1.27)
							)
						)
					)
					(number "211"
						(effects
							(font
								(size 1.27 1.27)
							)
						)
					)
					(alternate "GPIO09" passive line)
					(alternate "GPIO09(AUD_MCLK)" passive line)
				)
				(pin passive line
					(at 0 -20.32 0)
					(length 3.81)
					(name "GPIO10"
						(effects
							(font
								(size 1.27 1.27)
							)
						)
					)
					(number "212"
						(effects
							(font
								(size 1.27 1.27)
							)
						)
					)
				)
				(pin passive line
					(at 0 -22.86 0)
					(length 3.81)
					(name "GPIO11/CLK"
						(effects
							(font
								(size 1.27 1.27)
							)
						)
					)
					(number "216"
						(effects
							(font
								(size 1.27 1.27)
							)
						)
					)
					(alternate "GPIO11" passive line)
					(alternate "GPIO11(CLK)" passive line)
				)
				(pin passive line
					(at 0 -25.4 0)
					(length 3.81)
					(name "GPIO12/PWM"
						(effects
							(font
								(size 1.27 1.27)
							)
						)
					)
					(number "218"
						(effects
							(font
								(size 1.27 1.27)
							)
						)
					)
					(alternate "GPIO12" passive line)
					(alternate "GPIO12(PWM)" passive line)
				)
				(pin passive line
					(at 0 -27.94 0)
					(length 3.81)
					(name "GPIO13/PWM"
						(effects
							(font
								(size 1.27 1.27)
							)
						)
					)
					(number "228"
						(effects
							(font
								(size 1.27 1.27)
							)
						)
					)
					(alternate "GPIO13" passive line)
					(alternate "GPIO13(PWM)" passive line)
				)
			)
		)
	(symbol "antmicroTVSDiodes:DF2S30FS_SOD"
			(pin_numbers hide)
			(pin_names hide)
			(exclude_from_sim no)
			(in_bom yes)
			(on_board yes)
			(property "Reference" "D"
				(at 21.59 -2.54 0)
				(effects
					(font
						(size 1.27 1.27)
						(thickness 0.15)
					)
					(justify left bottom)
				)
			)
			(property "Value" "DF2S30FS_SOD"
				(at 21.59 -15.24 0)
				(effects
					(font
						(size 1.27 1.27)
						(thickness 0.15)
					)
					(justify left bottom)
					(hide yes)
				)
			)
			(property "Footprint" "antmicro-footprints:SOD-923"
				(at 21.59 -7.62 0)
				(effects
					(font
						(size 1.27 1.27)
						(thickness 0.15)
					)
					(justify left bottom)
					(hide yes)
				)
			)
			(property "Datasheet" "https://toshiba.semicon-storage.com/info/DF2S30FS_datasheet_en_20211216.pdf?did=11156&prodName=DF2S30FS"
				(at 21.59 -10.16 0)
				(effects
					(font
						(size 1.27 1.27)
						(thickness 0.15)
					)
					(justify left bottom)
					(hide yes)
				)
			)
			(property "Description" "Unidirectional TVS, 8 kV,  SOD-923, 23 V, 7 pF"
				(at 0 0 0)
				(effects
					(font
						(size 1.27 1.27)
					)
					(hide yes)
				)
			)
			(property "Manufacturer" "Toshiba"
				(at 21.59 -12.7 0)
				(effects
					(font
						(size 1.27 1.27)
						(thickness 0.15)
					)
					(justify left bottom)
					(hide yes)
				)
			)
			(property "MPN" "DF2S30FS"
				(at 21.59 -5.08 0)
				(effects
					(font
						(size 1.27 1.27)
						(thickness 0.15)
					)
					(justify left bottom)
				)
			)
			(property "Author" "Antmicro"
				(at 21.59 -17.78 0)
				(effects
					(font
						(size 1.27 1.27)
						(thickness 0.15)
					)
					(justify left bottom)
					(hide yes)
				)
			)
			(property "License" "Apache-2.0"
				(at 21.59 -20.32 0)
				(effects
					(font
						(size 1.27 1.27)
						(thickness 0.15)
					)
					(justify left bottom)
					(hide yes)
				)
			)
			(property "ki_keywords" "DIODE, SEMICONDUCTOR, TVS, ESD"
				(at 0 0 0)
				(effects
					(font
						(size 1.27 1.27)
					)
					(hide yes)
				)
			)
			(symbol "DF2S30FS_SOD_0_1"
				(polyline
					(pts
						(xy 1.905 0) (xy 0.635 0)
					)
					(stroke
						(width 0)
						(type default)
					)
					(fill
						(type none)
					)
				)
				(polyline
					(pts
						(xy 4.445 0) (xy 3.175 0)
					)
					(stroke
						(width 0)
						(type default)
					)
					(fill
						(type none)
					)
				)
			)
			(symbol "DF2S30FS_SOD_1_1"
				(polyline
					(pts
						(xy 1.778 1.016) (xy 1.397 1.016)
					)
					(stroke
						(width 0.254)
						(type default)
					)
					(fill
						(type none)
					)
				)
				(polyline
					(pts
						(xy 1.778 1.016) (xy 1.778 -1.016)
					)
					(stroke
						(width 0.254)
						(type default)
					)
					(fill
						(type none)
					)
				)
				(polyline
					(pts
						(xy 2.159 -1.016) (xy 1.778 -1.016)
					)
					(stroke
						(width 0.254)
						(type default)
					)
					(fill
						(type none)
					)
				)
				(polyline
					(pts
						(xy 3.302 1.016) (xy 3.302 -1.016) (xy 1.778 0) (xy 3.302 1.016)
					)
					(stroke
						(width 0.254)
						(type default)
					)
					(fill
						(type outline)
					)
				)
				(pin passive line
					(at 0 0 0)
					(length 0.635)
					(name "C"
						(effects
							(font
								(size 1.27 1.27)
							)
						)
					)
					(number "1"
						(effects
							(font
								(size 1.27 1.27)
							)
						)
					)
				)
				(pin passive line
					(at 5.08 0 180)
					(length 0.635)
					(name "A"
						(effects
							(font
								(size 1.27 1.27)
							)
						)
					)
					(number "2"
						(effects
							(font
								(size 1.27 1.27)
							)
						)
					)
				)
			)
		)
	(symbol "antmicroTVSDiodes:ESD9X5.0ST5G"
			(pin_numbers hide)
			(pin_names hide)
			(exclude_from_sim no)
			(in_bom yes)
			(on_board yes)
			(property "Reference" "D"
				(at 21.59 -2.54 0)
				(effects
					(font
						(size 1.27 1.27)
						(thickness 0.15)
					)
					(justify left bottom)
				)
			)
			(property "Value" "ESD9X5.0ST5G"
				(at 21.59 -15.24 0)
				(effects
					(font
						(size 1.27 1.27)
						(thickness 0.15)
					)
					(justify left bottom)
					(hide yes)
				)
			)
			(property "Footprint" "antmicro-footprints:SOD-923"
				(at 21.59 -7.62 0)
				(effects
					(font
						(size 1.27 1.27)
						(thickness 0.15)
					)
					(justify left bottom)
					(hide yes)
				)
			)
			(property "Datasheet" "https://www.onsemi.com/pdf/datasheet/esd9x3.3st5g-d.pdf"
				(at 21.59 -10.16 0)
				(effects
					(font
						(size 1.27 1.27)
						(thickness 0.15)
					)
					(justify left bottom)
					(hide yes)
				)
			)
			(property "Description" "Unidirectional TVS, 30 kV,  SOD-923, 5 V, 65 pF"
				(at 0 0 0)
				(effects
					(font
						(size 1.27 1.27)
					)
					(hide yes)
				)
			)
			(property "Manufacturer" "ON Semiconductor"
				(at 21.59 -12.7 0)
				(effects
					(font
						(size 1.27 1.27)
						(thickness 0.15)
					)
					(justify left bottom)
					(hide yes)
				)
			)
			(property "MPN" "ESD9X5.0ST5G"
				(at 21.59 -5.08 0)
				(effects
					(font
						(size 1.27 1.27)
						(thickness 0.15)
					)
					(justify left bottom)
				)
			)
			(property "Author" "Antmicro"
				(at 21.59 -17.78 0)
				(effects
					(font
						(size 1.27 1.27)
						(thickness 0.15)
					)
					(justify left bottom)
					(hide yes)
				)
			)
			(property "License" "Apache-2.0"
				(at 21.59 -20.32 0)
				(effects
					(font
						(size 1.27 1.27)
						(thickness 0.15)
					)
					(justify left bottom)
					(hide yes)
				)
			)
			(property "ki_keywords" "DIODE, SEMICONDUCTOR, TVS, ESD"
				(at 0 0 0)
				(effects
					(font
						(size 1.27 1.27)
					)
					(hide yes)
				)
			)
			(symbol "ESD9X5.0ST5G_0_1"
				(polyline
					(pts
						(xy 1.905 0) (xy 0.635 0)
					)
					(stroke
						(width 0)
						(type default)
					)
					(fill
						(type none)
					)
				)
				(polyline
					(pts
						(xy 4.445 0) (xy 3.175 0)
					)
					(stroke
						(width 0)
						(type default)
					)
					(fill
						(type none)
					)
				)
			)
			(symbol "ESD9X5.0ST5G_1_1"
				(polyline
					(pts
						(xy 1.778 1.016) (xy 1.397 1.016)
					)
					(stroke
						(width 0.254)
						(type default)
					)
					(fill
						(type none)
					)
				)
				(polyline
					(pts
						(xy 1.778 1.016) (xy 1.778 -1.016)
					)
					(stroke
						(width 0.254)
						(type default)
					)
					(fill
						(type none)
					)
				)
				(polyline
					(pts
						(xy 2.159 -1.016) (xy 1.778 -1.016)
					)
					(stroke
						(width 0.254)
						(type default)
					)
					(fill
						(type none)
					)
				)
				(polyline
					(pts
						(xy 3.302 1.016) (xy 3.302 -1.016) (xy 1.778 0) (xy 3.302 1.016)
					)
					(stroke
						(width 0.254)
						(type default)
					)
					(fill
						(type outline)
					)
				)
				(pin passive line
					(at 0 0 0)
					(length 0.635)
					(name "C"
						(effects
							(font
								(size 1.27 1.27)
							)
						)
					)
					(number "1"
						(effects
							(font
								(size 1.27 1.27)
							)
						)
					)
				)
				(pin passive line
					(at 5.08 0 180)
					(length 0.635)
					(name "A"
						(effects
							(font
								(size 1.27 1.27)
							)
						)
					)
					(number "2"
						(effects
							(font
								(size 1.27 1.27)
							)
						)
					)
				)
			)
		)
	(symbol "antmicroTVSDiodes:PTVS58VS1UR,115"
			(pin_numbers hide)
			(pin_names hide)
			(exclude_from_sim no)
			(in_bom yes)
			(on_board yes)
			(property "Reference" "D"
				(at 21.59 -5.08 0)
				(effects
					(font
						(size 1.27 1.27)
						(thickness 0.15)
					)
					(justify left bottom)
				)
			)
			(property "Value" "PTVS58VS1UR,115"
				(at 21.59 -15.24 0)
				(effects
					(font
						(size 1.27 1.27)
						(thickness 0.15)
					)
					(justify left bottom)
					(hide yes)
				)
			)
			(property "Footprint" "antmicro-footprints:D_SOD-123F"
				(at 21.59 -10.16 0)
				(effects
					(font
						(size 1.27 1.27)
						(thickness 0.15)
					)
					(justify left bottom)
					(hide yes)
				)
			)
			(property "Datasheet" "https://assets.nexperia.com/documents/data-sheet/PTVSXS1UR_SER.pdf"
				(at 21.59 -12.7 0)
				(effects
					(font
						(size 1.27 1.27)
						(thickness 0.15)
					)
					(justify left bottom)
					(hide yes)
				)
			)
			(property "Description" "Unidirectional TVS, 8 kV,  SOD-123F, 58 V"
				(at 0 0 0)
				(effects
					(font
						(size 1.27 1.27)
					)
					(hide yes)
				)
			)
			(property "MPN" "PTVS58VS1UR,115"
				(at 21.59 -7.62 0)
				(effects
					(font
						(size 1.27 1.27)
						(thickness 0.15)
					)
					(justify left bottom)
				)
			)
			(property "Manufacturer" "Nexperia"
				(at 21.59 -17.78 0)
				(effects
					(font
						(size 1.27 1.27)
						(thickness 0.15)
					)
					(justify left bottom)
					(hide yes)
				)
			)
			(property "Author" "Antmicro"
				(at 21.59 -20.32 0)
				(effects
					(font
						(size 1.27 1.27)
						(thickness 0.15)
					)
					(justify left bottom)
					(hide yes)
				)
			)
			(property "License" "Apache-2.0"
				(at 21.59 -22.86 0)
				(effects
					(font
						(size 1.27 1.27)
						(thickness 0.15)
					)
					(justify left bottom)
					(hide yes)
				)
			)
			(property "ki_keywords" "DIODE, SEMICONDUCTOR, TVS, ESD"
				(at 0 0 0)
				(effects
					(font
						(size 1.27 1.27)
					)
					(hide yes)
				)
			)
			(symbol "PTVS58VS1UR,115_0_1"
				(polyline
					(pts
						(xy 1.905 0) (xy 0.635 0)
					)
					(stroke
						(width 0)
						(type default)
					)
					(fill
						(type none)
					)
				)
				(polyline
					(pts
						(xy 4.445 0) (xy 3.175 0)
					)
					(stroke
						(width 0)
						(type default)
					)
					(fill
						(type none)
					)
				)
			)
			(symbol "PTVS58VS1UR,115_1_1"
				(polyline
					(pts
						(xy 1.778 1.016) (xy 1.397 1.016)
					)
					(stroke
						(width 0.254)
						(type default)
					)
					(fill
						(type none)
					)
				)
				(polyline
					(pts
						(xy 1.778 1.016) (xy 1.778 -1.016)
					)
					(stroke
						(width 0.254)
						(type default)
					)
					(fill
						(type none)
					)
				)
				(polyline
					(pts
						(xy 2.159 -1.016) (xy 1.778 -1.016)
					)
					(stroke
						(width 0.254)
						(type default)
					)
					(fill
						(type none)
					)
				)
				(polyline
					(pts
						(xy 3.302 1.016) (xy 3.302 -1.016) (xy 1.778 0) (xy 3.302 1.016)
					)
					(stroke
						(width 0.254)
						(type default)
					)
					(fill
						(type outline)
					)
				)
				(pin passive line
					(at 0 0 0)
					(length 0.635)
					(name "C"
						(effects
							(font
								(size 1.27 1.27)
							)
						)
					)
					(number "1"
						(effects
							(font
								(size 1.27 1.27)
							)
						)
					)
				)
				(pin passive line
					(at 5.08 0 180)
					(length 0.635)
					(name "A"
						(effects
							(font
								(size 1.27 1.27)
							)
						)
					)
					(number "2"
						(effects
							(font
								(size 1.27 1.27)
							)
						)
					)
				)
			)
		)
	(symbol "antmicroTVSDiodes:TPD1E0B04_XDFN-2"
			(pin_numbers hide)
			(pin_names hide)
			(exclude_from_sim no)
			(in_bom yes)
			(on_board yes)
			(property "Reference" "D"
				(at 15.24 0 0)
				(effects
					(font
						(size 1.27 1.27)
						(thickness 0.15)
					)
					(justify left bottom)
				)
			)
			(property "Value" "TPD1E0B04_XDFN-2"
				(at 15.24 -10.16 0)
				(effects
					(font
						(size 1.27 1.27)
						(thickness 0.15)
					)
					(justify left bottom)
					(hide yes)
				)
			)
			(property "Footprint" "antmicro-footprints:XDFN-2_1x0.60mm"
				(at 15.24 -5.08 0)
				(effects
					(font
						(size 1.27 1.27)
						(thickness 0.15)
					)
					(justify left bottom)
					(hide yes)
				)
			)
			(property "Datasheet" "https://www.ti.com/general/docs/suppproductinfo.tsp?distId=26&gotoUrl=https://www.ti.com/lit/gpn/tpd1e0b04"
				(at 15.24 -7.62 0)
				(effects
					(font
						(size 1.27 1.27)
						(thickness 0.15)
					)
					(justify left bottom)
					(hide yes)
				)
			)
			(property "Description" "Bidirectional TVS, 8 kV,  XDFN-2, 3.6 V, 0.18 pF"
				(at 0 0 0)
				(effects
					(font
						(size 1.27 1.27)
					)
					(hide yes)
				)
			)
			(property "MPN" "TPD1E0B04DPYR"
				(at 15.24 -2.54 0)
				(effects
					(font
						(size 1.27 1.27)
						(thickness 0.15)
					)
					(justify left bottom)
				)
			)
			(property "Manufacturer" "Texas Instruments"
				(at 15.24 -12.7 0)
				(effects
					(font
						(size 1.27 1.27)
						(thickness 0.15)
					)
					(justify left bottom)
					(hide yes)
				)
			)
			(property "Author" "Antmicro"
				(at 15.24 -15.24 0)
				(effects
					(font
						(size 1.27 1.27)
						(thickness 0.15)
					)
					(justify left bottom)
					(hide yes)
				)
			)
			(property "License" "Apache-2.0"
				(at 15.24 -17.78 0)
				(effects
					(font
						(size 1.27 1.27)
						(thickness 0.15)
					)
					(justify left bottom)
					(hide yes)
				)
			)
			(property "ki_keywords" "DIODE, SEMICONDUCTOR, TVS, ESD"
				(at 0 0 0)
				(effects
					(font
						(size 1.27 1.27)
					)
					(hide yes)
				)
			)
			(symbol "TPD1E0B04_XDFN-2_0_0"
				(text ""
					(at 7.62 -1.27 0)
					(effects
						(font
							(size 1.27 1.27)
						)
					)
				)
			)
			(symbol "TPD1E0B04_XDFN-2_0_1"
				(polyline
					(pts
						(xy 0.635 0) (xy 4.445 0)
					)
					(stroke
						(width 0)
						(type default)
					)
					(fill
						(type none)
					)
				)
			)
			(symbol "TPD1E0B04_XDFN-2_1_1"
				(polyline
					(pts
						(xy 2.54 1.016) (xy 2.159 1.016)
					)
					(stroke
						(width 0.254)
						(type default)
					)
					(fill
						(type none)
					)
				)
				(polyline
					(pts
						(xy 2.54 1.016) (xy 2.54 -1.016)
					)
					(stroke
						(width 0.254)
						(type default)
					)
					(fill
						(type none)
					)
				)
				(polyline
					(pts
						(xy 2.921 -1.016) (xy 2.54 -1.016)
					)
					(stroke
						(width 0.254)
						(type default)
					)
					(fill
						(type none)
					)
				)
				(polyline
					(pts
						(xy 1.016 -1.016) (xy 1.016 1.016) (xy 2.54 0) (xy 1.016 -1.016)
					)
					(stroke
						(width 0.254)
						(type default)
					)
					(fill
						(type outline)
					)
				)
				(polyline
					(pts
						(xy 4.064 1.016) (xy 4.064 -1.016) (xy 2.54 0) (xy 4.064 1.016)
					)
					(stroke
						(width 0.254)
						(type default)
					)
					(fill
						(type outline)
					)
				)
				(pin passive line
					(at 0 0 0)
					(length 0.635)
					(name "C"
						(effects
							(font
								(size 1.27 1.27)
							)
						)
					)
					(number "1"
						(effects
							(font
								(size 1.27 1.27)
							)
						)
					)
				)
				(pin passive line
					(at 5.08 0 180)
					(length 0.635)
					(name "A"
						(effects
							(font
								(size 1.27 1.27)
							)
						)
					)
					(number "2"
						(effects
							(font
								(size 1.27 1.27)
							)
						)
					)
				)
			)
		)
	(symbol "antmicroTVSDiodes:TPD4E02B04DQA"
			(pin_names hide)
			(exclude_from_sim no)
			(in_bom yes)
			(on_board yes)
			(property "Reference" "U"
				(at 7.62 3.81 0)
				(effects
					(font
						(size 1.27 1.27)
					)
					(justify left)
				)
			)
			(property "Value" "TPD4E02B04DQA_2"
				(at 7.62 1.905 0)
				(effects
					(font
						(size 1.27 1.27)
					)
					(justify left)
				)
			)
			(property "Footprint" "antmicro-footprints:USON-10_2.5x1mm_P0.5mm"
				(at -12.7 -22.86 0)
				(effects
					(font
						(size 1.27 1.27)
					)
					(justify left)
					(hide yes)
				)
			)
			(property "Datasheet" "http://www.ti.com/lit/ds/symlink/tpd4e02b04.pdf"
				(at 0 -20.32 0)
				(effects
					(font
						(size 1.27 1.27)
					)
					(hide yes)
				)
			)
			(property "Description" "4-Channel ESD Protection Diode for USB Type-C and HDMI 2.0, USON-10"
				(at 0 0 0)
				(effects
					(font
						(size 1.27 1.27)
					)
					(hide yes)
				)
			)
			(property "MPN" "TPD4E02B04DQAR"
				(at 0 -15.24 0)
				(effects
					(font
						(size 1.27 1.27)
					)
					(hide yes)
				)
			)
			(property "Manufacturer" "Texas Instruments"
				(at 0 -17.78 0)
				(effects
					(font
						(size 1.27 1.27)
					)
					(hide yes)
				)
			)
			(property "ki_keywords" "ESD protection USB HDMI"
				(at 0 0 0)
				(effects
					(font
						(size 1.27 1.27)
					)
					(hide yes)
				)
			)
			(property "ki_fp_filters" "USON*2.5x1.0mm*P0.5mm*"
				(at 0 0 0)
				(effects
					(font
						(size 1.27 1.27)
					)
					(hide yes)
				)
			)
			(symbol "TPD4E02B04DQA_0_0"
				(pin passive line
					(at 0 -5.08 90)
					(length 2.54)
					(name "G"
						(effects
							(font
								(size 1.27 1.27)
							)
						)
					)
					(number "3"
						(effects
							(font
								(size 1.27 1.27)
							)
						)
					)
				)
			)
			(symbol "TPD4E02B04DQA_0_1"
				(rectangle
					(start -6.35 5.08)
					(end 6.35 -2.54)
					(stroke
						(width 0.254)
						(type default)
					)
					(fill
						(type background)
					)
				)
				(circle
					(center 0 -1.27)
					(radius 0.254)
					(stroke
						(width 0)
						(type default)
					)
					(fill
						(type outline)
					)
				)
				(polyline
					(pts
						(xy -2.54 5.08) (xy -2.54 -1.27)
					)
					(stroke
						(width 0)
						(type default)
					)
					(fill
						(type none)
					)
				)
				(polyline
					(pts
						(xy 0 -1.27) (xy 0 -2.54)
					)
					(stroke
						(width 0)
						(type default)
					)
					(fill
						(type none)
					)
				)
				(polyline
					(pts
						(xy 2.54 5.08) (xy 2.54 -1.27)
					)
					(stroke
						(width 0)
						(type default)
					)
					(fill
						(type none)
					)
				)
				(polyline
					(pts
						(xy -5.08 5.08) (xy -5.08 -1.27) (xy 5.08 -1.27) (xy 5.08 5.08)
					)
					(stroke
						(width 0)
						(type default)
					)
					(fill
						(type none)
					)
				)
				(polyline
					(pts
						(xy -4.445 0) (xy -5.715 0) (xy -5.08 1.27) (xy -4.445 0)
					)
					(stroke
						(width 0)
						(type default)
					)
					(fill
						(type none)
					)
				)
				(polyline
					(pts
						(xy -3.175 1.524) (xy -2.921 1.27) (xy -2.159 1.27) (xy -1.905 1.016)
					)
					(stroke
						(width 0)
						(type default)
					)
					(fill
						(type none)
					)
				)
				(polyline
					(pts
						(xy -2.54 1.27) (xy -1.905 0) (xy -3.175 0) (xy -2.54 1.27)
					)
					(stroke
						(width 0)
						(type default)
					)
					(fill
						(type none)
					)
				)
				(polyline
					(pts
						(xy 2.54 1.27) (xy 1.905 0) (xy 3.175 0) (xy 2.54 1.27)
					)
					(stroke
						(width 0)
						(type default)
					)
					(fill
						(type none)
					)
				)
				(polyline
					(pts
						(xy 5.08 1.27) (xy 4.445 0) (xy 5.715 0) (xy 5.08 1.27)
					)
					(stroke
						(width 0)
						(type default)
					)
					(fill
						(type none)
					)
				)
				(circle
					(center 2.54 -1.27)
					(radius 0.254)
					(stroke
						(width 0)
						(type default)
					)
					(fill
						(type outline)
					)
				)
			)
			(symbol "TPD4E02B04DQA_1_1"
				(circle
					(center -2.54 -1.27)
					(radius 0.254)
					(stroke
						(width 0)
						(type default)
					)
					(fill
						(type outline)
					)
				)
				(polyline
					(pts
						(xy -5.715 1.524) (xy -5.461 1.27) (xy -4.699 1.27) (xy -4.445 1.016)
					)
					(stroke
						(width 0)
						(type default)
					)
					(fill
						(type none)
					)
				)
				(polyline
					(pts
						(xy -5.08 1.27) (xy -5.715 2.54) (xy -4.445 2.54) (xy -5.08 1.27)
					)
					(stroke
						(width 0)
						(type default)
					)
					(fill
						(type none)
					)
				)
				(polyline
					(pts
						(xy -2.54 1.27) (xy -3.175 2.54) (xy -1.905 2.54) (xy -2.54 1.27)
					)
					(stroke
						(width 0)
						(type default)
					)
					(fill
						(type none)
					)
				)
				(polyline
					(pts
						(xy 1.905 1.524) (xy 2.159 1.27) (xy 2.921 1.27) (xy 3.175 1.016)
					)
					(stroke
						(width 0)
						(type default)
					)
					(fill
						(type none)
					)
				)
				(polyline
					(pts
						(xy 2.54 1.27) (xy 1.905 2.54) (xy 3.175 2.54) (xy 2.54 1.27)
					)
					(stroke
						(width 0)
						(type default)
					)
					(fill
						(type none)
					)
				)
				(polyline
					(pts
						(xy 4.445 1.524) (xy 4.699 1.27) (xy 5.461 1.27) (xy 5.715 1.016)
					)
					(stroke
						(width 0)
						(type default)
					)
					(fill
						(type none)
					)
				)
				(polyline
					(pts
						(xy 5.08 1.27) (xy 4.445 2.54) (xy 5.715 2.54) (xy 5.08 1.27)
					)
					(stroke
						(width 0)
						(type default)
					)
					(fill
						(type none)
					)
				)
				(pin passive line
					(at -5.08 7.62 270)
					(length 2.54)
					(name "IO1"
						(effects
							(font
								(size 1.27 1.27)
							)
						)
					)
					(number "1"
						(effects
							(font
								(size 1.27 1.27)
							)
						)
					)
				)
				(pin passive line
					(at -5.08 7.62 270)
					(length 2.54) hide
					(name "NC"
						(effects
							(font
								(size 1.27 1.27)
							)
						)
					)
					(number "10"
						(effects
							(font
								(size 1.27 1.27)
							)
						)
					)
				)
				(pin passive line
					(at -2.54 7.62 270)
					(length 2.54)
					(name "IO2"
						(effects
							(font
								(size 1.27 1.27)
							)
						)
					)
					(number "2"
						(effects
							(font
								(size 1.27 1.27)
							)
						)
					)
				)
				(pin passive line
					(at 2.54 7.62 270)
					(length 2.54)
					(name "IO3"
						(effects
							(font
								(size 1.27 1.27)
							)
						)
					)
					(number "4"
						(effects
							(font
								(size 1.27 1.27)
							)
						)
					)
				)
				(pin passive line
					(at 5.08 7.62 270)
					(length 2.54)
					(name "IO4"
						(effects
							(font
								(size 1.27 1.27)
							)
						)
					)
					(number "5"
						(effects
							(font
								(size 1.27 1.27)
							)
						)
					)
				)
				(pin passive line
					(at 5.08 7.62 270)
					(length 2.54) hide
					(name "NC"
						(effects
							(font
								(size 1.27 1.27)
							)
						)
					)
					(number "6"
						(effects
							(font
								(size 1.27 1.27)
							)
						)
					)
				)
				(pin passive line
					(at 2.54 7.62 270)
					(length 2.54) hide
					(name "NC"
						(effects
							(font
								(size 1.27 1.27)
							)
						)
					)
					(number "7"
						(effects
							(font
								(size 1.27 1.27)
							)
						)
					)
				)
				(pin passive line
					(at 0 -5.08 90)
					(length 2.54) hide
					(name "G"
						(effects
							(font
								(size 1.27 1.27)
							)
						)
					)
					(number "8"
						(effects
							(font
								(size 1.27 1.27)
							)
						)
					)
				)
				(pin passive line
					(at -2.54 7.62 270)
					(length 2.54) hide
					(name "NC"
						(effects
							(font
								(size 1.27 1.27)
							)
						)
					)
					(number "9"
						(effects
							(font
								(size 1.27 1.27)
							)
						)
					)
				)
			)
		)
	(symbol "antmicroTVSDiodes:TPD4E05U06QDQARQ1"
			(exclude_from_sim no)
			(in_bom yes)
			(on_board yes)
			(property "Reference" "U"
				(at 24.13 0 0)
				(effects
					(font
						(size 1.27 1.27)
						(thickness 0.15)
					)
					(justify left bottom)
				)
			)
			(property "Value" "TPD4E05U06QDQARQ1"
				(at 24.13 -10.16 0)
				(effects
					(font
						(size 1.27 1.27)
						(thickness 0.15)
					)
					(justify left bottom)
					(hide yes)
				)
			)
			(property "Footprint" "antmicro-footprints:USON-10_2.5x1mm_P0.5mm"
				(at 24.13 -5.08 0)
				(effects
					(font
						(size 1.27 1.27)
						(thickness 0.15)
					)
					(justify left bottom)
					(hide yes)
				)
			)
			(property "Datasheet" "https://www.ti.com/lit/ds/symlink/tpd4e05u06-q1.pdf?HQS=dis-mous-null-mousermode-dsf-pf-null-wwe&ts=1663591265741&ref_url=https%253A%252F%252Fwww.mouser.com%252F"
				(at 24.13 -7.62 0)
				(effects
					(font
						(size 1.27 1.27)
						(thickness 0.15)
					)
					(justify left bottom)
					(hide yes)
				)
			)
			(property "Description" "TVS diode array, 12 kV, USON-10, 5.5 V, 0.5 pF"
				(at 0 0 0)
				(effects
					(font
						(size 1.27 1.27)
					)
					(hide yes)
				)
			)
			(property "MPN" "TPD4E05U06QDQARQ1"
				(at 24.13 -2.54 0)
				(effects
					(font
						(size 1.27 1.27)
						(thickness 0.15)
					)
					(justify left bottom)
				)
			)
			(property "Manufacturer" "Texas Instruments"
				(at 24.13 -12.7 0)
				(effects
					(font
						(size 1.27 1.27)
						(thickness 0.15)
					)
					(justify left bottom)
					(hide yes)
				)
			)
			(property "Author" "Antmicro"
				(at 24.13 -15.24 0)
				(effects
					(font
						(size 1.27 1.27)
						(thickness 0.15)
					)
					(justify left bottom)
					(hide yes)
				)
			)
			(property "License" "Apache-2.0"
				(at 24.13 -17.78 0)
				(effects
					(font
						(size 1.27 1.27)
						(thickness 0.15)
					)
					(justify left bottom)
					(hide yes)
				)
			)
			(property "ki_keywords" "SMT, DIODE, SEMICONDUCTOR, TVS, ESD"
				(at 0 0 0)
				(effects
					(font
						(size 1.27 1.27)
					)
					(hide yes)
				)
			)
			(symbol "TPD4E05U06QDQARQ1_1_1"
				(polyline
					(pts
						(xy 2.54 -7.62) (xy 7.62 -7.62)
					)
					(stroke
						(width 0.254)
						(type default)
					)
					(fill
						(type background)
					)
				)
				(polyline
					(pts
						(xy 2.54 -5.08) (xy 7.62 -5.08)
					)
					(stroke
						(width 0.254)
						(type default)
					)
					(fill
						(type background)
					)
				)
				(polyline
					(pts
						(xy 2.54 -2.54) (xy 7.62 -2.54)
					)
					(stroke
						(width 0.254)
						(type default)
					)
					(fill
						(type background)
					)
				)
				(polyline
					(pts
						(xy 2.54 0) (xy 7.62 0)
					)
					(stroke
						(width 0.254)
						(type default)
					)
					(fill
						(type background)
					)
				)
				(polyline
					(pts
						(xy 7.62 -10.16) (xy 2.54 -10.16)
					)
					(stroke
						(width 0.254)
						(type default)
					)
					(fill
						(type background)
					)
				)
				(polyline
					(pts
						(xy 7.62 0) (xy 7.62 -10.16)
					)
					(stroke
						(width 0.254)
						(type default)
					)
					(fill
						(type background)
					)
				)
				(polyline
					(pts
						(xy 4.826 -8.255) (xy 5.08 -8.001) (xy 5.08 -7.239) (xy 5.334 -6.985)
					)
					(stroke
						(width 0.254)
						(type default)
					)
					(fill
						(type background)
					)
				)
				(polyline
					(pts
						(xy 4.826 -5.715) (xy 5.08 -5.461) (xy 5.08 -4.699) (xy 5.334 -4.445)
					)
					(stroke
						(width 0.254)
						(type default)
					)
					(fill
						(type background)
					)
				)
				(polyline
					(pts
						(xy 4.826 -3.175) (xy 5.08 -2.921) (xy 5.08 -2.159) (xy 5.334 -1.905)
					)
					(stroke
						(width 0.254)
						(type default)
					)
					(fill
						(type background)
					)
				)
				(polyline
					(pts
						(xy 4.826 -0.635) (xy 5.08 -0.381) (xy 5.08 0.381) (xy 5.334 0.635)
					)
					(stroke
						(width 0.254)
						(type default)
					)
					(fill
						(type background)
					)
				)
				(polyline
					(pts
						(xy 5.08 -7.62) (xy 3.81 -8.255) (xy 3.81 -6.985) (xy 5.08 -7.62)
					)
					(stroke
						(width 0.254)
						(type default)
					)
					(fill
						(type background)
					)
				)
				(polyline
					(pts
						(xy 5.08 -5.08) (xy 3.81 -5.715) (xy 3.81 -4.445) (xy 5.08 -5.08)
					)
					(stroke
						(width 0.254)
						(type default)
					)
					(fill
						(type background)
					)
				)
				(polyline
					(pts
						(xy 5.08 -5.08) (xy 6.35 -4.445) (xy 6.35 -5.715) (xy 5.08 -5.08)
					)
					(stroke
						(width 0.254)
						(type default)
					)
					(fill
						(type background)
					)
				)
				(polyline
					(pts
						(xy 5.08 -2.54) (xy 3.81 -3.175) (xy 3.81 -1.905) (xy 5.08 -2.54)
					)
					(stroke
						(width 0.254)
						(type default)
					)
					(fill
						(type background)
					)
				)
				(polyline
					(pts
						(xy 5.08 -2.54) (xy 6.35 -3.175) (xy 6.35 -1.905) (xy 5.08 -2.54)
					)
					(stroke
						(width 0.254)
						(type default)
					)
					(fill
						(type background)
					)
				)
				(polyline
					(pts
						(xy 5.08 0) (xy 3.81 -0.635) (xy 3.81 0.635) (xy 5.08 0)
					)
					(stroke
						(width 0.254)
						(type default)
					)
					(fill
						(type background)
					)
				)
				(polyline
					(pts
						(xy 5.08 0) (xy 6.35 -0.635) (xy 6.35 0.635) (xy 5.08 0)
					)
					(stroke
						(width 0.254)
						(type default)
					)
					(fill
						(type background)
					)
				)
				(polyline
					(pts
						(xy 6.35 -6.985) (xy 6.35 -8.255) (xy 5.08 -7.62) (xy 6.35 -6.985)
					)
					(stroke
						(width 0.254)
						(type default)
					)
					(fill
						(type background)
					)
				)
				(rectangle
					(start 2.54 2.54)
					(end 8.89 -11.43)
					(stroke
						(width 0.254)
						(type default)
					)
					(fill
						(type background)
					)
				)
				(circle
					(center 7.62 -7.62)
					(radius 0.254)
					(stroke
						(width 0.254)
						(type default)
					)
					(fill
						(type background)
					)
				)
				(circle
					(center 7.62 -5.08)
					(radius 0.254)
					(stroke
						(width 0.254)
						(type default)
					)
					(fill
						(type background)
					)
				)
				(circle
					(center 7.62 -5.08)
					(radius 0.254)
					(stroke
						(width 0.254)
						(type default)
					)
					(fill
						(type background)
					)
				)
				(circle
					(center 7.62 -2.54)
					(radius 0.254)
					(stroke
						(width 0.254)
						(type default)
					)
					(fill
						(type background)
					)
				)
				(pin passive line
					(at 0 0 0)
					(length 2.54)
					(name "~"
						(effects
							(font
								(size 1.27 1.27)
							)
						)
					)
					(number "1"
						(effects
							(font
								(size 1.27 1.27)
							)
						)
					)
				)
				(pin passive line
					(at 0 0 0)
					(length 2.54) hide
					(name "~"
						(effects
							(font
								(size 1.27 1.27)
							)
						)
					)
					(number "10"
						(effects
							(font
								(size 1.27 1.27)
							)
						)
					)
				)
				(pin passive line
					(at 0 -2.54 0)
					(length 2.54)
					(name "~"
						(effects
							(font
								(size 1.27 1.27)
							)
						)
					)
					(number "2"
						(effects
							(font
								(size 1.27 1.27)
							)
						)
					)
				)
				(pin power_in line
					(at 0 -10.16 0)
					(length 2.54)
					(name "~"
						(effects
							(font
								(size 1.27 1.27)
							)
						)
					)
					(number "3"
						(effects
							(font
								(size 1.27 1.27)
							)
						)
					)
				)
				(pin passive line
					(at 0 -5.08 0)
					(length 2.54)
					(name "~"
						(effects
							(font
								(size 1.27 1.27)
							)
						)
					)
					(number "4"
						(effects
							(font
								(size 1.27 1.27)
							)
						)
					)
				)
				(pin passive line
					(at 0 -7.62 0)
					(length 2.54)
					(name "~"
						(effects
							(font
								(size 1.27 1.27)
							)
						)
					)
					(number "5"
						(effects
							(font
								(size 1.27 1.27)
							)
						)
					)
				)
				(pin passive line
					(at 0 -7.62 0)
					(length 2.54) hide
					(name "~"
						(effects
							(font
								(size 1.27 1.27)
							)
						)
					)
					(number "6"
						(effects
							(font
								(size 1.27 1.27)
							)
						)
					)
				)
				(pin passive line
					(at 0 -5.08 0)
					(length 2.54) hide
					(name "~"
						(effects
							(font
								(size 1.27 1.27)
							)
						)
					)
					(number "7"
						(effects
							(font
								(size 1.27 1.27)
							)
						)
					)
				)
				(pin passive line
					(at 0 -10.16 0)
					(length 2.54) hide
					(name "~"
						(effects
							(font
								(size 1.27 1.27)
							)
						)
					)
					(number "8"
						(effects
							(font
								(size 1.27 1.27)
							)
						)
					)
				)
				(pin passive line
					(at 0 -2.54 0)
					(length 2.54) hide
					(name "~"
						(effects
							(font
								(size 1.27 1.27)
							)
						)
					)
					(number "9"
						(effects
							(font
								(size 1.27 1.27)
							)
						)
					)
				)
			)
		)
	(symbol "antmicroTestPoints:TP_0.75mm_SMD"
			(pin_names hide)
			(exclude_from_sim no)
			(in_bom no)
			(on_board yes)
			(property "Reference" "TP"
				(at 10.16 -1.27 0)
				(effects
					(font
						(size 1.27 1.27)
						(thickness 0.15)
					)
					(justify left bottom)
				)
			)
			(property "Value" "TP_0.75mm_SMD"
				(at 10.16 -3.81 0)
				(effects
					(font
						(size 1.27 1.27)
						(thickness 0.15)
					)
					(justify left bottom)
					(hide yes)
				)
			)
			(property "Footprint" "antmicro-footprints:TP_SMD_0.75mm"
				(at 10.16 -6.35 0)
				(effects
					(font
						(size 1.27 1.27)
						(thickness 0.15)
					)
					(justify left bottom)
					(hide yes)
				)
			)
			(property "Datasheet" ""
				(at 17.78 -12.7 0)
				(effects
					(font
						(size 1.27 1.27)
						(thickness 0.15)
					)
					(justify left bottom)
					(hide yes)
				)
			)
			(property "Description" "SMT test point"
				(at 0 0 0)
				(effects
					(font
						(size 1.27 1.27)
					)
					(hide yes)
				)
			)
			(property "MPN" ""
				(at 10.795 -11.43 0)
				(effects
					(font
						(size 1.27 1.27)
						(thickness 0.15)
					)
					(justify left bottom)
					(hide yes)
				)
			)
			(property "Manufacturer" ""
				(at 10.795 -6.35 0)
				(effects
					(font
						(size 1.27 1.27)
						(thickness 0.15)
					)
					(justify left bottom)
					(hide yes)
				)
			)
			(property "Author" "Antmicro"
				(at 10.16 -8.89 0)
				(effects
					(font
						(size 1.27 1.27)
						(thickness 0.15)
					)
					(justify left bottom)
					(hide yes)
				)
			)
			(property "License" "Apache-2.0"
				(at 10.16 -11.43 0)
				(effects
					(font
						(size 1.27 1.27)
						(thickness 0.15)
					)
					(justify left bottom)
					(hide yes)
				)
			)
			(property "ki_keywords" "TESTPOINT"
				(at 0 0 0)
				(effects
					(font
						(size 1.27 1.27)
					)
					(hide yes)
				)
			)
			(symbol "TP_0.75mm_SMD_1_1"
				(circle
					(center 3.175 0)
					(radius 0.635)
					(stroke
						(width 0.254)
						(type default)
					)
					(fill
						(type none)
					)
				)
				(pin passive line
					(at 0 0 0)
					(length 2.54)
					(name "1"
						(effects
							(font
								(size 1.27 1.27)
							)
						)
					)
					(number "1"
						(effects
							(font
								(size 1.27 1.27)
							)
						)
					)
				)
			)
		)
	(symbol "antmicroTransistorsBipolarArrays:BCM857BS-7-F"
			(exclude_from_sim no)
			(in_bom yes)
			(on_board yes)
			(property "Reference" "Q"
				(at 22.86 0 0)
				(effects
					(font
						(size 1.27 1.27)
						(thickness 0.15)
					)
					(justify left bottom)
				)
			)
			(property "Value" "BCM857BS-7-F"
				(at 22.86 -2.54 0)
				(effects
					(font
						(size 1.27 1.27)
						(thickness 0.15)
					)
					(justify left bottom)
					(hide yes)
				)
			)
			(property "Footprint" "antmicro-footprints:SOT-363"
				(at 22.86 -5.08 0)
				(effects
					(font
						(size 1.27 1.27)
						(thickness 0.15)
					)
					(justify left bottom)
					(hide yes)
				)
			)
			(property "Datasheet" "https://www.diodes.com/assets/Datasheets/BCM857BS.pdf"
				(at 22.86 -7.62 0)
				(effects
					(font
						(size 1.27 1.27)
						(thickness 0.15)
					)
					(justify left bottom)
					(hide yes)
				)
			)
			(property "Description" "Bipolar transistor array"
				(at 0 0 0)
				(effects
					(font
						(size 1.27 1.27)
					)
					(hide yes)
				)
			)
			(property "MPN" "BCM857BS-7-F"
				(at 22.86 -10.16 0)
				(effects
					(font
						(size 1.27 1.27)
						(thickness 0.15)
					)
					(justify left bottom)
				)
			)
			(property "Manufacturer" "Diodes Incorporated"
				(at 22.86 -12.7 0)
				(effects
					(font
						(size 1.27 1.27)
						(thickness 0.15)
					)
					(justify left bottom)
					(hide yes)
				)
			)
			(property "Author" "Antmicro"
				(at 22.86 -15.24 0)
				(effects
					(font
						(size 1.27 1.27)
						(thickness 0.15)
					)
					(justify left bottom)
					(hide yes)
				)
			)
			(property "License" "Apache-2.0"
				(at 22.86 -17.78 0)
				(effects
					(font
						(size 1.27 1.27)
						(thickness 0.15)
					)
					(justify left bottom)
					(hide yes)
				)
			)
			(property "ki_keywords" "SMT, TRANSISTOR, SEMICONDUCTOR, BIPOLAR"
				(at 0 0 0)
				(effects
					(font
						(size 1.27 1.27)
					)
					(hide yes)
				)
			)
			(symbol "BCM857BS-7-F_1_1"
				(polyline
					(pts
						(xy 2.54 0) (xy 4.445 0)
					)
					(stroke
						(width 0.254)
						(type default)
					)
					(fill
						(type none)
					)
				)
				(polyline
					(pts
						(xy 4.445 0.635) (xy 6.35 2.54)
					)
					(stroke
						(width 0.254)
						(type default)
					)
					(fill
						(type background)
					)
				)
				(polyline
					(pts
						(xy 6.35 -2.54) (xy 6.35 -3.81)
					)
					(stroke
						(width 0.254)
						(type default)
					)
					(fill
						(type none)
					)
				)
				(polyline
					(pts
						(xy 6.35 2.54) (xy 6.35 3.81)
					)
					(stroke
						(width 0.254)
						(type default)
					)
					(fill
						(type none)
					)
				)
				(polyline
					(pts
						(xy 11.43 -2.54) (xy 11.43 -3.81)
					)
					(stroke
						(width 0.254)
						(type default)
					)
					(fill
						(type none)
					)
				)
				(polyline
					(pts
						(xy 11.43 2.54) (xy 11.43 3.81)
					)
					(stroke
						(width 0.254)
						(type default)
					)
					(fill
						(type none)
					)
				)
				(polyline
					(pts
						(xy 13.335 0) (xy 15.24 0)
					)
					(stroke
						(width 0.254)
						(type default)
					)
					(fill
						(type none)
					)
				)
				(polyline
					(pts
						(xy 13.335 0.635) (xy 11.43 2.54)
					)
					(stroke
						(width 0.254)
						(type default)
					)
					(fill
						(type background)
					)
				)
				(polyline
					(pts
						(xy 4.445 -0.635) (xy 6.35 -2.54) (xy 6.35 -2.54)
					)
					(stroke
						(width 0.254)
						(type default)
					)
					(fill
						(type background)
					)
				)
				(polyline
					(pts
						(xy 4.445 -0.635) (xy 6.35 -2.54) (xy 6.35 -2.54)
					)
					(stroke
						(width 0.254)
						(type default)
					)
					(fill
						(type background)
					)
				)
				(polyline
					(pts
						(xy 4.445 1.905) (xy 4.445 -1.905) (xy 4.445 -1.905)
					)
					(stroke
						(width 0.254)
						(type default)
					)
					(fill
						(type background)
					)
				)
				(polyline
					(pts
						(xy 13.335 -0.635) (xy 11.43 -2.54) (xy 11.43 -2.54)
					)
					(stroke
						(width 0.254)
						(type default)
					)
					(fill
						(type background)
					)
				)
				(polyline
					(pts
						(xy 13.335 -0.635) (xy 11.43 -2.54) (xy 11.43 -2.54)
					)
					(stroke
						(width 0.254)
						(type default)
					)
					(fill
						(type background)
					)
				)
				(polyline
					(pts
						(xy 13.335 1.905) (xy 13.335 -1.905) (xy 13.335 -1.905)
					)
					(stroke
						(width 0.254)
						(type default)
					)
					(fill
						(type background)
					)
				)
				(polyline
					(pts
						(xy 5.207 -1.8796) (xy 5.715 -1.3716) (xy 4.699 -0.8636) (xy 5.207 -1.8796) (xy 5.207 -1.8796)
					)
					(stroke
						(width 0.254)
						(type default)
					)
					(fill
						(type outline)
					)
				)
				(polyline
					(pts
						(xy 5.207 -1.8796) (xy 5.715 -1.3716) (xy 4.699 -0.8636) (xy 5.207 -1.8796) (xy 5.207 -1.8796)
					)
					(stroke
						(width 0.254)
						(type default)
					)
					(fill
						(type background)
					)
				)
				(polyline
					(pts
						(xy 5.207 -1.8796) (xy 5.715 -1.3716) (xy 4.699 -0.8636) (xy 5.207 -1.8796) (xy 5.207 -1.8796)
					)
					(stroke
						(width 0.254)
						(type default)
					)
					(fill
						(type background)
					)
				)
				(polyline
					(pts
						(xy 5.207 -1.8796) (xy 5.715 -1.3716) (xy 4.699 -0.8636) (xy 5.207 -1.8796) (xy 5.207 -1.8796)
					)
					(stroke
						(width 0.254)
						(type default)
					)
					(fill
						(type background)
					)
				)
				(polyline
					(pts
						(xy 12.573 -1.8796) (xy 12.065 -1.3716) (xy 13.081 -0.8636) (xy 12.573 -1.8796) (xy 12.573 -1.8796)
					)
					(stroke
						(width 0.254)
						(type default)
					)
					(fill
						(type outline)
					)
				)
				(polyline
					(pts
						(xy 12.573 -1.8796) (xy 12.065 -1.3716) (xy 13.081 -0.8636) (xy 12.573 -1.8796) (xy 12.573 -1.8796)
					)
					(stroke
						(width 0.254)
						(type default)
					)
					(fill
						(type background)
					)
				)
				(polyline
					(pts
						(xy 12.573 -1.8796) (xy 12.065 -1.3716) (xy 13.081 -0.8636) (xy 12.573 -1.8796) (xy 12.573 -1.8796)
					)
					(stroke
						(width 0.254)
						(type default)
					)
					(fill
						(type background)
					)
				)
				(polyline
					(pts
						(xy 12.573 -1.8796) (xy 12.065 -1.3716) (xy 13.081 -0.8636) (xy 12.573 -1.8796) (xy 12.573 -1.8796)
					)
					(stroke
						(width 0.254)
						(type default)
					)
					(fill
						(type background)
					)
				)
				(rectangle
					(start 2.54 3.81)
					(end 15.24 -3.81)
					(stroke
						(width 0.254)
						(type default)
					)
					(fill
						(type background)
					)
				)
				(pin passive line
					(at 6.35 -6.35 90)
					(length 2.54)
					(name "~"
						(effects
							(font
								(size 1.27 1.27)
							)
						)
					)
					(number "1"
						(effects
							(font
								(size 1.27 1.27)
							)
						)
					)
				)
				(pin passive line
					(at 0 0 0)
					(length 2.54)
					(name "~"
						(effects
							(font
								(size 1.27 1.27)
							)
						)
					)
					(number "2"
						(effects
							(font
								(size 1.27 1.27)
							)
						)
					)
				)
				(pin passive line
					(at 11.43 6.35 270)
					(length 2.54)
					(name "~"
						(effects
							(font
								(size 1.27 1.27)
							)
						)
					)
					(number "3"
						(effects
							(font
								(size 1.27 1.27)
							)
						)
					)
				)
				(pin passive line
					(at 11.43 -6.35 90)
					(length 2.54)
					(name "~"
						(effects
							(font
								(size 1.27 1.27)
							)
						)
					)
					(number "4"
						(effects
							(font
								(size 1.27 1.27)
							)
						)
					)
				)
				(pin passive line
					(at 17.78 0 180)
					(length 2.54)
					(name "~"
						(effects
							(font
								(size 1.27 1.27)
							)
						)
					)
					(number "5"
						(effects
							(font
								(size 1.27 1.27)
							)
						)
					)
				)
				(pin passive line
					(at 6.35 6.35 270)
					(length 2.54)
					(name "~"
						(effects
							(font
								(size 1.27 1.27)
							)
						)
					)
					(number "6"
						(effects
							(font
								(size 1.27 1.27)
							)
						)
					)
				)
			)
		)
	(symbol "antmicroTransistorsFETsMOSFETsSingle:PJE138K"
			(pin_names
				(offset 0)
			)
			(exclude_from_sim no)
			(in_bom yes)
			(on_board yes)
			(property "Reference" "Q"
				(at 22.86 -6.35 0)
				(effects
					(font
						(size 1.27 1.27)
						(thickness 0.15)
					)
					(justify left bottom)
				)
			)
			(property "Value" "PJE138K"
				(at 22.86 -8.89 0)
				(effects
					(font
						(size 1.27 1.27)
						(thickness 0.15)
					)
					(justify left bottom)
					(hide yes)
				)
			)
			(property "Footprint" "antmicro-footprints:SOT-523"
				(at 22.86 -11.43 0)
				(effects
					(font
						(size 1.27 1.27)
						(thickness 0.15)
					)
					(justify left bottom)
					(hide yes)
				)
			)
			(property "Datasheet" "https://www.mouser.com/datasheet/2/1057/PJE138K-1876698.pdf"
				(at 22.86 -13.97 0)
				(effects
					(font
						(size 1.27 1.27)
						(thickness 0.15)
					)
					(justify left bottom)
					(hide yes)
				)
			)
			(property "Description" "FET/MOSFET transistor"
				(at 0 0 0)
				(effects
					(font
						(size 1.27 1.27)
					)
					(hide yes)
				)
			)
			(property "MPN" "PJE138K_R1_00001"
				(at 22.86 -16.51 0)
				(effects
					(font
						(size 1.27 1.27)
						(thickness 0.15)
					)
					(justify left bottom)
				)
			)
			(property "Manufacturer" "PANJIT"
				(at 22.86 -19.05 0)
				(effects
					(font
						(size 1.27 1.27)
						(thickness 0.15)
					)
					(justify left bottom)
					(hide yes)
				)
			)
			(property "Author" "Antmicro"
				(at 22.86 -21.59 0)
				(effects
					(font
						(size 1.27 1.27)
						(thickness 0.15)
					)
					(justify left bottom)
					(hide yes)
				)
			)
			(property "License" "Apache-2.0"
				(at 22.86 -24.13 0)
				(effects
					(font
						(size 1.27 1.27)
						(thickness 0.15)
					)
					(justify left bottom)
					(hide yes)
				)
			)
			(property "ki_keywords" "SMT, TRANSISTOR, SEMICONDUCTOR, MOSFET, NMOS"
				(at 0 0 0)
				(effects
					(font
						(size 1.27 1.27)
					)
					(hide yes)
				)
			)
			(symbol "PJE138K_1_1"
				(polyline
					(pts
						(xy 3.81 1.143) (xy 3.81 0.635)
					)
					(stroke
						(width 0.254)
						(type default)
					)
					(fill
						(type background)
					)
				)
				(polyline
					(pts
						(xy 3.81 1.143) (xy 3.81 1.651)
					)
					(stroke
						(width 0.254)
						(type default)
					)
					(fill
						(type background)
					)
				)
				(polyline
					(pts
						(xy 3.81 2.54) (xy 3.81 2.032)
					)
					(stroke
						(width 0.254)
						(type default)
					)
					(fill
						(type background)
					)
				)
				(polyline
					(pts
						(xy 3.81 2.54) (xy 3.81 3.048)
					)
					(stroke
						(width 0.254)
						(type default)
					)
					(fill
						(type background)
					)
				)
				(polyline
					(pts
						(xy 3.81 4.445) (xy 3.81 3.429)
					)
					(stroke
						(width 0.254)
						(type default)
					)
					(fill
						(type background)
					)
				)
				(polyline
					(pts
						(xy 6.35 1.143) (xy 3.81 1.143)
					)
					(stroke
						(width 0.254)
						(type default)
					)
					(fill
						(type background)
					)
				)
				(polyline
					(pts
						(xy 7.874 3.048) (xy 6.858 3.048)
					)
					(stroke
						(width 0.254)
						(type default)
					)
					(fill
						(type background)
					)
				)
				(polyline
					(pts
						(xy 1.27 0) (xy 3.302 0) (xy 3.302 3.937)
					)
					(stroke
						(width 0.254)
						(type default)
					)
					(fill
						(type none)
					)
				)
				(polyline
					(pts
						(xy 6.35 -1.27) (xy 6.35 2.54) (xy 3.81 2.54)
					)
					(stroke
						(width 0.254)
						(type default)
					)
					(fill
						(type none)
					)
				)
				(polyline
					(pts
						(xy 6.35 6.35) (xy 6.35 3.937) (xy 3.81 3.937)
					)
					(stroke
						(width 0.254)
						(type default)
					)
					(fill
						(type none)
					)
				)
				(polyline
					(pts
						(xy 3.81 2.54) (xy 4.572 3.048) (xy 4.572 2.032) (xy 3.81 2.54)
					)
					(stroke
						(width 0.254)
						(type default)
					)
					(fill
						(type outline)
					)
				)
				(polyline
					(pts
						(xy 7.366 3.048) (xy 6.858 2.286) (xy 7.874 2.286) (xy 7.366 3.048)
					)
					(stroke
						(width 0.254)
						(type default)
					)
					(fill
						(type outline)
					)
				)
				(polyline
					(pts
						(xy 6.223 0.635) (xy 7.366 0.635) (xy 7.366 3.937) (xy 7.366 4.445) (xy 6.223 4.445)
					)
					(stroke
						(width 0.254)
						(type default)
					)
					(fill
						(type none)
					)
				)
				(circle
					(center 5.08 2.54)
					(radius 3.302)
					(stroke
						(width 0.254)
						(type default)
					)
					(fill
						(type background)
					)
				)
				(circle
					(center 6.35 0.635)
					(radius 0.127)
					(stroke
						(width 0.254)
						(type default)
					)
					(fill
						(type background)
					)
				)
				(circle
					(center 6.35 1.143)
					(radius 0.127)
					(stroke
						(width 0.254)
						(type default)
					)
					(fill
						(type background)
					)
				)
				(circle
					(center 6.35 4.445)
					(radius 0.127)
					(stroke
						(width 0.254)
						(type default)
					)
					(fill
						(type background)
					)
				)
				(pin passive line
					(at 0 0 0)
					(length 2.54)
					(name "G"
						(effects
							(font
								(size 1.27 1.27)
							)
						)
					)
					(number "1"
						(effects
							(font
								(size 1.27 1.27)
							)
						)
					)
				)
				(pin passive line
					(at 6.35 -2.54 90)
					(length 2.54)
					(name "S"
						(effects
							(font
								(size 1.27 1.27)
							)
						)
					)
					(number "2"
						(effects
							(font
								(size 1.27 1.27)
							)
						)
					)
				)
				(pin passive line
					(at 6.35 7.62 270)
					(length 2.54)
					(name "D"
						(effects
							(font
								(size 1.27 1.27)
							)
						)
					)
					(number "3"
						(effects
							(font
								(size 1.27 1.27)
							)
						)
					)
				)
			)
		)
	(symbol "antmicroTransistorsFETsMOSFETsSingle:SSM3J332R"
			(pin_names
				(offset 0)
			)
			(exclude_from_sim no)
			(in_bom yes)
			(on_board yes)
			(property "Reference" "Q"
				(at 13.97 0 0)
				(effects
					(font
						(size 1.27 1.27)
						(thickness 0.15)
					)
					(justify left bottom)
				)
			)
			(property "Value" "SSM3J332R"
				(at 13.97 -2.54 0)
				(effects
					(font
						(size 1.27 1.27)
						(thickness 0.15)
					)
					(justify left bottom)
					(hide yes)
				)
			)
			(property "Footprint" "antmicro-footprints:SOT-23-3"
				(at 13.97 -5.08 0)
				(effects
					(font
						(size 1.27 1.27)
						(thickness 0.15)
					)
					(justify left bottom)
					(hide yes)
				)
			)
			(property "Datasheet" "https://www.mouser.com/datasheet/2/408/SSM3J332R_datasheet_en_20181015-1150575.pdf"
				(at 13.97 -7.62 0)
				(effects
					(font
						(size 1.27 1.27)
						(thickness 0.15)
					)
					(justify left bottom)
					(hide yes)
				)
			)
			(property "Description" "Power MOSFET, P Channel, 30 V, 6 A, 0.036 ohm, SOT-23F, Surface Mount"
				(at 0 0 0)
				(effects
					(font
						(size 1.27 1.27)
					)
					(hide yes)
				)
			)
			(property "MPN" "SSM3J332R,LF"
				(at 13.97 -10.16 0)
				(effects
					(font
						(size 1.27 1.27)
						(thickness 0.15)
					)
					(justify left bottom)
				)
			)
			(property "Manufacturer" "Toshiba"
				(at 13.97 -12.7 0)
				(effects
					(font
						(size 1.27 1.27)
						(thickness 0.15)
					)
					(justify left bottom)
					(hide yes)
				)
			)
			(property "Author" "Antmicro"
				(at 13.97 -15.24 0)
				(effects
					(font
						(size 1.27 1.27)
						(thickness 0.15)
					)
					(justify left bottom)
					(hide yes)
				)
			)
			(property "License" "Apache-2.0"
				(at 13.97 -17.78 0)
				(effects
					(font
						(size 1.27 1.27)
						(thickness 0.15)
					)
					(justify left bottom)
					(hide yes)
				)
			)
			(property "ki_keywords" "SMT, TRANSISTOR, SEMICONDUCTOR, MOSFET, PMOS"
				(at 0 0 0)
				(effects
					(font
						(size 1.27 1.27)
					)
					(hide yes)
				)
			)
			(symbol "SSM3J332R_1_1"
				(polyline
					(pts
						(xy 5.08 1.143) (xy 5.08 0.635)
					)
					(stroke
						(width 0.254)
						(type default)
					)
					(fill
						(type background)
					)
				)
				(polyline
					(pts
						(xy 5.08 1.143) (xy 5.08 1.651)
					)
					(stroke
						(width 0.254)
						(type default)
					)
					(fill
						(type background)
					)
				)
				(polyline
					(pts
						(xy 5.08 2.54) (xy 5.08 2.032)
					)
					(stroke
						(width 0.254)
						(type default)
					)
					(fill
						(type background)
					)
				)
				(polyline
					(pts
						(xy 5.08 2.54) (xy 5.08 3.048)
					)
					(stroke
						(width 0.254)
						(type default)
					)
					(fill
						(type background)
					)
				)
				(polyline
					(pts
						(xy 5.08 4.445) (xy 5.08 3.429)
					)
					(stroke
						(width 0.254)
						(type default)
					)
					(fill
						(type background)
					)
				)
				(polyline
					(pts
						(xy 7.62 1.143) (xy 5.08 1.143)
					)
					(stroke
						(width 0.254)
						(type default)
					)
					(fill
						(type background)
					)
				)
				(polyline
					(pts
						(xy 9.144 2.3368) (xy 8.128 2.3368)
					)
					(stroke
						(width 0.254)
						(type default)
					)
					(fill
						(type background)
					)
				)
				(polyline
					(pts
						(xy 2.54 0) (xy 4.572 0) (xy 4.572 3.937)
					)
					(stroke
						(width 0.254)
						(type default)
					)
					(fill
						(type none)
					)
				)
				(polyline
					(pts
						(xy 7.62 -1.27) (xy 7.62 2.54) (xy 5.08 2.54)
					)
					(stroke
						(width 0.254)
						(type default)
					)
					(fill
						(type background)
					)
				)
				(polyline
					(pts
						(xy 7.62 6.35) (xy 7.62 3.937) (xy 5.08 3.937)
					)
					(stroke
						(width 0.254)
						(type default)
					)
					(fill
						(type background)
					)
				)
				(polyline
					(pts
						(xy 7.239 2.54) (xy 6.477 3.048) (xy 6.477 2.032) (xy 7.239 2.54)
					)
					(stroke
						(width 0.254)
						(type default)
					)
					(fill
						(type background)
					)
				)
				(polyline
					(pts
						(xy 8.636 2.286) (xy 9.144 3.048) (xy 8.128 3.048) (xy 8.636 2.286)
					)
					(stroke
						(width 0.254)
						(type default)
					)
					(fill
						(type background)
					)
				)
				(polyline
					(pts
						(xy 7.493 0.635) (xy 8.636 0.635) (xy 8.636 3.937) (xy 8.636 4.445) (xy 7.493 4.445)
					)
					(stroke
						(width 0.254)
						(type default)
					)
					(fill
						(type background)
					)
				)
				(circle
					(center 6.35 2.54)
					(radius 3.302)
					(stroke
						(width 0.254)
						(type default)
					)
					(fill
						(type background)
					)
				)
				(circle
					(center 7.62 0.635)
					(radius 0.127)
					(stroke
						(width 0.254)
						(type default)
					)
					(fill
						(type background)
					)
				)
				(circle
					(center 7.62 1.143)
					(radius 0.127)
					(stroke
						(width 0.254)
						(type default)
					)
					(fill
						(type background)
					)
				)
				(circle
					(center 7.62 4.445)
					(radius 0.127)
					(stroke
						(width 0.254)
						(type default)
					)
					(fill
						(type background)
					)
				)
				(pin bidirectional line
					(at 0 0 0)
					(length 2.54)
					(name "G"
						(effects
							(font
								(size 1.27 1.27)
							)
						)
					)
					(number "1"
						(effects
							(font
								(size 1.27 1.27)
							)
						)
					)
				)
				(pin bidirectional line
					(at 7.62 -3.81 90)
					(length 2.54)
					(name "S"
						(effects
							(font
								(size 1.27 1.27)
							)
						)
					)
					(number "2"
						(effects
							(font
								(size 1.27 1.27)
							)
						)
					)
				)
				(pin bidirectional line
					(at 7.62 8.89 270)
					(length 2.54)
					(name "D"
						(effects
							(font
								(size 1.27 1.27)
							)
						)
					)
					(number "3"
						(effects
							(font
								(size 1.27 1.27)
							)
						)
					)
				)
			)
		)
	(symbol "antmicroUSBConnectors:USB-C_GCT_USB4105-GF-A"
			(exclude_from_sim no)
			(in_bom yes)
			(on_board yes)
			(property "Reference" "J"
				(at 38.1 -2.54 0)
				(effects
					(font
						(size 1.27 1.27)
						(thickness 0.15)
					)
					(justify left bottom)
				)
			)
			(property "Value" "USB-C_GCT_USB4105-GF-A"
				(at 38.1 -5.08 0)
				(effects
					(font
						(size 1.27 1.27)
						(thickness 0.15)
					)
					(justify left bottom)
				)
			)
			(property "Footprint" "antmicro-footprints:USB-C_Receptacle_GCT_USB4105-GF-A"
				(at 38.1 -7.62 0)
				(effects
					(font
						(size 1.27 1.27)
						(thickness 0.15)
					)
					(justify left bottom)
					(hide yes)
				)
			)
			(property "Datasheet" "https://gct.co/files/drawings/usb4105.pdf"
				(at 38.1 -10.16 0)
				(effects
					(font
						(size 1.27 1.27)
						(thickness 0.15)
					)
					(justify left bottom)
					(hide yes)
				)
			)
			(property "Description" "USB-C (USB TYPE-C) USB 2.0 Receptacle Connector 24 (16+8 Dummy) Position Surface Mount, Right Angle"
				(at 0 0 0)
				(effects
					(font
						(size 1.27 1.27)
					)
					(hide yes)
				)
			)
			(property "Manufacturer" "GCT"
				(at 38.1 -12.7 0)
				(effects
					(font
						(size 1.27 1.27)
						(thickness 0.15)
					)
					(justify left bottom)
					(hide yes)
				)
			)
			(property "MPN" "USB4105-GF-A"
				(at 38.1 -15.24 0)
				(effects
					(font
						(size 1.27 1.27)
						(thickness 0.15)
					)
					(justify left bottom)
					(hide yes)
				)
			)
			(property "Author" "Antmicro"
				(at 38.1 -17.78 0)
				(effects
					(font
						(size 1.27 1.27)
						(thickness 0.15)
					)
					(justify left bottom)
					(hide yes)
				)
			)
			(property "License" "Apache-2.0"
				(at 38.1 -20.32 0)
				(effects
					(font
						(size 1.27 1.27)
						(thickness 0.15)
					)
					(justify left bottom)
					(hide yes)
				)
			)
			(property "ki_keywords" "USB, CONNECTOR, SMT, HORIZONTAL"
				(at 0 0 0)
				(effects
					(font
						(size 1.27 1.27)
					)
					(hide yes)
				)
			)
			(symbol "USB-C_GCT_USB4105-GF-A_1_1"
				(rectangle
					(start -22.86 2.54)
					(end -3.81 -38.1)
					(stroke
						(width 0.254)
						(type default)
					)
					(fill
						(type background)
					)
				)
				(circle
					(center -20.066 -18.034)
					(radius 0.284)
					(stroke
						(width 0.254)
						(type default)
					)
					(fill
						(type outline)
					)
				)
				(circle
					(center -19.177 -20.828)
					(radius 0.5236)
					(stroke
						(width 0.254)
						(type default)
					)
					(fill
						(type outline)
					)
				)
				(rectangle
					(start -18.669 -18.034)
					(end -17.907 -17.272)
					(stroke
						(width 0.254)
						(type default)
					)
					(fill
						(type outline)
					)
				)
				(arc
					(start -16.51 -21.59)
					(mid -14.605 -23.4867)
					(end -12.7 -21.59)
					(stroke
						(width 0.254)
						(type default)
					)
					(fill
						(type background)
					)
				)
				(arc
					(start -15.24 -21.59)
					(mid -14.605 -22.2223)
					(end -13.97 -21.59)
					(stroke
						(width 0.254)
						(type default)
					)
					(fill
						(type outline)
					)
				)
				(arc
					(start -15.24 -21.59)
					(mid -14.605 -22.2223)
					(end -13.97 -21.59)
					(stroke
						(width 0.254)
						(type default)
					)
					(fill
						(type background)
					)
				)
				(rectangle
					(start -15.24 -21.59)
					(end -13.97 -13.97)
					(stroke
						(width 0.254)
						(type default)
					)
					(fill
						(type outline)
					)
				)
				(arc
					(start -13.97 -13.97)
					(mid -14.605 -13.3377)
					(end -15.24 -13.97)
					(stroke
						(width 0.254)
						(type default)
					)
					(fill
						(type outline)
					)
				)
				(arc
					(start -13.97 -13.97)
					(mid -14.605 -13.3377)
					(end -15.24 -13.97)
					(stroke
						(width 0.254)
						(type default)
					)
					(fill
						(type background)
					)
				)
				(arc
					(start -12.7 -13.97)
					(mid -14.605 -12.0733)
					(end -16.51 -13.97)
					(stroke
						(width 0.254)
						(type default)
					)
					(fill
						(type background)
					)
				)
				(polyline
					(pts
						(xy -19.177 -20.701) (xy -19.177 -16.383)
					)
					(stroke
						(width 0.254)
						(type default)
					)
					(fill
						(type background)
					)
				)
				(polyline
					(pts
						(xy -16.51 -21.59) (xy -16.51 -13.97)
					)
					(stroke
						(width 0.254)
						(type default)
					)
					(fill
						(type background)
					)
				)
				(polyline
					(pts
						(xy -12.7 -13.97) (xy -12.7 -21.59)
					)
					(stroke
						(width 0.254)
						(type default)
					)
					(fill
						(type background)
					)
				)
				(polyline
					(pts
						(xy -19.177 -19.939) (xy -20.066 -19.05) (xy -20.066 -18.415)
					)
					(stroke
						(width 0.254)
						(type default)
					)
					(fill
						(type background)
					)
				)
				(polyline
					(pts
						(xy -19.177 -19.558) (xy -18.288 -18.669) (xy -18.288 -18.034)
					)
					(stroke
						(width 0.254)
						(type default)
					)
					(fill
						(type background)
					)
				)
				(polyline
					(pts
						(xy -19.812 -16.383) (xy -19.177 -15.24) (xy -18.542 -16.383) (xy -19.812 -16.383)
					)
					(stroke
						(width 0.254)
						(type default)
					)
					(fill
						(type outline)
					)
				)
				(pin power_in line
					(at 0 -33.02 180)
					(length 3.81)
					(name "GND"
						(effects
							(font
								(size 1.27 1.27)
							)
						)
					)
					(number "A1"
						(effects
							(font
								(size 1.27 1.27)
							)
						)
					)
				)
				(pin passive line
					(at 0 -33.02 180)
					(length 3.81) hide
					(name "GND"
						(effects
							(font
								(size 1.27 1.27)
							)
						)
					)
					(number "A12"
						(effects
							(font
								(size 1.27 1.27)
							)
						)
					)
				)
				(pin passive line
					(at 0 0 180)
					(length 3.81)
					(name "VBUS"
						(effects
							(font
								(size 1.27 1.27)
							)
						)
					)
					(number "A4"
						(effects
							(font
								(size 1.27 1.27)
							)
						)
					)
				)
				(pin bidirectional line
					(at 0 -5.08 180)
					(length 3.81)
					(name "CC_{1}"
						(effects
							(font
								(size 1.27 1.27)
							)
						)
					)
					(number "A5"
						(effects
							(font
								(size 1.27 1.27)
							)
						)
					)
				)
				(pin bidirectional line
					(at 0 -12.7 180)
					(length 3.81)
					(name "D_{A}+"
						(effects
							(font
								(size 1.27 1.27)
							)
						)
					)
					(number "A6"
						(effects
							(font
								(size 1.27 1.27)
							)
						)
					)
				)
				(pin bidirectional line
					(at 0 -15.24 180)
					(length 3.81)
					(name "D_{A}-"
						(effects
							(font
								(size 1.27 1.27)
							)
						)
					)
					(number "A7"
						(effects
							(font
								(size 1.27 1.27)
							)
						)
					)
				)
				(pin bidirectional line
					(at 0 -25.4 180)
					(length 3.81)
					(name "SBU_{1}"
						(effects
							(font
								(size 1.27 1.27)
							)
						)
					)
					(number "A8"
						(effects
							(font
								(size 1.27 1.27)
							)
						)
					)
				)
				(pin passive line
					(at 0 0 180)
					(length 3.81) hide
					(name "VBUS"
						(effects
							(font
								(size 1.27 1.27)
							)
						)
					)
					(number "A9"
						(effects
							(font
								(size 1.27 1.27)
							)
						)
					)
				)
				(pin passive line
					(at 0 -33.02 180)
					(length 3.81) hide
					(name "GND"
						(effects
							(font
								(size 1.27 1.27)
							)
						)
					)
					(number "B1"
						(effects
							(font
								(size 1.27 1.27)
							)
						)
					)
				)
				(pin passive line
					(at 0 -33.02 180)
					(length 3.81) hide
					(name "GND"
						(effects
							(font
								(size 1.27 1.27)
							)
						)
					)
					(number "B12"
						(effects
							(font
								(size 1.27 1.27)
							)
						)
					)
				)
				(pin passive line
					(at 0 0 180)
					(length 3.81) hide
					(name "VBUS"
						(effects
							(font
								(size 1.27 1.27)
							)
						)
					)
					(number "B4"
						(effects
							(font
								(size 1.27 1.27)
							)
						)
					)
				)
				(pin bidirectional line
					(at 0 -7.62 180)
					(length 3.81)
					(name "CC_{2}"
						(effects
							(font
								(size 1.27 1.27)
							)
						)
					)
					(number "B5"
						(effects
							(font
								(size 1.27 1.27)
							)
						)
					)
				)
				(pin bidirectional line
					(at 0 -17.78 180)
					(length 3.81)
					(name "D_{B}+"
						(effects
							(font
								(size 1.27 1.27)
							)
						)
					)
					(number "B6"
						(effects
							(font
								(size 1.27 1.27)
							)
						)
					)
				)
				(pin bidirectional line
					(at 0 -20.32 180)
					(length 3.81)
					(name "D_{B}-"
						(effects
							(font
								(size 1.27 1.27)
							)
						)
					)
					(number "B7"
						(effects
							(font
								(size 1.27 1.27)
							)
						)
					)
				)
				(pin bidirectional line
					(at 0 -27.94 180)
					(length 3.81)
					(name "SBU_{2}"
						(effects
							(font
								(size 1.27 1.27)
							)
						)
					)
					(number "B8"
						(effects
							(font
								(size 1.27 1.27)
							)
						)
					)
				)
				(pin passive line
					(at 0 0 180)
					(length 3.81) hide
					(name "VBUS"
						(effects
							(font
								(size 1.27 1.27)
							)
						)
					)
					(number "B9"
						(effects
							(font
								(size 1.27 1.27)
							)
						)
					)
				)
				(pin passive line
					(at 0 -35.56 180)
					(length 3.81)
					(name "SH"
						(effects
							(font
								(size 1.27 1.27)
							)
						)
					)
					(number "SH"
						(effects
							(font
								(size 1.27 1.27)
							)
						)
					)
				)
			)
		)
	(symbol "antmicroUSBConnectors:USB-C_WE_632723300011"
			(exclude_from_sim no)
			(in_bom yes)
			(on_board yes)
			(property "Reference" "J"
				(at 15.24 -2.54 0)
				(effects
					(font
						(size 1.27 1.27)
						(thickness 0.15)
					)
					(justify left bottom)
				)
			)
			(property "Value" "USB-C_WE_632723300011"
				(at 15.24 -7.62 0)
				(effects
					(font
						(size 1.27 1.27)
						(thickness 0.15)
					)
					(justify left bottom)
					(hide yes)
				)
			)
			(property "Footprint" "antmicro-footprints:USB-C_Receptacle_WE_632723300011"
				(at 15.24 -10.16 0)
				(effects
					(font
						(size 1.27 1.27)
						(thickness 0.15)
					)
					(justify left bottom)
					(hide yes)
				)
			)
			(property "Datasheet" "https://www.we-online.com/components/products/datasheet/632723300011.pdf"
				(at 15.24 -12.7 0)
				(effects
					(font
						(size 1.27 1.27)
						(thickness 0.15)
					)
					(justify left bottom)
					(hide yes)
				)
			)
			(property "Description" "USB-C (USB TYPE-C) USB 3.2 Gen 2 (USB 3.1 Gen 2, Superspeed + (USB 3.1)) Receptacle Connector 24 Position Surface Mount, Right Angle; Through Hole"
				(at 0 0 0)
				(effects
					(font
						(size 1.27 1.27)
					)
					(hide yes)
				)
			)
			(property "Manufacturer" "Würth Elektronik"
				(at 15.24 -15.24 0)
				(effects
					(font
						(size 1.27 1.27)
						(thickness 0.15)
					)
					(justify left bottom)
					(hide yes)
				)
			)
			(property "MPN" "632723300011"
				(at 15.24 -5.08 0)
				(effects
					(font
						(size 1.27 1.27)
						(thickness 0.15)
					)
					(justify left bottom)
				)
			)
			(property "Author" "Antmicro"
				(at 15.24 -17.78 0)
				(effects
					(font
						(size 1.27 1.27)
						(thickness 0.15)
					)
					(justify left bottom)
					(hide yes)
				)
			)
			(property "License" "Apache-2.0"
				(at 15.24 -20.32 0)
				(effects
					(font
						(size 1.27 1.27)
						(thickness 0.15)
					)
					(justify left bottom)
					(hide yes)
				)
			)
			(property "ki_keywords" "USB, CONNECTOR, SMT, HORIZONTAL"
				(at 0 0 0)
				(effects
					(font
						(size 1.27 1.27)
					)
					(hide yes)
				)
			)
			(symbol "USB-C_WE_632723300011_1_1"
				(rectangle
					(start -22.86 -68.58)
					(end -3.81 2.54)
					(stroke
						(width 0.254)
						(type default)
					)
					(fill
						(type background)
					)
				)
				(circle
					(center -20.066 -33.274)
					(radius 0.284)
					(stroke
						(width 0.254)
						(type default)
					)
					(fill
						(type background)
					)
				)
				(circle
					(center -19.177 -36.068)
					(radius 0.5236)
					(stroke
						(width 0.254)
						(type default)
					)
					(fill
						(type background)
					)
				)
				(rectangle
					(start -18.669 -33.274)
					(end -17.907 -32.512)
					(stroke
						(width 0.254)
						(type default)
					)
					(fill
						(type background)
					)
				)
				(arc
					(start -16.51 -36.83)
					(mid -14.605 -38.7267)
					(end -12.7 -36.83)
					(stroke
						(width 0.254)
						(type default)
					)
					(fill
						(type background)
					)
				)
				(arc
					(start -15.24 -36.83)
					(mid -14.605 -37.4623)
					(end -13.97 -36.83)
					(stroke
						(width 0.254)
						(type default)
					)
					(fill
						(type background)
					)
				)
				(arc
					(start -15.24 -36.83)
					(mid -14.605 -37.4623)
					(end -13.97 -36.83)
					(stroke
						(width 0.254)
						(type default)
					)
					(fill
						(type background)
					)
				)
				(rectangle
					(start -15.24 -36.83)
					(end -13.97 -29.21)
					(stroke
						(width 0.254)
						(type default)
					)
					(fill
						(type background)
					)
				)
				(arc
					(start -13.97 -29.21)
					(mid -14.605 -28.5777)
					(end -15.24 -29.21)
					(stroke
						(width 0.254)
						(type default)
					)
					(fill
						(type background)
					)
				)
				(arc
					(start -13.97 -29.21)
					(mid -14.605 -28.5777)
					(end -15.24 -29.21)
					(stroke
						(width 0.254)
						(type default)
					)
					(fill
						(type background)
					)
				)
				(arc
					(start -12.7 -29.21)
					(mid -14.605 -27.3133)
					(end -16.51 -29.21)
					(stroke
						(width 0.254)
						(type default)
					)
					(fill
						(type background)
					)
				)
				(polyline
					(pts
						(xy -19.177 -35.941) (xy -19.177 -31.623)
					)
					(stroke
						(width 0.254)
						(type default)
					)
					(fill
						(type background)
					)
				)
				(polyline
					(pts
						(xy -16.51 -36.83) (xy -16.51 -29.21)
					)
					(stroke
						(width 0.254)
						(type default)
					)
					(fill
						(type background)
					)
				)
				(polyline
					(pts
						(xy -12.7 -29.21) (xy -12.7 -36.83)
					)
					(stroke
						(width 0.254)
						(type default)
					)
					(fill
						(type background)
					)
				)
				(polyline
					(pts
						(xy -19.177 -35.179) (xy -20.066 -34.29) (xy -20.066 -33.655)
					)
					(stroke
						(width 0.254)
						(type default)
					)
					(fill
						(type background)
					)
				)
				(polyline
					(pts
						(xy -19.177 -34.798) (xy -18.288 -33.909) (xy -18.288 -33.274)
					)
					(stroke
						(width 0.254)
						(type default)
					)
					(fill
						(type background)
					)
				)
				(polyline
					(pts
						(xy -19.812 -31.623) (xy -19.177 -30.48) (xy -18.542 -31.623) (xy -19.812 -31.623)
					)
					(stroke
						(width 0.254)
						(type default)
					)
					(fill
						(type background)
					)
				)
				(pin power_in line
					(at 0 -63.5 180)
					(length 3.81)
					(name "GND"
						(effects
							(font
								(size 1.27 1.27)
							)
						)
					)
					(number "A1"
						(effects
							(font
								(size 1.27 1.27)
							)
						)
					)
				)
				(pin bidirectional line
					(at 0 -43.18 180)
					(length 3.81)
					(name "RX_{2}-"
						(effects
							(font
								(size 1.27 1.27)
							)
						)
					)
					(number "A10"
						(effects
							(font
								(size 1.27 1.27)
							)
						)
					)
				)
				(pin bidirectional line
					(at 0 -40.64 180)
					(length 3.81)
					(name "RX_{2}+"
						(effects
							(font
								(size 1.27 1.27)
							)
						)
					)
					(number "A11"
						(effects
							(font
								(size 1.27 1.27)
							)
						)
					)
				)
				(pin passive line
					(at 0 -63.5 180)
					(length 3.81) hide
					(name "GND"
						(effects
							(font
								(size 1.27 1.27)
							)
						)
					)
					(number "A12"
						(effects
							(font
								(size 1.27 1.27)
							)
						)
					)
				)
				(pin bidirectional line
					(at 0 -33.02 180)
					(length 3.81)
					(name "TX_{1}+"
						(effects
							(font
								(size 1.27 1.27)
							)
						)
					)
					(number "A2"
						(effects
							(font
								(size 1.27 1.27)
							)
						)
					)
				)
				(pin bidirectional line
					(at 0 -35.56 180)
					(length 3.81)
					(name "TX_{1}-"
						(effects
							(font
								(size 1.27 1.27)
							)
						)
					)
					(number "A3"
						(effects
							(font
								(size 1.27 1.27)
							)
						)
					)
				)
				(pin passive line
					(at 0 0 180)
					(length 3.81)
					(name "VBUS"
						(effects
							(font
								(size 1.27 1.27)
							)
						)
					)
					(number "A4"
						(effects
							(font
								(size 1.27 1.27)
							)
						)
					)
				)
				(pin bidirectional line
					(at 0 -5.08 180)
					(length 3.81)
					(name "CC_{1}"
						(effects
							(font
								(size 1.27 1.27)
							)
						)
					)
					(number "A5"
						(effects
							(font
								(size 1.27 1.27)
							)
						)
					)
				)
				(pin bidirectional line
					(at 0 -12.7 180)
					(length 3.81)
					(name "D_{A}+"
						(effects
							(font
								(size 1.27 1.27)
							)
						)
					)
					(number "A6"
						(effects
							(font
								(size 1.27 1.27)
							)
						)
					)
				)
				(pin bidirectional line
					(at 0 -15.24 180)
					(length 3.81)
					(name "D_{A}-"
						(effects
							(font
								(size 1.27 1.27)
							)
						)
					)
					(number "A7"
						(effects
							(font
								(size 1.27 1.27)
							)
						)
					)
				)
				(pin bidirectional line
					(at 0 -55.88 180)
					(length 3.81)
					(name "SBU_{1}"
						(effects
							(font
								(size 1.27 1.27)
							)
						)
					)
					(number "A8"
						(effects
							(font
								(size 1.27 1.27)
							)
						)
					)
				)
				(pin passive line
					(at 0 0 180)
					(length 3.81) hide
					(name "VBUS"
						(effects
							(font
								(size 1.27 1.27)
							)
						)
					)
					(number "A9"
						(effects
							(font
								(size 1.27 1.27)
							)
						)
					)
				)
				(pin passive line
					(at 0 -63.5 180)
					(length 3.81) hide
					(name "GND"
						(effects
							(font
								(size 1.27 1.27)
							)
						)
					)
					(number "B1"
						(effects
							(font
								(size 1.27 1.27)
							)
						)
					)
				)
				(pin bidirectional line
					(at 0 -27.94 180)
					(length 3.81)
					(name "RX_{1}-"
						(effects
							(font
								(size 1.27 1.27)
							)
						)
					)
					(number "B10"
						(effects
							(font
								(size 1.27 1.27)
							)
						)
					)
				)
				(pin bidirectional line
					(at 0 -25.4 180)
					(length 3.81)
					(name "RX_{1}+"
						(effects
							(font
								(size 1.27 1.27)
							)
						)
					)
					(number "B11"
						(effects
							(font
								(size 1.27 1.27)
							)
						)
					)
				)
				(pin passive line
					(at 0 -63.5 180)
					(length 3.81) hide
					(name "GND"
						(effects
							(font
								(size 1.27 1.27)
							)
						)
					)
					(number "B12"
						(effects
							(font
								(size 1.27 1.27)
							)
						)
					)
				)
				(pin bidirectional line
					(at 0 -48.26 180)
					(length 3.81)
					(name "TX_{2}+"
						(effects
							(font
								(size 1.27 1.27)
							)
						)
					)
					(number "B2"
						(effects
							(font
								(size 1.27 1.27)
							)
						)
					)
				)
				(pin bidirectional line
					(at 0 -50.8 180)
					(length 3.81)
					(name "TX_{2}-"
						(effects
							(font
								(size 1.27 1.27)
							)
						)
					)
					(number "B3"
						(effects
							(font
								(size 1.27 1.27)
							)
						)
					)
				)
				(pin passive line
					(at 0 0 180)
					(length 3.81) hide
					(name "VBUS"
						(effects
							(font
								(size 1.27 1.27)
							)
						)
					)
					(number "B4"
						(effects
							(font
								(size 1.27 1.27)
							)
						)
					)
				)
				(pin bidirectional line
					(at 0 -7.62 180)
					(length 3.81)
					(name "CC_{2}"
						(effects
							(font
								(size 1.27 1.27)
							)
						)
					)
					(number "B5"
						(effects
							(font
								(size 1.27 1.27)
							)
						)
					)
				)
				(pin bidirectional line
					(at 0 -17.78 180)
					(length 3.81)
					(name "D_{B}+"
						(effects
							(font
								(size 1.27 1.27)
							)
						)
					)
					(number "B6"
						(effects
							(font
								(size 1.27 1.27)
							)
						)
					)
				)
				(pin bidirectional line
					(at 0 -20.32 180)
					(length 3.81)
					(name "D_{B}-"
						(effects
							(font
								(size 1.27 1.27)
							)
						)
					)
					(number "B7"
						(effects
							(font
								(size 1.27 1.27)
							)
						)
					)
				)
				(pin bidirectional line
					(at 0 -58.42 180)
					(length 3.81)
					(name "SBU_{2}"
						(effects
							(font
								(size 1.27 1.27)
							)
						)
					)
					(number "B8"
						(effects
							(font
								(size 1.27 1.27)
							)
						)
					)
				)
				(pin passive line
					(at 0 0 180)
					(length 3.81) hide
					(name "VBUS"
						(effects
							(font
								(size 1.27 1.27)
							)
						)
					)
					(number "B9"
						(effects
							(font
								(size 1.27 1.27)
							)
						)
					)
				)
				(pin passive line
					(at 0 -66.04 180)
					(length 3.81)
					(name "SH"
						(effects
							(font
								(size 1.27 1.27)
							)
						)
					)
					(number "SH"
						(effects
							(font
								(size 1.27 1.27)
							)
						)
					)
				)
			)
		)
	(symbol "antmicroVideoConnectors:HDMI-Mini-C_WE_685119136923"
			(exclude_from_sim no)
			(in_bom yes)
			(on_board yes)
			(property "Reference" "J"
				(at 59.69 -2.54 0)
				(effects
					(font
						(size 1.27 1.27)
						(thickness 0.15)
					)
					(justify left bottom)
				)
			)
			(property "Value" "HDMI-Mini-C_WE_685119136923"
				(at 59.69 -5.08 0)
				(effects
					(font
						(size 1.27 1.27)
						(thickness 0.15)
					)
					(justify left bottom)
					(hide yes)
				)
			)
			(property "Footprint" "antmicro-footprints:HDMI-Mini-C_Receptacle_WE_685119136923"
				(at 59.69 -7.62 0)
				(effects
					(font
						(size 1.27 1.27)
						(thickness 0.15)
					)
					(justify left bottom)
					(hide yes)
				)
			)
			(property "Datasheet" "https://www.we-online.com/components/products/datasheet/685119136923.pdf"
				(at 59.69 -10.16 0)
				(effects
					(font
						(size 1.27 1.27)
						(thickness 0.15)
					)
					(justify left bottom)
					(hide yes)
				)
			)
			(property "Description" "HDMI - Mini Receptacle Connector 19 Position Surface Mount, Right Angle; Through Hole"
				(at 0 0 0)
				(effects
					(font
						(size 1.27 1.27)
					)
					(hide yes)
				)
			)
			(property "Manufacturer" "Würth Elektronik"
				(at 59.69 -12.7 0)
				(effects
					(font
						(size 1.27 1.27)
						(thickness 0.15)
					)
					(justify left bottom)
					(hide yes)
				)
			)
			(property "MPN" "685119136923"
				(at 59.69 -15.24 0)
				(effects
					(font
						(size 1.27 1.27)
						(thickness 0.15)
					)
					(justify left bottom)
				)
			)
			(property "Author" "Antmicro"
				(at 59.69 -17.78 0)
				(effects
					(font
						(size 1.27 1.27)
						(thickness 0.15)
					)
					(justify left bottom)
					(hide yes)
				)
			)
			(property "License" "Apache-2.0"
				(at 59.69 -20.32 0)
				(effects
					(font
						(size 1.27 1.27)
						(thickness 0.15)
					)
					(justify left bottom)
					(hide yes)
				)
			)
			(property "ki_keywords" "MINI, HDMI, CONNECTOR, SMT"
				(at 0 0 0)
				(effects
					(font
						(size 1.27 1.27)
					)
					(hide yes)
				)
			)
			(symbol "HDMI-Mini-C_WE_685119136923_0_0"
				(polyline
					(pts
						(xy 22.098 0) (xy 22.098 1.524)
					)
					(stroke
						(width 0.635)
						(type default)
					)
					(fill
						(type none)
					)
				)
				(polyline
					(pts
						(xy 13.97 0) (xy 13.97 1.524) (xy 13.97 0.762) (xy 15.875 0.762) (xy 15.875 1.524) (xy 15.875 0)
					)
					(stroke
						(width 0.635)
						(type default)
					)
					(fill
						(type none)
					)
				)
				(polyline
					(pts
						(xy 16.637 1.524) (xy 18.288 1.524) (xy 18.542 1.27) (xy 18.542 0.254) (xy 18.288 0) (xy 16.637 0)
						(xy 16.637 0.762)
					)
					(stroke
						(width 0.635)
						(type default)
					)
					(fill
						(type none)
					)
				)
				(text "mini"
					(at 19.05 -1.27 0)
					(effects
						(font
							(size 1.27 1.27)
						)
					)
				)
			)
			(symbol "HDMI-Mini-C_WE_685119136923_0_1"
				(polyline
					(pts
						(xy 10.16 -15.24) (xy 13.97 -15.24) (xy 15.875 -17.145) (xy 15.875 -28.575) (xy 13.97 -30.48)
						(xy 10.16 -30.48) (xy 10.16 -15.24)
					)
					(stroke
						(width 0.635)
						(type default)
					)
					(fill
						(type none)
					)
				)
				(polyline
					(pts
						(xy 12.065 -16.51) (xy 13.335 -16.51) (xy 13.97 -17.145) (xy 13.97 -28.575) (xy 13.335 -29.21)
						(xy 12.065 -29.21) (xy 12.065 -16.51)
					)
					(stroke
						(width 0.254)
						(type default)
					)
					(fill
						(type outline)
					)
				)
				(polyline
					(pts
						(xy 19.304 0) (xy 19.304 1.524) (xy 20.32 1.524) (xy 20.32 0) (xy 20.32 1.524) (xy 21.082 1.524)
						(xy 21.336 1.27) (xy 21.336 0)
					)
					(stroke
						(width 0.635)
						(type default)
					)
					(fill
						(type none)
					)
				)
				(rectangle
					(start 2.54 2.54)
					(end 22.86 -53.34)
					(stroke
						(width 0.254)
						(type default)
					)
					(fill
						(type background)
					)
				)
				(pin passive line
					(at 25.4 -38.1 180)
					(length 2.54)
					(name "D2S"
						(effects
							(font
								(size 1.27 1.27)
							)
						)
					)
					(number "1"
						(effects
							(font
								(size 1.27 1.27)
							)
						)
					)
				)
				(pin passive line
					(at 25.4 -45.72 180)
					(length 2.54)
					(name "CKS"
						(effects
							(font
								(size 1.27 1.27)
							)
						)
					)
					(number "10"
						(effects
							(font
								(size 1.27 1.27)
							)
						)
					)
				)
				(pin bidirectional line
					(at 0 -22.86 0)
					(length 2.54)
					(name "CK+"
						(effects
							(font
								(size 1.27 1.27)
							)
						)
					)
					(number "11"
						(effects
							(font
								(size 1.27 1.27)
							)
						)
					)
				)
				(pin bidirectional line
					(at 0 -25.4 0)
					(length 2.54)
					(name "CK-"
						(effects
							(font
								(size 1.27 1.27)
							)
						)
					)
					(number "12"
						(effects
							(font
								(size 1.27 1.27)
							)
						)
					)
				)
				(pin power_in line
					(at 25.4 -48.26 180)
					(length 2.54)
					(name "GND"
						(effects
							(font
								(size 1.27 1.27)
							)
						)
					)
					(number "13"
						(effects
							(font
								(size 1.27 1.27)
							)
						)
					)
				)
				(pin bidirectional line
					(at 0 -38.1 0)
					(length 2.54)
					(name "CEC"
						(effects
							(font
								(size 1.27 1.27)
							)
						)
					)
					(number "14"
						(effects
							(font
								(size 1.27 1.27)
							)
						)
					)
				)
				(pin bidirectional line
					(at 0 -30.48 0)
					(length 2.54)
					(name "SCL"
						(effects
							(font
								(size 1.27 1.27)
							)
						)
					)
					(number "15"
						(effects
							(font
								(size 1.27 1.27)
							)
						)
					)
				)
				(pin bidirectional line
					(at 0 -33.02 0)
					(length 2.54)
					(name "SDA"
						(effects
							(font
								(size 1.27 1.27)
							)
						)
					)
					(number "16"
						(effects
							(font
								(size 1.27 1.27)
							)
						)
					)
				)
				(pin bidirectional line
					(at 0 -45.72 0)
					(length 2.54)
					(name "UTIL/HEAC+"
						(effects
							(font
								(size 1.27 1.27)
							)
						)
					)
					(number "17"
						(effects
							(font
								(size 1.27 1.27)
							)
						)
					)
					(alternate "HEAC+" passive line)
					(alternate "Utility" passive line)
				)
				(pin power_in line
					(at 0 -50.8 0)
					(length 2.54)
					(name "+5V"
						(effects
							(font
								(size 1.27 1.27)
							)
						)
					)
					(number "18"
						(effects
							(font
								(size 1.27 1.27)
							)
						)
					)
				)
				(pin bidirectional line
					(at 0 -43.18 0)
					(length 2.54)
					(name "HPD/HEAC-"
						(effects
							(font
								(size 1.27 1.27)
							)
						)
					)
					(number "19"
						(effects
							(font
								(size 1.27 1.27)
							)
						)
					)
					(alternate "HEAC-" passive line)
					(alternate "HPD" passive line)
				)
				(pin bidirectional line
					(at 0 0 0)
					(length 2.54)
					(name "D2+"
						(effects
							(font
								(size 1.27 1.27)
							)
						)
					)
					(number "2"
						(effects
							(font
								(size 1.27 1.27)
							)
						)
					)
				)
				(pin bidirectional line
					(at 0 -2.54 0)
					(length 2.54)
					(name "D2-"
						(effects
							(font
								(size 1.27 1.27)
							)
						)
					)
					(number "3"
						(effects
							(font
								(size 1.27 1.27)
							)
						)
					)
				)
				(pin passive line
					(at 25.4 -40.64 180)
					(length 2.54)
					(name "D1S"
						(effects
							(font
								(size 1.27 1.27)
							)
						)
					)
					(number "4"
						(effects
							(font
								(size 1.27 1.27)
							)
						)
					)
				)
				(pin bidirectional line
					(at 0 -7.62 0)
					(length 2.54)
					(name "D1+"
						(effects
							(font
								(size 1.27 1.27)
							)
						)
					)
					(number "5"
						(effects
							(font
								(size 1.27 1.27)
							)
						)
					)
				)
				(pin bidirectional line
					(at 0 -10.16 0)
					(length 2.54)
					(name "D1-"
						(effects
							(font
								(size 1.27 1.27)
							)
						)
					)
					(number "6"
						(effects
							(font
								(size 1.27 1.27)
							)
						)
					)
				)
				(pin passive line
					(at 25.4 -43.18 180)
					(length 2.54)
					(name "D0S"
						(effects
							(font
								(size 1.27 1.27)
							)
						)
					)
					(number "7"
						(effects
							(font
								(size 1.27 1.27)
							)
						)
					)
				)
				(pin bidirectional line
					(at 0 -15.24 0)
					(length 2.54)
					(name "D0+"
						(effects
							(font
								(size 1.27 1.27)
							)
						)
					)
					(number "8"
						(effects
							(font
								(size 1.27 1.27)
							)
						)
					)
				)
				(pin bidirectional line
					(at 0 -17.78 0)
					(length 2.54)
					(name "D0-"
						(effects
							(font
								(size 1.27 1.27)
							)
						)
					)
					(number "9"
						(effects
							(font
								(size 1.27 1.27)
							)
						)
					)
				)
				(pin passive line
					(at 25.4 -50.8 180)
					(length 2.54)
					(name "SH"
						(effects
							(font
								(size 1.27 1.27)
							)
						)
					)
					(number "SH"
						(effects
							(font
								(size 1.27 1.27)
							)
						)
					)
				)
			)
		)
	(symbol "antmicroWire2BoardConnectors:JST_SH_1x4_SM04B-SRSS-TB-LF-SN"
			(exclude_from_sim no)
			(in_bom yes)
			(on_board yes)
			(property "Reference" "J"
				(at 26.67 -2.54 0)
				(effects
					(font
						(size 1.27 1.27)
						(thickness 0.15)
					)
					(justify left bottom)
				)
			)
			(property "Value" "JST_SH_1x4_SM04B-SRSS-TB-LF-SN"
				(at 26.67 -7.62 0)
				(effects
					(font
						(size 1.27 1.27)
						(thickness 0.15)
					)
					(justify left bottom)
					(hide yes)
				)
			)
			(property "Footprint" "antmicro-footprints:Conn_JST_SH_1x4_SM04B-SRSS-TB-LF-SN"
				(at 26.67 -10.16 0)
				(effects
					(font
						(size 1.27 1.27)
						(thickness 0.15)
					)
					(justify left bottom)
					(hide yes)
				)
			)
			(property "Datasheet" "https://www.jst-mfg.com/product/pdf/eng/eSH.pdf"
				(at 26.67 -12.7 0)
				(effects
					(font
						(size 1.27 1.27)
						(thickness 0.15)
					)
					(justify left bottom)
					(hide yes)
				)
			)
			(property "Description" "Pin Header, Right Angle, Wire-to-Board, 1 mm, 1 Rows, 4 Contacts, Surface Mount Right Angle, SH"
				(at 0 0 0)
				(effects
					(font
						(size 1.27 1.27)
					)
					(hide yes)
				)
			)
			(property "MPN" "SM04B-SRSS-TB(LF)(SN)"
				(at 26.67 -5.08 0)
				(effects
					(font
						(size 1.27 1.27)
						(thickness 0.15)
					)
					(justify left bottom)
				)
			)
			(property "Manufacturer" "JST Automotive Connectors"
				(at 26.67 -15.24 0)
				(effects
					(font
						(size 1.27 1.27)
						(thickness 0.15)
					)
					(justify left bottom)
					(hide yes)
				)
			)
			(property "Author" "Antmicro"
				(at 26.67 -17.78 0)
				(effects
					(font
						(size 1.27 1.27)
						(thickness 0.15)
					)
					(justify left bottom)
					(hide yes)
				)
			)
			(property "License" "Apache-2.0"
				(at 26.67 -20.32 0)
				(effects
					(font
						(size 1.27 1.27)
						(thickness 0.15)
					)
					(justify left bottom)
					(hide yes)
				)
			)
			(property "ki_keywords" "VERTICAL, SMT, WIRE-BOARD, CONNECTOR, MALE, HEADER"
				(at 0 0 0)
				(effects
					(font
						(size 1.27 1.27)
					)
					(hide yes)
				)
			)
			(symbol "JST_SH_1x4_SM04B-SRSS-TB-LF-SN_1_1"
				(rectangle
					(start 2.54 -10.033)
					(end 3.81 -10.287)
					(stroke
						(width 0.254)
						(type default)
					)
					(fill
						(type background)
					)
				)
				(rectangle
					(start 2.54 -7.493)
					(end 3.81 -7.747)
					(stroke
						(width 0.254)
						(type default)
					)
					(fill
						(type background)
					)
				)
				(rectangle
					(start 2.54 -4.953)
					(end 3.81 -5.207)
					(stroke
						(width 0.254)
						(type default)
					)
					(fill
						(type background)
					)
				)
				(rectangle
					(start 2.54 -2.413)
					(end 3.81 -2.667)
					(stroke
						(width 0.254)
						(type default)
					)
					(fill
						(type background)
					)
				)
				(rectangle
					(start 2.54 0.127)
					(end 3.81 -0.127)
					(stroke
						(width 0.254)
						(type default)
					)
					(fill
						(type background)
					)
				)
				(rectangle
					(start 2.54 2.54)
					(end 5.08 -12.7)
					(stroke
						(width 0.254)
						(type default)
					)
					(fill
						(type background)
					)
				)
				(pin passive line
					(at 0 0 0)
					(length 2.54)
					(name "~"
						(effects
							(font
								(size 1.27 1.27)
							)
						)
					)
					(number "1"
						(effects
							(font
								(size 1.27 1.27)
							)
						)
					)
				)
				(pin passive line
					(at 0 -2.54 0)
					(length 2.54)
					(name "~"
						(effects
							(font
								(size 1.27 1.27)
							)
						)
					)
					(number "2"
						(effects
							(font
								(size 1.27 1.27)
							)
						)
					)
				)
				(pin passive line
					(at 0 -5.08 0)
					(length 2.54)
					(name "~"
						(effects
							(font
								(size 1.27 1.27)
							)
						)
					)
					(number "3"
						(effects
							(font
								(size 1.27 1.27)
							)
						)
					)
				)
				(pin passive line
					(at 0 -7.62 0)
					(length 2.54)
					(name "~"
						(effects
							(font
								(size 1.27 1.27)
							)
						)
					)
					(number "4"
						(effects
							(font
								(size 1.27 1.27)
							)
						)
					)
				)
				(pin passive line
					(at 0 -10.16 0)
					(length 2.54)
					(name "~"
						(effects
							(font
								(size 1.27 1.27)
							)
						)
					)
					(number "MP"
						(effects
							(font
								(size 1.27 1.27)
							)
						)
					)
				)
			)
		)
	(symbol "antmicroWire2BoardConnectors:Molex_Nano-Fit_1x2_SMD_1054301202"
			(exclude_from_sim no)
			(in_bom yes)
			(on_board yes)
			(property "Reference" "J"
				(at 26.67 -2.54 0)
				(effects
					(font
						(size 1.27 1.27)
						(thickness 0.15)
					)
					(justify left bottom)
				)
			)
			(property "Value" "Molex_Nano-Fit_1x2_SMD_1054301202"
				(at 26.67 -7.62 0)
				(effects
					(font
						(size 1.27 1.27)
						(thickness 0.15)
					)
					(justify left bottom)
					(hide yes)
				)
			)
			(property "Footprint" "antmicro-footprints:Conn_Molex_Nano-Fit_1x2_SMD_1054301202"
				(at 26.67 -10.16 0)
				(effects
					(font
						(size 1.27 1.27)
						(thickness 0.15)
					)
					(justify left bottom)
					(hide yes)
				)
			)
			(property "Datasheet" "https://www.farnell.com/cad/3578051.pdf"
				(at 26.67 -12.7 0)
				(effects
					(font
						(size 1.27 1.27)
						(thickness 0.15)
					)
					(justify left bottom)
					(hide yes)
				)
			)
			(property "Description" "Pin Header, Pitch 2.5 mm, 1 Row, 2 Contacts, Nano-Fit"
				(at 0 0 0)
				(effects
					(font
						(size 1.27 1.27)
					)
					(hide yes)
				)
			)
			(property "Manufacturer" "Molex"
				(at 26.67 -15.24 0)
				(effects
					(font
						(size 1.27 1.27)
						(thickness 0.15)
					)
					(justify left bottom)
					(hide yes)
				)
			)
			(property "MPN" "105430-1202"
				(at 26.67 -5.08 0)
				(effects
					(font
						(size 1.27 1.27)
						(thickness 0.15)
					)
					(justify left bottom)
				)
			)
			(property "Author" "Antmicro"
				(at 26.67 -17.78 0)
				(effects
					(font
						(size 1.27 1.27)
						(thickness 0.15)
					)
					(justify left bottom)
					(hide yes)
				)
			)
			(property "License" "Apache-2.0"
				(at 26.67 -20.32 0)
				(effects
					(font
						(size 1.27 1.27)
						(thickness 0.15)
					)
					(justify left bottom)
					(hide yes)
				)
			)
			(property "ki_keywords" "CONNECTOR, HEADER, HORIZONTAL, SMT"
				(at 0 0 0)
				(effects
					(font
						(size 1.27 1.27)
					)
					(hide yes)
				)
			)
			(symbol "Molex_Nano-Fit_1x2_SMD_1054301202_1_1"
				(rectangle
					(start 2.54 -5.334)
					(end 4.1402 -4.699)
					(stroke
						(width 0.254)
						(type default)
					)
					(fill
						(type background)
					)
				)
				(rectangle
					(start 2.54 -2.794)
					(end 4.1402 -2.159)
					(stroke
						(width 0.254)
						(type default)
					)
					(fill
						(type background)
					)
				)
				(rectangle
					(start 2.54 -0.254)
					(end 4.1402 0.381)
					(stroke
						(width 0.254)
						(type default)
					)
					(fill
						(type background)
					)
				)
				(rectangle
					(start 2.54 2.54)
					(end 6.35 -7.62)
					(stroke
						(width 0.254)
						(type default)
					)
					(fill
						(type background)
					)
				)
				(pin passive line
					(at 0 0 0)
					(length 2.54)
					(name "~"
						(effects
							(font
								(size 1.27 1.27)
							)
						)
					)
					(number "1"
						(effects
							(font
								(size 1.27 1.27)
							)
						)
					)
				)
				(pin passive line
					(at 0 -2.54 0)
					(length 2.54)
					(name "~"
						(effects
							(font
								(size 1.27 1.27)
							)
						)
					)
					(number "2"
						(effects
							(font
								(size 1.27 1.27)
							)
						)
					)
				)
				(pin passive line
					(at 0 -5.08 0)
					(length 2.54)
					(name "~"
						(effects
							(font
								(size 1.27 1.27)
							)
						)
					)
					(number "MP"
						(effects
							(font
								(size 1.27 1.27)
							)
						)
					)
				)
			)
		)
	(symbol "antmicroWire2BoardConnectors:Molex_PicoBlade_1x4_0533980471"
			(pin_names hide)
			(exclude_from_sim no)
			(in_bom yes)
			(on_board yes)
			(property "Reference" "J"
				(at 20.32 -5.08 0)
				(effects
					(font
						(size 1.27 1.27)
						(thickness 0.15)
					)
					(justify left bottom)
				)
			)
			(property "Value" "Molex_PicoBlade_1x4_0533980471"
				(at 20.32 -7.62 0)
				(effects
					(font
						(size 1.27 1.27)
						(thickness 0.15)
					)
					(justify left bottom)
					(hide yes)
				)
			)
			(property "Footprint" "antmicro-footprints:Conn_Molex_PicoBlade_1x4_0533980471"
				(at 20.32 -10.16 0)
				(effects
					(font
						(size 1.27 1.27)
						(thickness 0.15)
					)
					(justify left bottom)
					(hide yes)
				)
			)
			(property "Datasheet" "https://www.molex.com/molex/products/part-detail/pcb_headers/0533980471"
				(at 20.32 -12.7 0)
				(effects
					(font
						(size 1.27 1.27)
						(thickness 0.15)
					)
					(justify left bottom)
					(hide yes)
				)
			)
			(property "Description" "Pin Header, Vertical, Signal, 1.25 mm, 1 Rows, 4 Contacts, Surface Mount Straight"
				(at 0 0 0)
				(effects
					(font
						(size 1.27 1.27)
					)
					(hide yes)
				)
			)
			(property "MPN" "0533980471"
				(at 20.32 -17.78 0)
				(effects
					(font
						(size 1.27 1.27)
						(thickness 0.15)
					)
					(justify left bottom)
				)
			)
			(property "Manufacturer" "Molex"
				(at 20.32 -15.24 0)
				(effects
					(font
						(size 1.27 1.27)
						(thickness 0.15)
					)
					(justify left bottom)
					(hide yes)
				)
			)
			(property "Author" "Antmicro"
				(at 20.32 -20.32 0)
				(effects
					(font
						(size 1.27 1.27)
						(thickness 0.15)
					)
					(justify left bottom)
					(hide yes)
				)
			)
			(property "License" "Apache-2.0"
				(at 20.32 -22.86 0)
				(effects
					(font
						(size 1.27 1.27)
						(thickness 0.15)
					)
					(justify left bottom)
					(hide yes)
				)
			)
			(property "ki_keywords" "PINSTRIP, HEADER, SMT"
				(at 0 0 0)
				(effects
					(font
						(size 1.27 1.27)
					)
					(hide yes)
				)
			)
			(symbol "Molex_PicoBlade_1x4_0533980471_1_1"
				(rectangle
					(start 3.81 -12.573)
					(end 5.08 -12.827)
					(stroke
						(width 0.254)
						(type default)
					)
					(fill
						(type background)
					)
				)
				(rectangle
					(start 3.81 -10.033)
					(end 5.08 -10.287)
					(stroke
						(width 0.254)
						(type default)
					)
					(fill
						(type background)
					)
				)
				(rectangle
					(start 3.81 -7.493)
					(end 5.08 -7.747)
					(stroke
						(width 0.254)
						(type default)
					)
					(fill
						(type background)
					)
				)
				(rectangle
					(start 3.81 -4.953)
					(end 5.08 -5.207)
					(stroke
						(width 0.254)
						(type default)
					)
					(fill
						(type background)
					)
				)
				(rectangle
					(start 3.81 -2.413)
					(end 5.08 -2.667)
					(stroke
						(width 0.254)
						(type default)
					)
					(fill
						(type background)
					)
				)
				(rectangle
					(start 3.81 0.127)
					(end 5.08 -0.127)
					(stroke
						(width 0.254)
						(type default)
					)
					(fill
						(type background)
					)
				)
				(rectangle
					(start 3.81 1.27)
					(end 6.35 -13.97)
					(stroke
						(width 0.254)
						(type default)
					)
					(fill
						(type background)
					)
				)
				(pin passive line
					(at 0 0 0)
					(length 3.81)
					(name "1"
						(effects
							(font
								(size 1.27 1.27)
							)
						)
					)
					(number "1"
						(effects
							(font
								(size 1.27 1.27)
							)
						)
					)
				)
				(pin passive line
					(at 0 -2.54 0)
					(length 3.81)
					(name "2"
						(effects
							(font
								(size 1.27 1.27)
							)
						)
					)
					(number "2"
						(effects
							(font
								(size 1.27 1.27)
							)
						)
					)
				)
				(pin passive line
					(at 0 -5.08 0)
					(length 3.81)
					(name "3"
						(effects
							(font
								(size 1.27 1.27)
							)
						)
					)
					(number "3"
						(effects
							(font
								(size 1.27 1.27)
							)
						)
					)
				)
				(pin passive line
					(at 0 -7.62 0)
					(length 3.81)
					(name "4"
						(effects
							(font
								(size 1.27 1.27)
							)
						)
					)
					(number "4"
						(effects
							(font
								(size 1.27 1.27)
							)
						)
					)
				)
				(pin passive line
					(at 0 -10.16 0)
					(length 3.81)
					(name "MP1"
						(effects
							(font
								(size 1.27 1.27)
							)
						)
					)
					(number "MP1"
						(effects
							(font
								(size 1.27 1.27)
							)
						)
					)
				)
				(pin passive line
					(at 0 -12.7 0)
					(length 3.81)
					(name "MP2"
						(effects
							(font
								(size 1.27 1.27)
							)
						)
					)
					(number "MP2"
						(effects
							(font
								(size 1.27 1.27)
							)
						)
					)
				)
			)
		)
	(symbol "antmicropower:+1V8"
			(power)
			(pin_numbers hide)
			(pin_names hide)
			(exclude_from_sim no)
			(in_bom yes)
			(on_board yes)
			(property "Reference" "#PWR"
				(at 15.24 -2.54 0)
				(effects
					(font
						(size 1.27 1.27)
						(thickness 0.15)
					)
					(justify left bottom)
					(hide yes)
				)
			)
			(property "Value" "+1V8"
				(at -3.175 2.54 0)
				(effects
					(font
						(size 1.27 1.27)
						(thickness 0.15)
					)
					(justify left bottom)
				)
			)
			(property "Footprint" ""
				(at 15.24 -7.62 0)
				(effects
					(font
						(size 1.27 1.27)
						(thickness 0.15)
					)
					(justify left bottom)
					(hide yes)
				)
			)
			(property "Datasheet" ""
				(at 15.24 -10.16 0)
				(effects
					(font
						(size 1.27 1.27)
						(thickness 0.15)
					)
					(justify left bottom)
					(hide yes)
				)
			)
			(property "Description" ""
				(at 0 0 0)
				(effects
					(font
						(size 1.27 1.27)
					)
					(hide yes)
				)
			)
			(property "Author" "Antmicro"
				(at 15.24 -5.08 0)
				(effects
					(font
						(size 1.27 1.27)
						(thickness 0.15)
					)
					(justify left bottom)
					(hide yes)
				)
			)
			(property "License" "Apache-2.0"
				(at 15.24 -7.62 0)
				(effects
					(font
						(size 1.27 1.27)
						(thickness 0.15)
					)
					(justify left bottom)
					(hide yes)
				)
			)
			(symbol "+1V8_1_1"
				(polyline
					(pts
						(xy -0.762 1.27) (xy 0 2.54)
					)
					(stroke
						(width 0)
						(type default)
					)
					(fill
						(type background)
					)
				)
				(polyline
					(pts
						(xy 0 0) (xy 0 2.54)
					)
					(stroke
						(width 0)
						(type default)
					)
					(fill
						(type background)
					)
				)
				(polyline
					(pts
						(xy 0 2.54) (xy 0.762 1.27)
					)
					(stroke
						(width 0)
						(type default)
					)
					(fill
						(type background)
					)
				)
				(pin power_in line
					(at 0 0 90)
					(length 0) hide
					(name "+1V8"
						(effects
							(font
								(size 1.27 1.27)
							)
						)
					)
					(number "1"
						(effects
							(font
								(size 1.27 1.27)
							)
						)
					)
				)
			)
		)
	(symbol "antmicropower:+3V3"
			(power)
			(pin_numbers hide)
			(pin_names hide)
			(exclude_from_sim no)
			(in_bom yes)
			(on_board yes)
			(property "Reference" "#PWR"
				(at 15.24 0 0)
				(effects
					(font
						(size 1.27 1.27)
						(thickness 0.15)
					)
					(justify left bottom)
					(hide yes)
				)
			)
			(property "Value" "+3V3"
				(at -3.175 2.54 0)
				(effects
					(font
						(size 1.27 1.27)
						(thickness 0.15)
					)
					(justify left bottom)
				)
			)
			(property "Footprint" ""
				(at 15.24 -7.62 0)
				(effects
					(font
						(size 1.27 1.27)
						(thickness 0.15)
					)
					(justify left bottom)
					(hide yes)
				)
			)
			(property "Datasheet" ""
				(at 15.24 -10.16 0)
				(effects
					(font
						(size 1.27 1.27)
						(thickness 0.15)
					)
					(justify left bottom)
					(hide yes)
				)
			)
			(property "Description" ""
				(at 0 0 0)
				(effects
					(font
						(size 1.27 1.27)
					)
					(hide yes)
				)
			)
			(property "Author" "Antmicro"
				(at 15.24 -2.54 0)
				(effects
					(font
						(size 1.27 1.27)
						(thickness 0.15)
					)
					(justify left bottom)
					(hide yes)
				)
			)
			(property "License" "Apache-2.0"
				(at 15.24 -5.08 0)
				(effects
					(font
						(size 1.27 1.27)
						(thickness 0.15)
					)
					(justify left bottom)
					(hide yes)
				)
			)
			(symbol "+3V3_0_1"
				(polyline
					(pts
						(xy 0 0) (xy 0 2.54)
					)
					(stroke
						(width 0)
						(type default)
					)
					(fill
						(type none)
					)
				)
				(polyline
					(pts
						(xy 0 2.54) (xy -0.762 1.27)
					)
					(stroke
						(width 0)
						(type default)
					)
					(fill
						(type none)
					)
				)
				(polyline
					(pts
						(xy 0 2.54) (xy 0.762 1.27)
					)
					(stroke
						(width 0)
						(type default)
					)
					(fill
						(type none)
					)
				)
			)
			(symbol "+3V3_1_1"
				(pin power_in line
					(at 0 0 90)
					(length 0) hide
					(name "+3V3"
						(effects
							(font
								(size 1.27 1.27)
							)
						)
					)
					(number "1"
						(effects
							(font
								(size 1.27 1.27)
							)
						)
					)
				)
			)
		)
	(symbol "antmicropower:+5V"
			(power)
			(pin_numbers hide)
			(pin_names hide)
			(exclude_from_sim no)
			(in_bom yes)
			(on_board yes)
			(property "Reference" "#PWR"
				(at 15.24 -2.54 0)
				(effects
					(font
						(size 1.27 1.27)
						(thickness 0.15)
					)
					(justify left bottom)
					(hide yes)
				)
			)
			(property "Value" "+5V"
				(at 15.24 -5.08 0)
				(effects
					(font
						(size 1.27 1.27)
						(thickness 0.15)
					)
					(justify left bottom)
				)
			)
			(property "Footprint" ""
				(at 15.24 -7.62 0)
				(effects
					(font
						(size 1.27 1.27)
						(thickness 0.15)
					)
					(justify left bottom)
					(hide yes)
				)
			)
			(property "Datasheet" ""
				(at 15.24 -10.16 0)
				(effects
					(font
						(size 1.27 1.27)
						(thickness 0.15)
					)
					(justify left bottom)
					(hide yes)
				)
			)
			(property "Description" ""
				(at 0 0 0)
				(effects
					(font
						(size 1.27 1.27)
					)
					(hide yes)
				)
			)
			(property "Author" "Antmicro"
				(at 15.24 -7.62 0)
				(effects
					(font
						(size 1.27 1.27)
						(thickness 0.15)
					)
					(justify left bottom)
					(hide yes)
				)
			)
			(property "License" "Apache-2.0"
				(at 15.24 -10.16 0)
				(effects
					(font
						(size 1.27 1.27)
						(thickness 0.15)
					)
					(justify left bottom)
					(hide yes)
				)
			)
			(symbol "+5V_1_1"
				(polyline
					(pts
						(xy -0.762 1.27) (xy 0 2.54)
					)
					(stroke
						(width 0)
						(type default)
					)
					(fill
						(type background)
					)
				)
				(polyline
					(pts
						(xy 0 0) (xy 0 2.54)
					)
					(stroke
						(width 0)
						(type default)
					)
					(fill
						(type background)
					)
				)
				(polyline
					(pts
						(xy 0 2.54) (xy 0.762 1.27)
					)
					(stroke
						(width 0)
						(type default)
					)
					(fill
						(type background)
					)
				)
				(pin power_in line
					(at 0 0 90)
					(length 0)
					(name "+5V"
						(effects
							(font
								(size 1.27 1.27)
							)
						)
					)
					(number "1"
						(effects
							(font
								(size 1.27 1.27)
							)
						)
					)
				)
			)
		)
	(symbol "antmicropower:GND"
			(power)
			(pin_numbers hide)
			(pin_names hide)
			(exclude_from_sim no)
			(in_bom yes)
			(on_board yes)
			(property "Reference" "#PWR"
				(at 8.89 -2.54 0)
				(effects
					(font
						(size 1.27 1.27)
						(thickness 0.15)
					)
					(justify left bottom)
					(hide yes)
				)
			)
			(property "Value" "GND"
				(at 8.89 -5.08 0)
				(effects
					(font
						(size 1.27 1.27)
						(thickness 0.15)
					)
					(justify left bottom)
				)
			)
			(property "Footprint" ""
				(at 8.89 -7.62 0)
				(effects
					(font
						(size 1.27 1.27)
						(thickness 0.15)
					)
					(justify left bottom)
					(hide yes)
				)
			)
			(property "Datasheet" ""
				(at 8.89 -12.7 0)
				(effects
					(font
						(size 1.27 1.27)
						(thickness 0.15)
					)
					(justify left bottom)
					(hide yes)
				)
			)
			(property "Description" ""
				(at 0 0 0)
				(effects
					(font
						(size 1.27 1.27)
					)
					(hide yes)
				)
			)
			(property "Author" "Antmicro"
				(at 8.89 -7.62 0)
				(effects
					(font
						(size 1.27 1.27)
						(thickness 0.15)
					)
					(justify left bottom)
					(hide yes)
				)
			)
			(property "License" "Apache-2.0"
				(at 8.89 -10.16 0)
				(effects
					(font
						(size 1.27 1.27)
						(thickness 0.15)
					)
					(justify left bottom)
					(hide yes)
				)
			)
			(symbol "GND_1_1"
				(polyline
					(pts
						(xy 0 0) (xy 0 -1.27) (xy 1.27 -1.27) (xy 0 -2.54) (xy -1.27 -1.27) (xy 0 -1.27)
					)
					(stroke
						(width 0)
						(type default)
					)
					(fill
						(type none)
					)
				)
				(pin power_in line
					(at 0 0 270)
					(length 0)
					(name "GND"
						(effects
							(font
								(size 1.27 1.27)
							)
						)
					)
					(number "1"
						(effects
							(font
								(size 1.27 1.27)
							)
						)
					)
				)
			)
		)
	(symbol "antmicropower:GNDD"
			(power)
			(pin_numbers hide)
			(pin_names hide)
			(exclude_from_sim no)
			(in_bom yes)
			(on_board yes)
			(property "Reference" "#PWR"
				(at 15.24 -2.54 0)
				(effects
					(font
						(size 1.27 1.27)
						(thickness 0.15)
					)
					(justify left bottom)
					(hide yes)
				)
			)
			(property "Value" "GNDD"
				(at 15.24 -5.08 0)
				(effects
					(font
						(size 1.27 1.27)
						(thickness 0.15)
					)
					(justify left bottom)
				)
			)
			(property "Footprint" ""
				(at 15.24 -10.16 0)
				(effects
					(font
						(size 1.27 1.27)
						(thickness 0.15)
					)
					(justify left bottom)
					(hide yes)
				)
			)
			(property "Datasheet" ""
				(at 15.24 -12.7 0)
				(effects
					(font
						(size 1.27 1.27)
						(thickness 0.15)
					)
					(justify left bottom)
					(hide yes)
				)
			)
			(property "Description" ""
				(at 0 0 0)
				(effects
					(font
						(size 1.27 1.27)
					)
					(hide yes)
				)
			)
			(property "Author" "Antmicro"
				(at 15.24 -7.62 0)
				(effects
					(font
						(size 1.27 1.27)
						(thickness 0.15)
					)
					(justify left bottom)
					(hide yes)
				)
			)
			(property "License" "Apache-2.0"
				(at 15.24 -10.16 0)
				(effects
					(font
						(size 1.27 1.27)
						(thickness 0.15)
					)
					(justify left bottom)
					(hide yes)
				)
			)
			(symbol "GNDD_1_1"
				(rectangle
					(start -1.27 -1.524)
					(end 1.27 -2.032)
					(stroke
						(width 0)
						(type default)
					)
					(fill
						(type outline)
					)
				)
				(polyline
					(pts
						(xy 0 0) (xy 0 -1.524)
					)
					(stroke
						(width 0)
						(type default)
					)
					(fill
						(type background)
					)
				)
				(pin power_in line
					(at 0 0 270)
					(length 0)
					(name "GNDD"
						(effects
							(font
								(size 1.27 1.27)
							)
						)
					)
					(number "1"
						(effects
							(font
								(size 1.27 1.27)
							)
						)
					)
				)
			)
		)
	(symbol "antmicropower:PWR_FLAG"
			(power)
			(pin_numbers hide)
			(pin_names
				(offset 0) hide)
			(exclude_from_sim no)
			(in_bom yes)
			(on_board yes)
			(property "Reference" "#FLG"
				(at 0 1.905 0)
				(effects
					(font
						(size 1.27 1.27)
					)
					(hide yes)
				)
			)
			(property "Value" "PWR_FLAG"
				(at 0 3.81 0)
				(effects
					(font
						(size 1.27 1.27)
					)
				)
			)
			(property "Footprint" ""
				(at 0 0 0)
				(effects
					(font
						(size 1.27 1.27)
					)
					(hide yes)
				)
			)
			(property "Datasheet" ""
				(at 0 0 0)
				(effects
					(font
						(size 1.27 1.27)
					)
					(hide yes)
				)
			)
			(property "Description" ""
				(at 0 0 0)
				(effects
					(font
						(size 1.27 1.27)
					)
					(hide yes)
				)
			)
			(symbol "PWR_FLAG_0_0"
				(pin power_out line
					(at 0 0 90)
					(length 0)
					(name "pwr"
						(effects
							(font
								(size 1.27 1.27)
							)
						)
					)
					(number "1"
						(effects
							(font
								(size 1.27 1.27)
							)
						)
					)
				)
			)
			(symbol "PWR_FLAG_0_1"
				(polyline
					(pts
						(xy 0 0) (xy 0 1.27) (xy -1.016 1.905) (xy 0 2.54) (xy 1.016 1.905) (xy 0 1.27)
					)
					(stroke
						(width 0)
						(type default)
					)
					(fill
						(type none)
					)
				)
			)
		)
	(symbol "antmicropower:VCC"
			(power)
			(pin_names
				(offset 0)
			)
			(exclude_from_sim no)
			(in_bom yes)
			(on_board yes)
			(property "Reference" "#PWR"
				(at 0 -3.81 0)
				(effects
					(font
						(size 1.27 1.27)
					)
					(hide yes)
				)
			)
			(property "Value" "VCC"
				(at 0 3.81 0)
				(effects
					(font
						(size 1.27 1.27)
					)
				)
			)
			(property "Footprint" ""
				(at 0 0 0)
				(effects
					(font
						(size 1.27 1.27)
					)
					(hide yes)
				)
			)
			(property "Datasheet" ""
				(at 0 0 0)
				(effects
					(font
						(size 1.27 1.27)
					)
					(hide yes)
				)
			)
			(property "Description" ""
				(at 0 0 0)
				(effects
					(font
						(size 1.27 1.27)
					)
					(hide yes)
				)
			)
			(symbol "VCC_0_1"
				(polyline
					(pts
						(xy -0.762 1.27) (xy 0 2.54)
					)
					(stroke
						(width 0)
						(type default)
					)
					(fill
						(type none)
					)
				)
				(polyline
					(pts
						(xy 0 0) (xy 0 2.54)
					)
					(stroke
						(width 0)
						(type default)
					)
					(fill
						(type none)
					)
				)
				(polyline
					(pts
						(xy 0 2.54) (xy 0.762 1.27)
					)
					(stroke
						(width 0)
						(type default)
					)
					(fill
						(type none)
					)
				)
			)
			(symbol "VCC_1_1"
				(pin power_in line
					(at 0 0 90)
					(length 0) hide
					(name "VCC"
						(effects
							(font
								(size 1.27 1.27)
							)
						)
					)
					(number "1"
						(effects
							(font
								(size 1.27 1.27)
							)
						)
					)
				)
			)
		)
	(symbol "jetson-orin-baseboard:AP22615_1"
			(exclude_from_sim no)
			(in_bom yes)
			(on_board yes)
			(property "Reference" "U"
				(at 0 8.89 0)
				(effects
					(font
						(size 1.27 1.27)
					)
				)
			)
			(property "Value" "AP22615_1"
				(at 0 6.35 0)
				(effects
					(font
						(size 1.27 1.27)
					)
				)
			)
			(property "Footprint" "jetson-orin-baseboard-footprints:TSOT23-6"
				(at 1.27 -26.67 0)
				(effects
					(font
						(size 1.27 1.27)
					)
					(hide yes)
				)
			)
			(property "Datasheet" "https://www.mouser.pl/datasheet/2/115/DIOD_S_A0008958405_1-2543193.pdf"
				(at 0 -29.21 0)
				(effects
					(font
						(size 1.27 1.27)
					)
					(hide yes)
				)
			)
			(property "Description" "SINGLE CHANNEL POWER DISTRIBUTION SWITCH WITH OUTPUT OVERVOLTAGE, OVERCURRENT, SHORT-CIRCUIT AND OVERTEMPERATURE PROTECTION, Supports USB PD 3.0 FAST ROLE-SWAP"
				(at 0 0 0)
				(effects
					(font
						(size 1.27 1.27)
					)
					(hide yes)
				)
			)
			(property "MPN" "AP22615AWU-7 "
				(at 5.08 -24.13 0)
				(effects
					(font
						(size 1.27 1.27)
					)
					(hide yes)
				)
			)
			(property "Manufacturer" "DIODES"
				(at -3.81 -24.13 0)
				(effects
					(font
						(size 1.27 1.27)
					)
					(hide yes)
				)
			)
			(property "ki_keywords" "single channel power distribution switch output ovp"
				(at 0 0 0)
				(effects
					(font
						(size 1.27 1.27)
					)
					(hide yes)
				)
			)
			(symbol "AP22615_1_0_1"
				(rectangle
					(start -5.08 5.08)
					(end 5.08 -5.08)
					(stroke
						(width 0)
						(type default)
					)
					(fill
						(type background)
					)
				)
			)
			(symbol "AP22615_1_1_1"
				(pin power_out line
					(at 7.62 2.54 180)
					(length 2.54)
					(name "OUT"
						(effects
							(font
								(size 1.27 1.27)
							)
						)
					)
					(number "1"
						(effects
							(font
								(size 1.27 1.27)
							)
						)
					)
				)
				(pin power_in line
					(at 7.62 -2.54 180)
					(length 2.54)
					(name "GND"
						(effects
							(font
								(size 1.27 1.27)
							)
						)
					)
					(number "2"
						(effects
							(font
								(size 1.27 1.27)
							)
						)
					)
				)
				(pin output line
					(at -7.62 0 0)
					(length 2.54)
					(name "FLG"
						(effects
							(font
								(size 1.27 1.27)
							)
						)
					)
					(number "3"
						(effects
							(font
								(size 1.27 1.27)
							)
						)
					)
				)
				(pin input line
					(at -7.62 -2.54 0)
					(length 2.54)
					(name "EN"
						(effects
							(font
								(size 1.27 1.27)
							)
						)
					)
					(number "4"
						(effects
							(font
								(size 1.27 1.27)
							)
						)
					)
				)
				(pin passive line
					(at 7.62 0 180)
					(length 2.54)
					(name "ISET"
						(effects
							(font
								(size 1.27 1.27)
							)
						)
					)
					(number "5"
						(effects
							(font
								(size 1.27 1.27)
							)
						)
					)
				)
				(pin power_in line
					(at -7.62 2.54 0)
					(length 2.54)
					(name "IN"
						(effects
							(font
								(size 1.27 1.27)
							)
						)
					)
					(number "6"
						(effects
							(font
								(size 1.27 1.27)
							)
						)
					)
				)
			)
		)
	(symbol "jetson-orin-baseboard:GNDD_10"
			(power)
			(pin_numbers hide)
			(pin_names hide)
			(exclude_from_sim no)
			(in_bom yes)
			(on_board yes)
			(property "Reference" "#PWR"
				(at 15.24 -2.54 0)
				(effects
					(font
						(size 1.27 1.27)
						(thickness 0.15)
					)
					(justify left bottom)
				)
			)
			(property "Value" "GNDD_10"
				(at 15.24 -5.08 0)
				(effects
					(font
						(size 1.27 1.27)
						(thickness 0.15)
					)
					(justify left bottom)
					(hide yes)
				)
			)
			(property "Footprint" ""
				(at 15.24 -10.16 0)
				(effects
					(font
						(size 1.27 1.27)
						(thickness 0.15)
					)
					(justify left bottom)
					(hide yes)
				)
			)
			(property "Datasheet" ""
				(at 15.24 -12.7 0)
				(effects
					(font
						(size 1.27 1.27)
						(thickness 0.15)
					)
					(justify left bottom)
					(hide yes)
				)
			)
			(property "Description" ""
				(at 0 0 0)
				(effects
					(font
						(size 1.27 1.27)
					)
					(hide yes)
				)
			)
			(property "Author" "Antmicro"
				(at 15.24 -7.62 0)
				(effects
					(font
						(size 1.27 1.27)
						(thickness 0.15)
					)
					(justify left bottom)
					(hide yes)
				)
			)
			(property "License" "Apache-2.0"
				(at 15.24 -10.16 0)
				(effects
					(font
						(size 1.27 1.27)
						(thickness 0.15)
					)
					(justify left bottom)
					(hide yes)
				)
			)
			(symbol "GNDD_10_1_1"
				(rectangle
					(start -1.27 -1.524)
					(end 1.27 -2.032)
					(stroke
						(width 0.254)
						(type default)
					)
					(fill
						(type outline)
					)
				)
				(polyline
					(pts
						(xy 0 0) (xy 0 -1.524)
					)
					(stroke
						(width 0.254)
						(type default)
					)
					(fill
						(type background)
					)
				)
				(pin power_in line
					(at 0 0 270)
					(length 0)
					(name "GNDD"
						(effects
							(font
								(size 1.27 1.27)
							)
						)
					)
					(number "1"
						(effects
							(font
								(size 1.27 1.27)
							)
						)
					)
				)
			)
		)
	(symbol "jetson-orin-baseboard:GND_10"
			(power)
			(pin_numbers hide)
			(pin_names hide)
			(exclude_from_sim no)
			(in_bom yes)
			(on_board yes)
			(property "Reference" "#PWR"
				(at 8.89 -2.54 0)
				(effects
					(font
						(size 1.27 1.27)
						(thickness 0.15)
					)
					(justify left bottom)
				)
			)
			(property "Value" "GND_10"
				(at 8.89 -5.08 0)
				(effects
					(font
						(size 1.27 1.27)
						(thickness 0.15)
					)
					(justify left bottom)
					(hide yes)
				)
			)
			(property "Footprint" ""
				(at 8.89 -7.62 0)
				(effects
					(font
						(size 1.27 1.27)
						(thickness 0.15)
					)
					(justify left bottom)
					(hide yes)
				)
			)
			(property "Datasheet" ""
				(at 8.89 -12.7 0)
				(effects
					(font
						(size 1.27 1.27)
						(thickness 0.15)
					)
					(justify left bottom)
					(hide yes)
				)
			)
			(property "Description" ""
				(at 0 0 0)
				(effects
					(font
						(size 1.27 1.27)
					)
					(hide yes)
				)
			)
			(property "Author" "Antmicro"
				(at 8.89 -7.62 0)
				(effects
					(font
						(size 1.27 1.27)
						(thickness 0.15)
					)
					(justify left bottom)
					(hide yes)
				)
			)
			(property "License" "Apache-2.0"
				(at 8.89 -10.16 0)
				(effects
					(font
						(size 1.27 1.27)
						(thickness 0.15)
					)
					(justify left bottom)
					(hide yes)
				)
			)
			(symbol "GND_10_1_1"
				(polyline
					(pts
						(xy 0 0) (xy 0 -1.27) (xy 1.27 -1.27) (xy 0 -2.54) (xy -1.27 -1.27) (xy 0 -1.27)
					)
					(stroke
						(width 0.254)
						(type default)
					)
					(fill
						(type none)
					)
				)
				(pin power_in line
					(at 0 0 270)
					(length 0)
					(name "GND"
						(effects
							(font
								(size 1.27 1.27)
							)
						)
					)
					(number "1"
						(effects
							(font
								(size 1.27 1.27)
							)
						)
					)
				)
			)
		)
	(symbol "jetson-orin-baseboard:GND_11"
			(power)
			(pin_numbers hide)
			(pin_names hide)
			(exclude_from_sim no)
			(in_bom yes)
			(on_board yes)
			(property "Reference" "#PWR"
				(at 8.89 -2.54 0)
				(effects
					(font
						(size 1.27 1.27)
						(thickness 0.15)
					)
					(justify left bottom)
				)
			)
			(property "Value" "GND_11"
				(at 8.89 -5.08 0)
				(effects
					(font
						(size 1.27 1.27)
						(thickness 0.15)
					)
					(justify left bottom)
					(hide yes)
				)
			)
			(property "Footprint" ""
				(at 8.89 -7.62 0)
				(effects
					(font
						(size 1.27 1.27)
						(thickness 0.15)
					)
					(justify left bottom)
					(hide yes)
				)
			)
			(property "Datasheet" ""
				(at 8.89 -12.7 0)
				(effects
					(font
						(size 1.27 1.27)
						(thickness 0.15)
					)
					(justify left bottom)
					(hide yes)
				)
			)
			(property "Description" ""
				(at 0 0 0)
				(effects
					(font
						(size 1.27 1.27)
					)
					(hide yes)
				)
			)
			(property "Author" "Antmicro"
				(at 8.89 -7.62 0)
				(effects
					(font
						(size 1.27 1.27)
						(thickness 0.15)
					)
					(justify left bottom)
					(hide yes)
				)
			)
			(property "License" "Apache-2.0"
				(at 8.89 -10.16 0)
				(effects
					(font
						(size 1.27 1.27)
						(thickness 0.15)
					)
					(justify left bottom)
					(hide yes)
				)
			)
			(symbol "GND_11_1_1"
				(polyline
					(pts
						(xy 0 0) (xy 0 -1.27) (xy 1.27 -1.27) (xy 0 -2.54) (xy -1.27 -1.27) (xy 0 -1.27)
					)
					(stroke
						(width 0.254)
						(type default)
					)
					(fill
						(type none)
					)
				)
				(pin power_in line
					(at 0 0 270)
					(length 0)
					(name "GND"
						(effects
							(font
								(size 1.27 1.27)
							)
						)
					)
					(number "1"
						(effects
							(font
								(size 1.27 1.27)
							)
						)
					)
				)
			)
		)
	(symbol "jetson-orin-baseboard:GND_12"
			(power)
			(pin_numbers hide)
			(pin_names hide)
			(exclude_from_sim no)
			(in_bom yes)
			(on_board yes)
			(property "Reference" "#PWR"
				(at 8.89 -2.54 0)
				(effects
					(font
						(size 1.27 1.27)
						(thickness 0.15)
					)
					(justify left bottom)
				)
			)
			(property "Value" "GND_12"
				(at 8.89 -5.08 0)
				(effects
					(font
						(size 1.27 1.27)
						(thickness 0.15)
					)
					(justify left bottom)
					(hide yes)
				)
			)
			(property "Footprint" ""
				(at 8.89 -7.62 0)
				(effects
					(font
						(size 1.27 1.27)
						(thickness 0.15)
					)
					(justify left bottom)
					(hide yes)
				)
			)
			(property "Datasheet" ""
				(at 8.89 -12.7 0)
				(effects
					(font
						(size 1.27 1.27)
						(thickness 0.15)
					)
					(justify left bottom)
					(hide yes)
				)
			)
			(property "Description" ""
				(at 0 0 0)
				(effects
					(font
						(size 1.27 1.27)
					)
					(hide yes)
				)
			)
			(property "Author" "Antmicro"
				(at 8.89 -7.62 0)
				(effects
					(font
						(size 1.27 1.27)
						(thickness 0.15)
					)
					(justify left bottom)
					(hide yes)
				)
			)
			(property "License" "Apache-2.0"
				(at 8.89 -10.16 0)
				(effects
					(font
						(size 1.27 1.27)
						(thickness 0.15)
					)
					(justify left bottom)
					(hide yes)
				)
			)
			(symbol "GND_12_1_1"
				(polyline
					(pts
						(xy 0 0) (xy 0 -1.27) (xy 1.27 -1.27) (xy 0 -2.54) (xy -1.27 -1.27) (xy 0 -1.27)
					)
					(stroke
						(width 0.254)
						(type default)
					)
					(fill
						(type none)
					)
				)
				(pin power_in line
					(at 0 0 270)
					(length 0)
					(name "GND"
						(effects
							(font
								(size 1.27 1.27)
							)
						)
					)
					(number "1"
						(effects
							(font
								(size 1.27 1.27)
							)
						)
					)
				)
			)
		)
	(symbol "jetson-orin-baseboard:GND_13"
			(power)
			(pin_numbers hide)
			(pin_names hide)
			(exclude_from_sim no)
			(in_bom yes)
			(on_board yes)
			(property "Reference" "#PWR"
				(at 8.89 -2.54 0)
				(effects
					(font
						(size 1.27 1.27)
						(thickness 0.15)
					)
					(justify left bottom)
				)
			)
			(property "Value" "GND_13"
				(at 8.89 -5.08 0)
				(effects
					(font
						(size 1.27 1.27)
						(thickness 0.15)
					)
					(justify left bottom)
					(hide yes)
				)
			)
			(property "Footprint" ""
				(at 8.89 -7.62 0)
				(effects
					(font
						(size 1.27 1.27)
						(thickness 0.15)
					)
					(justify left bottom)
					(hide yes)
				)
			)
			(property "Datasheet" ""
				(at 8.89 -12.7 0)
				(effects
					(font
						(size 1.27 1.27)
						(thickness 0.15)
					)
					(justify left bottom)
					(hide yes)
				)
			)
			(property "Description" ""
				(at 0 0 0)
				(effects
					(font
						(size 1.27 1.27)
					)
					(hide yes)
				)
			)
			(property "Author" "Antmicro"
				(at 8.89 -7.62 0)
				(effects
					(font
						(size 1.27 1.27)
						(thickness 0.15)
					)
					(justify left bottom)
					(hide yes)
				)
			)
			(property "License" "Apache-2.0"
				(at 8.89 -10.16 0)
				(effects
					(font
						(size 1.27 1.27)
						(thickness 0.15)
					)
					(justify left bottom)
					(hide yes)
				)
			)
			(symbol "GND_13_1_1"
				(polyline
					(pts
						(xy 0 0) (xy 0 -1.27) (xy 1.27 -1.27) (xy 0 -2.54) (xy -1.27 -1.27) (xy 0 -1.27)
					)
					(stroke
						(width 0.254)
						(type default)
					)
					(fill
						(type none)
					)
				)
				(pin power_in line
					(at 0 0 270)
					(length 0)
					(name "GND"
						(effects
							(font
								(size 1.27 1.27)
							)
						)
					)
					(number "1"
						(effects
							(font
								(size 1.27 1.27)
							)
						)
					)
				)
			)
		)
	(symbol "jetson-orin-baseboard:GND_14"
			(power)
			(pin_numbers hide)
			(pin_names hide)
			(exclude_from_sim no)
			(in_bom yes)
			(on_board yes)
			(property "Reference" "#PWR"
				(at 8.89 -2.54 0)
				(effects
					(font
						(size 1.27 1.27)
						(thickness 0.15)
					)
					(justify left bottom)
				)
			)
			(property "Value" "GND_14"
				(at 8.89 -5.08 0)
				(effects
					(font
						(size 1.27 1.27)
						(thickness 0.15)
					)
					(justify left bottom)
					(hide yes)
				)
			)
			(property "Footprint" ""
				(at 8.89 -7.62 0)
				(effects
					(font
						(size 1.27 1.27)
						(thickness 0.15)
					)
					(justify left bottom)
					(hide yes)
				)
			)
			(property "Datasheet" ""
				(at 8.89 -12.7 0)
				(effects
					(font
						(size 1.27 1.27)
						(thickness 0.15)
					)
					(justify left bottom)
					(hide yes)
				)
			)
			(property "Description" ""
				(at 0 0 0)
				(effects
					(font
						(size 1.27 1.27)
					)
					(hide yes)
				)
			)
			(property "Author" "Antmicro"
				(at 8.89 -7.62 0)
				(effects
					(font
						(size 1.27 1.27)
						(thickness 0.15)
					)
					(justify left bottom)
					(hide yes)
				)
			)
			(property "License" "Apache-2.0"
				(at 8.89 -10.16 0)
				(effects
					(font
						(size 1.27 1.27)
						(thickness 0.15)
					)
					(justify left bottom)
					(hide yes)
				)
			)
			(symbol "GND_14_1_1"
				(polyline
					(pts
						(xy 0 0) (xy 0 -1.27) (xy 1.27 -1.27) (xy 0 -2.54) (xy -1.27 -1.27) (xy 0 -1.27)
					)
					(stroke
						(width 0.254)
						(type default)
					)
					(fill
						(type none)
					)
				)
				(pin power_in line
					(at 0 0 270)
					(length 0)
					(name "GND"
						(effects
							(font
								(size 1.27 1.27)
							)
						)
					)
					(number "1"
						(effects
							(font
								(size 1.27 1.27)
							)
						)
					)
				)
			)
		)
	(symbol "jetson-orin-baseboard:GND_15"
			(power)
			(pin_numbers hide)
			(pin_names hide)
			(exclude_from_sim no)
			(in_bom yes)
			(on_board yes)
			(property "Reference" "#PWR"
				(at 8.89 -2.54 0)
				(effects
					(font
						(size 1.27 1.27)
						(thickness 0.15)
					)
					(justify left bottom)
				)
			)
			(property "Value" "GND_15"
				(at 8.89 -5.08 0)
				(effects
					(font
						(size 1.27 1.27)
						(thickness 0.15)
					)
					(justify left bottom)
					(hide yes)
				)
			)
			(property "Footprint" ""
				(at 8.89 -7.62 0)
				(effects
					(font
						(size 1.27 1.27)
						(thickness 0.15)
					)
					(justify left bottom)
					(hide yes)
				)
			)
			(property "Datasheet" ""
				(at 8.89 -12.7 0)
				(effects
					(font
						(size 1.27 1.27)
						(thickness 0.15)
					)
					(justify left bottom)
					(hide yes)
				)
			)
			(property "Description" ""
				(at 0 0 0)
				(effects
					(font
						(size 1.27 1.27)
					)
					(hide yes)
				)
			)
			(property "Author" "Antmicro"
				(at 8.89 -7.62 0)
				(effects
					(font
						(size 1.27 1.27)
						(thickness 0.15)
					)
					(justify left bottom)
					(hide yes)
				)
			)
			(property "License" "Apache-2.0"
				(at 8.89 -10.16 0)
				(effects
					(font
						(size 1.27 1.27)
						(thickness 0.15)
					)
					(justify left bottom)
					(hide yes)
				)
			)
			(symbol "GND_15_1_1"
				(polyline
					(pts
						(xy 0 0) (xy 0 -1.27) (xy 1.27 -1.27) (xy 0 -2.54) (xy -1.27 -1.27) (xy 0 -1.27)
					)
					(stroke
						(width 0.254)
						(type default)
					)
					(fill
						(type none)
					)
				)
				(pin power_in line
					(at 0 0 270)
					(length 0)
					(name "GND"
						(effects
							(font
								(size 1.27 1.27)
							)
						)
					)
					(number "1"
						(effects
							(font
								(size 1.27 1.27)
							)
						)
					)
				)
			)
		)
	(symbol "jetson-orin-baseboard:GND_16"
			(power)
			(pin_numbers hide)
			(pin_names hide)
			(exclude_from_sim no)
			(in_bom yes)
			(on_board yes)
			(property "Reference" "#PWR"
				(at 8.89 -2.54 0)
				(effects
					(font
						(size 1.27 1.27)
						(thickness 0.15)
					)
					(justify left bottom)
				)
			)
			(property "Value" "GND_16"
				(at 8.89 -5.08 0)
				(effects
					(font
						(size 1.27 1.27)
						(thickness 0.15)
					)
					(justify left bottom)
					(hide yes)
				)
			)
			(property "Footprint" ""
				(at 8.89 -7.62 0)
				(effects
					(font
						(size 1.27 1.27)
						(thickness 0.15)
					)
					(justify left bottom)
					(hide yes)
				)
			)
			(property "Datasheet" ""
				(at 8.89 -12.7 0)
				(effects
					(font
						(size 1.27 1.27)
						(thickness 0.15)
					)
					(justify left bottom)
					(hide yes)
				)
			)
			(property "Description" ""
				(at 0 0 0)
				(effects
					(font
						(size 1.27 1.27)
					)
					(hide yes)
				)
			)
			(property "Author" "Antmicro"
				(at 8.89 -7.62 0)
				(effects
					(font
						(size 1.27 1.27)
						(thickness 0.15)
					)
					(justify left bottom)
					(hide yes)
				)
			)
			(property "License" "Apache-2.0"
				(at 8.89 -10.16 0)
				(effects
					(font
						(size 1.27 1.27)
						(thickness 0.15)
					)
					(justify left bottom)
					(hide yes)
				)
			)
			(symbol "GND_16_1_1"
				(polyline
					(pts
						(xy 0 0) (xy 0 -1.27) (xy 1.27 -1.27) (xy 0 -2.54) (xy -1.27 -1.27) (xy 0 -1.27)
					)
					(stroke
						(width 0.254)
						(type default)
					)
					(fill
						(type none)
					)
				)
				(pin power_in line
					(at 0 0 270)
					(length 0)
					(name "GND"
						(effects
							(font
								(size 1.27 1.27)
							)
						)
					)
					(number "1"
						(effects
							(font
								(size 1.27 1.27)
							)
						)
					)
				)
			)
		)
	(symbol "jetson-orin-baseboard:GND_17"
			(power)
			(pin_numbers hide)
			(pin_names hide)
			(exclude_from_sim no)
			(in_bom yes)
			(on_board yes)
			(property "Reference" "#PWR"
				(at 8.89 -2.54 0)
				(effects
					(font
						(size 1.27 1.27)
						(thickness 0.15)
					)
					(justify left bottom)
				)
			)
			(property "Value" "GND_17"
				(at 8.89 -5.08 0)
				(effects
					(font
						(size 1.27 1.27)
						(thickness 0.15)
					)
					(justify left bottom)
					(hide yes)
				)
			)
			(property "Footprint" ""
				(at 8.89 -7.62 0)
				(effects
					(font
						(size 1.27 1.27)
						(thickness 0.15)
					)
					(justify left bottom)
					(hide yes)
				)
			)
			(property "Datasheet" ""
				(at 8.89 -12.7 0)
				(effects
					(font
						(size 1.27 1.27)
						(thickness 0.15)
					)
					(justify left bottom)
					(hide yes)
				)
			)
			(property "Description" ""
				(at 0 0 0)
				(effects
					(font
						(size 1.27 1.27)
					)
					(hide yes)
				)
			)
			(property "Author" "Antmicro"
				(at 8.89 -7.62 0)
				(effects
					(font
						(size 1.27 1.27)
						(thickness 0.15)
					)
					(justify left bottom)
					(hide yes)
				)
			)
			(property "License" "Apache-2.0"
				(at 8.89 -10.16 0)
				(effects
					(font
						(size 1.27 1.27)
						(thickness 0.15)
					)
					(justify left bottom)
					(hide yes)
				)
			)
			(symbol "GND_17_1_1"
				(polyline
					(pts
						(xy 0 0) (xy 0 -1.27) (xy 1.27 -1.27) (xy 0 -2.54) (xy -1.27 -1.27) (xy 0 -1.27)
					)
					(stroke
						(width 0.254)
						(type default)
					)
					(fill
						(type none)
					)
				)
				(pin power_in line
					(at 0 0 270)
					(length 0)
					(name "GND"
						(effects
							(font
								(size 1.27 1.27)
							)
						)
					)
					(number "1"
						(effects
							(font
								(size 1.27 1.27)
							)
						)
					)
				)
			)
		)
	(symbol "jetson-orin-baseboard:GND_18"
			(power)
			(pin_numbers hide)
			(pin_names hide)
			(exclude_from_sim no)
			(in_bom yes)
			(on_board yes)
			(property "Reference" "#PWR"
				(at 8.89 -2.54 0)
				(effects
					(font
						(size 1.27 1.27)
						(thickness 0.15)
					)
					(justify left bottom)
				)
			)
			(property "Value" "GND_18"
				(at 8.89 -5.08 0)
				(effects
					(font
						(size 1.27 1.27)
						(thickness 0.15)
					)
					(justify left bottom)
					(hide yes)
				)
			)
			(property "Footprint" ""
				(at 8.89 -7.62 0)
				(effects
					(font
						(size 1.27 1.27)
						(thickness 0.15)
					)
					(justify left bottom)
					(hide yes)
				)
			)
			(property "Datasheet" ""
				(at 8.89 -12.7 0)
				(effects
					(font
						(size 1.27 1.27)
						(thickness 0.15)
					)
					(justify left bottom)
					(hide yes)
				)
			)
			(property "Description" ""
				(at 0 0 0)
				(effects
					(font
						(size 1.27 1.27)
					)
					(hide yes)
				)
			)
			(property "Author" "Antmicro"
				(at 8.89 -7.62 0)
				(effects
					(font
						(size 1.27 1.27)
						(thickness 0.15)
					)
					(justify left bottom)
					(hide yes)
				)
			)
			(property "License" "Apache-2.0"
				(at 8.89 -10.16 0)
				(effects
					(font
						(size 1.27 1.27)
						(thickness 0.15)
					)
					(justify left bottom)
					(hide yes)
				)
			)
			(symbol "GND_18_1_1"
				(polyline
					(pts
						(xy 0 0) (xy 0 -1.27) (xy 1.27 -1.27) (xy 0 -2.54) (xy -1.27 -1.27) (xy 0 -1.27)
					)
					(stroke
						(width 0.254)
						(type default)
					)
					(fill
						(type none)
					)
				)
				(pin power_in line
					(at 0 0 270)
					(length 0)
					(name "GND"
						(effects
							(font
								(size 1.27 1.27)
							)
						)
					)
					(number "1"
						(effects
							(font
								(size 1.27 1.27)
							)
						)
					)
				)
			)
		)
	(symbol "jetson-orin-baseboard:GND_19"
			(power)
			(pin_numbers hide)
			(pin_names hide)
			(exclude_from_sim no)
			(in_bom yes)
			(on_board yes)
			(property "Reference" "#PWR"
				(at 8.89 -2.54 0)
				(effects
					(font
						(size 1.27 1.27)
						(thickness 0.15)
					)
					(justify left bottom)
				)
			)
			(property "Value" "GND_19"
				(at 8.89 -5.08 0)
				(effects
					(font
						(size 1.27 1.27)
						(thickness 0.15)
					)
					(justify left bottom)
					(hide yes)
				)
			)
			(property "Footprint" ""
				(at 8.89 -7.62 0)
				(effects
					(font
						(size 1.27 1.27)
						(thickness 0.15)
					)
					(justify left bottom)
					(hide yes)
				)
			)
			(property "Datasheet" ""
				(at 8.89 -12.7 0)
				(effects
					(font
						(size 1.27 1.27)
						(thickness 0.15)
					)
					(justify left bottom)
					(hide yes)
				)
			)
			(property "Description" ""
				(at 0 0 0)
				(effects
					(font
						(size 1.27 1.27)
					)
					(hide yes)
				)
			)
			(property "Author" "Antmicro"
				(at 8.89 -7.62 0)
				(effects
					(font
						(size 1.27 1.27)
						(thickness 0.15)
					)
					(justify left bottom)
					(hide yes)
				)
			)
			(property "License" "Apache-2.0"
				(at 8.89 -10.16 0)
				(effects
					(font
						(size 1.27 1.27)
						(thickness 0.15)
					)
					(justify left bottom)
					(hide yes)
				)
			)
			(symbol "GND_19_1_1"
				(polyline
					(pts
						(xy 0 0) (xy 0 -1.27) (xy 1.27 -1.27) (xy 0 -2.54) (xy -1.27 -1.27) (xy 0 -1.27)
					)
					(stroke
						(width 0.254)
						(type default)
					)
					(fill
						(type none)
					)
				)
				(pin power_in line
					(at 0 0 270)
					(length 0)
					(name "GND"
						(effects
							(font
								(size 1.27 1.27)
							)
						)
					)
					(number "1"
						(effects
							(font
								(size 1.27 1.27)
							)
						)
					)
				)
			)
		)
	(symbol "jetson-orin-baseboard:GND_20"
			(power)
			(pin_numbers hide)
			(pin_names hide)
			(exclude_from_sim no)
			(in_bom yes)
			(on_board yes)
			(property "Reference" "#PWR"
				(at 8.89 -2.54 0)
				(effects
					(font
						(size 1.27 1.27)
						(thickness 0.15)
					)
					(justify left bottom)
				)
			)
			(property "Value" "GND_20"
				(at 8.89 -5.08 0)
				(effects
					(font
						(size 1.27 1.27)
						(thickness 0.15)
					)
					(justify left bottom)
					(hide yes)
				)
			)
			(property "Footprint" ""
				(at 8.89 -7.62 0)
				(effects
					(font
						(size 1.27 1.27)
						(thickness 0.15)
					)
					(justify left bottom)
					(hide yes)
				)
			)
			(property "Datasheet" ""
				(at 8.89 -12.7 0)
				(effects
					(font
						(size 1.27 1.27)
						(thickness 0.15)
					)
					(justify left bottom)
					(hide yes)
				)
			)
			(property "Description" ""
				(at 0 0 0)
				(effects
					(font
						(size 1.27 1.27)
					)
					(hide yes)
				)
			)
			(property "Author" "Antmicro"
				(at 8.89 -7.62 0)
				(effects
					(font
						(size 1.27 1.27)
						(thickness 0.15)
					)
					(justify left bottom)
					(hide yes)
				)
			)
			(property "License" "Apache-2.0"
				(at 8.89 -10.16 0)
				(effects
					(font
						(size 1.27 1.27)
						(thickness 0.15)
					)
					(justify left bottom)
					(hide yes)
				)
			)
			(symbol "GND_20_1_1"
				(polyline
					(pts
						(xy 0 0) (xy 0 -1.27) (xy 1.27 -1.27) (xy 0 -2.54) (xy -1.27 -1.27) (xy 0 -1.27)
					)
					(stroke
						(width 0.254)
						(type default)
					)
					(fill
						(type none)
					)
				)
				(pin power_in line
					(at 0 0 270)
					(length 0)
					(name "GND"
						(effects
							(font
								(size 1.27 1.27)
							)
						)
					)
					(number "1"
						(effects
							(font
								(size 1.27 1.27)
							)
						)
					)
				)
			)
		)
	(symbol "jetson-orin-baseboard:GND_21"
			(power)
			(pin_numbers hide)
			(pin_names hide)
			(exclude_from_sim no)
			(in_bom yes)
			(on_board yes)
			(property "Reference" "#PWR"
				(at 8.89 -2.54 0)
				(effects
					(font
						(size 1.27 1.27)
						(thickness 0.15)
					)
					(justify left bottom)
				)
			)
			(property "Value" "GND_21"
				(at 8.89 -5.08 0)
				(effects
					(font
						(size 1.27 1.27)
						(thickness 0.15)
					)
					(justify left bottom)
					(hide yes)
				)
			)
			(property "Footprint" ""
				(at 8.89 -7.62 0)
				(effects
					(font
						(size 1.27 1.27)
						(thickness 0.15)
					)
					(justify left bottom)
					(hide yes)
				)
			)
			(property "Datasheet" ""
				(at 8.89 -12.7 0)
				(effects
					(font
						(size 1.27 1.27)
						(thickness 0.15)
					)
					(justify left bottom)
					(hide yes)
				)
			)
			(property "Description" ""
				(at 0 0 0)
				(effects
					(font
						(size 1.27 1.27)
					)
					(hide yes)
				)
			)
			(property "Author" "Antmicro"
				(at 8.89 -7.62 0)
				(effects
					(font
						(size 1.27 1.27)
						(thickness 0.15)
					)
					(justify left bottom)
					(hide yes)
				)
			)
			(property "License" "Apache-2.0"
				(at 8.89 -10.16 0)
				(effects
					(font
						(size 1.27 1.27)
						(thickness 0.15)
					)
					(justify left bottom)
					(hide yes)
				)
			)
			(symbol "GND_21_1_1"
				(polyline
					(pts
						(xy 0 0) (xy 0 -1.27) (xy 1.27 -1.27) (xy 0 -2.54) (xy -1.27 -1.27) (xy 0 -1.27)
					)
					(stroke
						(width 0.254)
						(type default)
					)
					(fill
						(type none)
					)
				)
				(pin power_in line
					(at 0 0 270)
					(length 0)
					(name "GND"
						(effects
							(font
								(size 1.27 1.27)
							)
						)
					)
					(number "1"
						(effects
							(font
								(size 1.27 1.27)
							)
						)
					)
				)
			)
		)
	(symbol "jetson-orin-baseboard:GND_22"
			(power)
			(pin_numbers hide)
			(pin_names hide)
			(exclude_from_sim no)
			(in_bom yes)
			(on_board yes)
			(property "Reference" "#PWR"
				(at 8.89 -2.54 0)
				(effects
					(font
						(size 1.27 1.27)
						(thickness 0.15)
					)
					(justify left bottom)
				)
			)
			(property "Value" "GND_22"
				(at 8.89 -5.08 0)
				(effects
					(font
						(size 1.27 1.27)
						(thickness 0.15)
					)
					(justify left bottom)
					(hide yes)
				)
			)
			(property "Footprint" ""
				(at 8.89 -7.62 0)
				(effects
					(font
						(size 1.27 1.27)
						(thickness 0.15)
					)
					(justify left bottom)
					(hide yes)
				)
			)
			(property "Datasheet" ""
				(at 8.89 -12.7 0)
				(effects
					(font
						(size 1.27 1.27)
						(thickness 0.15)
					)
					(justify left bottom)
					(hide yes)
				)
			)
			(property "Description" ""
				(at 0 0 0)
				(effects
					(font
						(size 1.27 1.27)
					)
					(hide yes)
				)
			)
			(property "Author" "Antmicro"
				(at 8.89 -7.62 0)
				(effects
					(font
						(size 1.27 1.27)
						(thickness 0.15)
					)
					(justify left bottom)
					(hide yes)
				)
			)
			(property "License" "Apache-2.0"
				(at 8.89 -10.16 0)
				(effects
					(font
						(size 1.27 1.27)
						(thickness 0.15)
					)
					(justify left bottom)
					(hide yes)
				)
			)
			(symbol "GND_22_1_1"
				(polyline
					(pts
						(xy 0 0) (xy 0 -1.27) (xy 1.27 -1.27) (xy 0 -2.54) (xy -1.27 -1.27) (xy 0 -1.27)
					)
					(stroke
						(width 0.254)
						(type default)
					)
					(fill
						(type none)
					)
				)
				(pin power_in line
					(at 0 0 270)
					(length 0)
					(name "GND"
						(effects
							(font
								(size 1.27 1.27)
							)
						)
					)
					(number "1"
						(effects
							(font
								(size 1.27 1.27)
							)
						)
					)
				)
			)
		)
	(symbol "jetson-orin-baseboard:GND_23"
			(power)
			(pin_numbers hide)
			(pin_names hide)
			(exclude_from_sim no)
			(in_bom yes)
			(on_board yes)
			(property "Reference" "#PWR"
				(at 8.89 -2.54 0)
				(effects
					(font
						(size 1.27 1.27)
						(thickness 0.15)
					)
					(justify left bottom)
				)
			)
			(property "Value" "GND_23"
				(at 8.89 -5.08 0)
				(effects
					(font
						(size 1.27 1.27)
						(thickness 0.15)
					)
					(justify left bottom)
					(hide yes)
				)
			)
			(property "Footprint" ""
				(at 8.89 -7.62 0)
				(effects
					(font
						(size 1.27 1.27)
						(thickness 0.15)
					)
					(justify left bottom)
					(hide yes)
				)
			)
			(property "Datasheet" ""
				(at 8.89 -12.7 0)
				(effects
					(font
						(size 1.27 1.27)
						(thickness 0.15)
					)
					(justify left bottom)
					(hide yes)
				)
			)
			(property "Description" ""
				(at 0 0 0)
				(effects
					(font
						(size 1.27 1.27)
					)
					(hide yes)
				)
			)
			(property "Author" "Antmicro"
				(at 8.89 -7.62 0)
				(effects
					(font
						(size 1.27 1.27)
						(thickness 0.15)
					)
					(justify left bottom)
					(hide yes)
				)
			)
			(property "License" "Apache-2.0"
				(at 8.89 -10.16 0)
				(effects
					(font
						(size 1.27 1.27)
						(thickness 0.15)
					)
					(justify left bottom)
					(hide yes)
				)
			)
			(symbol "GND_23_1_1"
				(polyline
					(pts
						(xy 0 0) (xy 0 -1.27) (xy 1.27 -1.27) (xy 0 -2.54) (xy -1.27 -1.27) (xy 0 -1.27)
					)
					(stroke
						(width 0.254)
						(type default)
					)
					(fill
						(type none)
					)
				)
				(pin power_in line
					(at 0 0 270)
					(length 0)
					(name "GND"
						(effects
							(font
								(size 1.27 1.27)
							)
						)
					)
					(number "1"
						(effects
							(font
								(size 1.27 1.27)
							)
						)
					)
				)
			)
		)
	(symbol "jetson-orin-baseboard:GND_24"
			(power)
			(pin_numbers hide)
			(pin_names hide)
			(exclude_from_sim no)
			(in_bom yes)
			(on_board yes)
			(property "Reference" "#PWR"
				(at 8.89 -2.54 0)
				(effects
					(font
						(size 1.27 1.27)
						(thickness 0.15)
					)
					(justify left bottom)
				)
			)
			(property "Value" "GND_24"
				(at 8.89 -5.08 0)
				(effects
					(font
						(size 1.27 1.27)
						(thickness 0.15)
					)
					(justify left bottom)
					(hide yes)
				)
			)
			(property "Footprint" ""
				(at 8.89 -7.62 0)
				(effects
					(font
						(size 1.27 1.27)
						(thickness 0.15)
					)
					(justify left bottom)
					(hide yes)
				)
			)
			(property "Datasheet" ""
				(at 8.89 -12.7 0)
				(effects
					(font
						(size 1.27 1.27)
						(thickness 0.15)
					)
					(justify left bottom)
					(hide yes)
				)
			)
			(property "Description" ""
				(at 0 0 0)
				(effects
					(font
						(size 1.27 1.27)
					)
					(hide yes)
				)
			)
			(property "Author" "Antmicro"
				(at 8.89 -7.62 0)
				(effects
					(font
						(size 1.27 1.27)
						(thickness 0.15)
					)
					(justify left bottom)
					(hide yes)
				)
			)
			(property "License" "Apache-2.0"
				(at 8.89 -10.16 0)
				(effects
					(font
						(size 1.27 1.27)
						(thickness 0.15)
					)
					(justify left bottom)
					(hide yes)
				)
			)
			(symbol "GND_24_1_1"
				(polyline
					(pts
						(xy 0 0) (xy 0 -1.27) (xy 1.27 -1.27) (xy 0 -2.54) (xy -1.27 -1.27) (xy 0 -1.27)
					)
					(stroke
						(width 0.254)
						(type default)
					)
					(fill
						(type none)
					)
				)
				(pin power_in line
					(at 0 0 270)
					(length 0)
					(name "GND"
						(effects
							(font
								(size 1.27 1.27)
							)
						)
					)
					(number "1"
						(effects
							(font
								(size 1.27 1.27)
							)
						)
					)
				)
			)
		)
	(symbol "jetson-orin-baseboard:GND_25"
			(power)
			(pin_numbers hide)
			(pin_names hide)
			(exclude_from_sim no)
			(in_bom yes)
			(on_board yes)
			(property "Reference" "#PWR"
				(at 8.89 -2.54 0)
				(effects
					(font
						(size 1.27 1.27)
						(thickness 0.15)
					)
					(justify left bottom)
				)
			)
			(property "Value" "GND_25"
				(at 8.89 -5.08 0)
				(effects
					(font
						(size 1.27 1.27)
						(thickness 0.15)
					)
					(justify left bottom)
					(hide yes)
				)
			)
			(property "Footprint" ""
				(at 8.89 -7.62 0)
				(effects
					(font
						(size 1.27 1.27)
						(thickness 0.15)
					)
					(justify left bottom)
					(hide yes)
				)
			)
			(property "Datasheet" ""
				(at 8.89 -12.7 0)
				(effects
					(font
						(size 1.27 1.27)
						(thickness 0.15)
					)
					(justify left bottom)
					(hide yes)
				)
			)
			(property "Description" ""
				(at 0 0 0)
				(effects
					(font
						(size 1.27 1.27)
					)
					(hide yes)
				)
			)
			(property "Author" "Antmicro"
				(at 8.89 -7.62 0)
				(effects
					(font
						(size 1.27 1.27)
						(thickness 0.15)
					)
					(justify left bottom)
					(hide yes)
				)
			)
			(property "License" "Apache-2.0"
				(at 8.89 -10.16 0)
				(effects
					(font
						(size 1.27 1.27)
						(thickness 0.15)
					)
					(justify left bottom)
					(hide yes)
				)
			)
			(symbol "GND_25_1_1"
				(polyline
					(pts
						(xy 0 0) (xy 0 -1.27) (xy 1.27 -1.27) (xy 0 -2.54) (xy -1.27 -1.27) (xy 0 -1.27)
					)
					(stroke
						(width 0.254)
						(type default)
					)
					(fill
						(type none)
					)
				)
				(pin power_in line
					(at 0 0 270)
					(length 0)
					(name "GND"
						(effects
							(font
								(size 1.27 1.27)
							)
						)
					)
					(number "1"
						(effects
							(font
								(size 1.27 1.27)
							)
						)
					)
				)
			)
		)
	(symbol "jetson-orin-baseboard:GND_26"
			(power)
			(pin_numbers hide)
			(pin_names hide)
			(exclude_from_sim no)
			(in_bom yes)
			(on_board yes)
			(property "Reference" "#PWR"
				(at 8.89 -2.54 0)
				(effects
					(font
						(size 1.27 1.27)
						(thickness 0.15)
					)
					(justify left bottom)
				)
			)
			(property "Value" "GND_26"
				(at 8.89 -5.08 0)
				(effects
					(font
						(size 1.27 1.27)
						(thickness 0.15)
					)
					(justify left bottom)
					(hide yes)
				)
			)
			(property "Footprint" ""
				(at 8.89 -7.62 0)
				(effects
					(font
						(size 1.27 1.27)
						(thickness 0.15)
					)
					(justify left bottom)
					(hide yes)
				)
			)
			(property "Datasheet" ""
				(at 8.89 -12.7 0)
				(effects
					(font
						(size 1.27 1.27)
						(thickness 0.15)
					)
					(justify left bottom)
					(hide yes)
				)
			)
			(property "Description" ""
				(at 0 0 0)
				(effects
					(font
						(size 1.27 1.27)
					)
					(hide yes)
				)
			)
			(property "Author" "Antmicro"
				(at 8.89 -7.62 0)
				(effects
					(font
						(size 1.27 1.27)
						(thickness 0.15)
					)
					(justify left bottom)
					(hide yes)
				)
			)
			(property "License" "Apache-2.0"
				(at 8.89 -10.16 0)
				(effects
					(font
						(size 1.27 1.27)
						(thickness 0.15)
					)
					(justify left bottom)
					(hide yes)
				)
			)
			(symbol "GND_26_1_1"
				(polyline
					(pts
						(xy 0 0) (xy 0 -1.27) (xy 1.27 -1.27) (xy 0 -2.54) (xy -1.27 -1.27) (xy 0 -1.27)
					)
					(stroke
						(width 0.254)
						(type default)
					)
					(fill
						(type none)
					)
				)
				(pin power_in line
					(at 0 0 270)
					(length 0)
					(name "GND"
						(effects
							(font
								(size 1.27 1.27)
							)
						)
					)
					(number "1"
						(effects
							(font
								(size 1.27 1.27)
							)
						)
					)
				)
			)
		)
	(symbol "jetson-orin-baseboard:GND_27"
			(power)
			(pin_numbers hide)
			(pin_names hide)
			(exclude_from_sim no)
			(in_bom yes)
			(on_board yes)
			(property "Reference" "#PWR"
				(at 8.89 -2.54 0)
				(effects
					(font
						(size 1.27 1.27)
						(thickness 0.15)
					)
					(justify left bottom)
				)
			)
			(property "Value" "GND_27"
				(at 8.89 -5.08 0)
				(effects
					(font
						(size 1.27 1.27)
						(thickness 0.15)
					)
					(justify left bottom)
					(hide yes)
				)
			)
			(property "Footprint" ""
				(at 8.89 -7.62 0)
				(effects
					(font
						(size 1.27 1.27)
						(thickness 0.15)
					)
					(justify left bottom)
					(hide yes)
				)
			)
			(property "Datasheet" ""
				(at 8.89 -12.7 0)
				(effects
					(font
						(size 1.27 1.27)
						(thickness 0.15)
					)
					(justify left bottom)
					(hide yes)
				)
			)
			(property "Description" ""
				(at 0 0 0)
				(effects
					(font
						(size 1.27 1.27)
					)
					(hide yes)
				)
			)
			(property "Author" "Antmicro"
				(at 8.89 -7.62 0)
				(effects
					(font
						(size 1.27 1.27)
						(thickness 0.15)
					)
					(justify left bottom)
					(hide yes)
				)
			)
			(property "License" "Apache-2.0"
				(at 8.89 -10.16 0)
				(effects
					(font
						(size 1.27 1.27)
						(thickness 0.15)
					)
					(justify left bottom)
					(hide yes)
				)
			)
			(symbol "GND_27_1_1"
				(polyline
					(pts
						(xy 0 0) (xy 0 -1.27) (xy 1.27 -1.27) (xy 0 -2.54) (xy -1.27 -1.27) (xy 0 -1.27)
					)
					(stroke
						(width 0.254)
						(type default)
					)
					(fill
						(type none)
					)
				)
				(pin power_in line
					(at 0 0 270)
					(length 0)
					(name "GND"
						(effects
							(font
								(size 1.27 1.27)
							)
						)
					)
					(number "1"
						(effects
							(font
								(size 1.27 1.27)
							)
						)
					)
				)
			)
		)
	(symbol "jetson-orin-baseboard:GND_28"
			(power)
			(pin_numbers hide)
			(pin_names hide)
			(exclude_from_sim no)
			(in_bom yes)
			(on_board yes)
			(property "Reference" "#PWR"
				(at 8.89 -2.54 0)
				(effects
					(font
						(size 1.27 1.27)
						(thickness 0.15)
					)
					(justify left bottom)
				)
			)
			(property "Value" "GND_28"
				(at 8.89 -5.08 0)
				(effects
					(font
						(size 1.27 1.27)
						(thickness 0.15)
					)
					(justify left bottom)
					(hide yes)
				)
			)
			(property "Footprint" ""
				(at 8.89 -7.62 0)
				(effects
					(font
						(size 1.27 1.27)
						(thickness 0.15)
					)
					(justify left bottom)
					(hide yes)
				)
			)
			(property "Datasheet" ""
				(at 8.89 -12.7 0)
				(effects
					(font
						(size 1.27 1.27)
						(thickness 0.15)
					)
					(justify left bottom)
					(hide yes)
				)
			)
			(property "Description" ""
				(at 0 0 0)
				(effects
					(font
						(size 1.27 1.27)
					)
					(hide yes)
				)
			)
			(property "Author" "Antmicro"
				(at 8.89 -7.62 0)
				(effects
					(font
						(size 1.27 1.27)
						(thickness 0.15)
					)
					(justify left bottom)
					(hide yes)
				)
			)
			(property "License" "Apache-2.0"
				(at 8.89 -10.16 0)
				(effects
					(font
						(size 1.27 1.27)
						(thickness 0.15)
					)
					(justify left bottom)
					(hide yes)
				)
			)
			(symbol "GND_28_1_1"
				(polyline
					(pts
						(xy 0 0) (xy 0 -1.27) (xy 1.27 -1.27) (xy 0 -2.54) (xy -1.27 -1.27) (xy 0 -1.27)
					)
					(stroke
						(width 0.254)
						(type default)
					)
					(fill
						(type none)
					)
				)
				(pin power_in line
					(at 0 0 270)
					(length 0)
					(name "GND"
						(effects
							(font
								(size 1.27 1.27)
							)
						)
					)
					(number "1"
						(effects
							(font
								(size 1.27 1.27)
							)
						)
					)
				)
			)
		)
	(symbol "jetson-orin-baseboard:GND_29"
			(power)
			(pin_numbers hide)
			(pin_names hide)
			(exclude_from_sim no)
			(in_bom yes)
			(on_board yes)
			(property "Reference" "#PWR"
				(at 8.89 -2.54 0)
				(effects
					(font
						(size 1.27 1.27)
						(thickness 0.15)
					)
					(justify left bottom)
				)
			)
			(property "Value" "GND_29"
				(at 8.89 -5.08 0)
				(effects
					(font
						(size 1.27 1.27)
						(thickness 0.15)
					)
					(justify left bottom)
					(hide yes)
				)
			)
			(property "Footprint" ""
				(at 8.89 -7.62 0)
				(effects
					(font
						(size 1.27 1.27)
						(thickness 0.15)
					)
					(justify left bottom)
					(hide yes)
				)
			)
			(property "Datasheet" ""
				(at 8.89 -12.7 0)
				(effects
					(font
						(size 1.27 1.27)
						(thickness 0.15)
					)
					(justify left bottom)
					(hide yes)
				)
			)
			(property "Description" ""
				(at 0 0 0)
				(effects
					(font
						(size 1.27 1.27)
					)
					(hide yes)
				)
			)
			(property "Author" "Antmicro"
				(at 8.89 -7.62 0)
				(effects
					(font
						(size 1.27 1.27)
						(thickness 0.15)
					)
					(justify left bottom)
					(hide yes)
				)
			)
			(property "License" "Apache-2.0"
				(at 8.89 -10.16 0)
				(effects
					(font
						(size 1.27 1.27)
						(thickness 0.15)
					)
					(justify left bottom)
					(hide yes)
				)
			)
			(symbol "GND_29_1_1"
				(polyline
					(pts
						(xy 0 0) (xy 0 -1.27) (xy 1.27 -1.27) (xy 0 -2.54) (xy -1.27 -1.27) (xy 0 -1.27)
					)
					(stroke
						(width 0.254)
						(type default)
					)
					(fill
						(type none)
					)
				)
				(pin power_in line
					(at 0 0 270)
					(length 0)
					(name "GND"
						(effects
							(font
								(size 1.27 1.27)
							)
						)
					)
					(number "1"
						(effects
							(font
								(size 1.27 1.27)
							)
						)
					)
				)
			)
		)
	(symbol "jetson-orin-baseboard:GND_30"
			(power)
			(pin_numbers hide)
			(pin_names hide)
			(exclude_from_sim no)
			(in_bom yes)
			(on_board yes)
			(property "Reference" "#PWR"
				(at 8.89 -2.54 0)
				(effects
					(font
						(size 1.27 1.27)
						(thickness 0.15)
					)
					(justify left bottom)
				)
			)
			(property "Value" "GND_30"
				(at 8.89 -5.08 0)
				(effects
					(font
						(size 1.27 1.27)
						(thickness 0.15)
					)
					(justify left bottom)
					(hide yes)
				)
			)
			(property "Footprint" ""
				(at 8.89 -7.62 0)
				(effects
					(font
						(size 1.27 1.27)
						(thickness 0.15)
					)
					(justify left bottom)
					(hide yes)
				)
			)
			(property "Datasheet" ""
				(at 8.89 -12.7 0)
				(effects
					(font
						(size 1.27 1.27)
						(thickness 0.15)
					)
					(justify left bottom)
					(hide yes)
				)
			)
			(property "Description" ""
				(at 0 0 0)
				(effects
					(font
						(size 1.27 1.27)
					)
					(hide yes)
				)
			)
			(property "Author" "Antmicro"
				(at 8.89 -7.62 0)
				(effects
					(font
						(size 1.27 1.27)
						(thickness 0.15)
					)
					(justify left bottom)
					(hide yes)
				)
			)
			(property "License" "Apache-2.0"
				(at 8.89 -10.16 0)
				(effects
					(font
						(size 1.27 1.27)
						(thickness 0.15)
					)
					(justify left bottom)
					(hide yes)
				)
			)
			(symbol "GND_30_1_1"
				(polyline
					(pts
						(xy 0 0) (xy 0 -1.27) (xy 1.27 -1.27) (xy 0 -2.54) (xy -1.27 -1.27) (xy 0 -1.27)
					)
					(stroke
						(width 0.254)
						(type default)
					)
					(fill
						(type none)
					)
				)
				(pin power_in line
					(at 0 0 270)
					(length 0)
					(name "GND"
						(effects
							(font
								(size 1.27 1.27)
							)
						)
					)
					(number "1"
						(effects
							(font
								(size 1.27 1.27)
							)
						)
					)
				)
			)
		)
	(symbol "jetson-orin-baseboard:GND_31"
			(power)
			(pin_numbers hide)
			(pin_names hide)
			(exclude_from_sim no)
			(in_bom yes)
			(on_board yes)
			(property "Reference" "#PWR"
				(at 8.89 -2.54 0)
				(effects
					(font
						(size 1.27 1.27)
						(thickness 0.15)
					)
					(justify left bottom)
				)
			)
			(property "Value" "GND_31"
				(at 8.89 -5.08 0)
				(effects
					(font
						(size 1.27 1.27)
						(thickness 0.15)
					)
					(justify left bottom)
					(hide yes)
				)
			)
			(property "Footprint" ""
				(at 8.89 -7.62 0)
				(effects
					(font
						(size 1.27 1.27)
						(thickness 0.15)
					)
					(justify left bottom)
					(hide yes)
				)
			)
			(property "Datasheet" ""
				(at 8.89 -12.7 0)
				(effects
					(font
						(size 1.27 1.27)
						(thickness 0.15)
					)
					(justify left bottom)
					(hide yes)
				)
			)
			(property "Description" ""
				(at 0 0 0)
				(effects
					(font
						(size 1.27 1.27)
					)
					(hide yes)
				)
			)
			(property "Author" "Antmicro"
				(at 8.89 -7.62 0)
				(effects
					(font
						(size 1.27 1.27)
						(thickness 0.15)
					)
					(justify left bottom)
					(hide yes)
				)
			)
			(property "License" "Apache-2.0"
				(at 8.89 -10.16 0)
				(effects
					(font
						(size 1.27 1.27)
						(thickness 0.15)
					)
					(justify left bottom)
					(hide yes)
				)
			)
			(symbol "GND_31_1_1"
				(polyline
					(pts
						(xy 0 0) (xy 0 -1.27) (xy 1.27 -1.27) (xy 0 -2.54) (xy -1.27 -1.27) (xy 0 -1.27)
					)
					(stroke
						(width 0.254)
						(type default)
					)
					(fill
						(type none)
					)
				)
				(pin power_in line
					(at 0 0 270)
					(length 0)
					(name "GND"
						(effects
							(font
								(size 1.27 1.27)
							)
						)
					)
					(number "1"
						(effects
							(font
								(size 1.27 1.27)
							)
						)
					)
				)
			)
		)
	(symbol "jetson-orin-baseboard:GND_32"
			(power)
			(pin_numbers hide)
			(pin_names hide)
			(exclude_from_sim no)
			(in_bom yes)
			(on_board yes)
			(property "Reference" "#PWR"
				(at 8.89 -2.54 0)
				(effects
					(font
						(size 1.27 1.27)
						(thickness 0.15)
					)
					(justify left bottom)
				)
			)
			(property "Value" "GND_32"
				(at 8.89 -5.08 0)
				(effects
					(font
						(size 1.27 1.27)
						(thickness 0.15)
					)
					(justify left bottom)
					(hide yes)
				)
			)
			(property "Footprint" ""
				(at 8.89 -7.62 0)
				(effects
					(font
						(size 1.27 1.27)
						(thickness 0.15)
					)
					(justify left bottom)
					(hide yes)
				)
			)
			(property "Datasheet" ""
				(at 8.89 -12.7 0)
				(effects
					(font
						(size 1.27 1.27)
						(thickness 0.15)
					)
					(justify left bottom)
					(hide yes)
				)
			)
			(property "Description" ""
				(at 0 0 0)
				(effects
					(font
						(size 1.27 1.27)
					)
					(hide yes)
				)
			)
			(property "Author" "Antmicro"
				(at 8.89 -7.62 0)
				(effects
					(font
						(size 1.27 1.27)
						(thickness 0.15)
					)
					(justify left bottom)
					(hide yes)
				)
			)
			(property "License" "Apache-2.0"
				(at 8.89 -10.16 0)
				(effects
					(font
						(size 1.27 1.27)
						(thickness 0.15)
					)
					(justify left bottom)
					(hide yes)
				)
			)
			(symbol "GND_32_1_1"
				(polyline
					(pts
						(xy 0 0) (xy 0 -1.27) (xy 1.27 -1.27) (xy 0 -2.54) (xy -1.27 -1.27) (xy 0 -1.27)
					)
					(stroke
						(width 0.254)
						(type default)
					)
					(fill
						(type none)
					)
				)
				(pin power_in line
					(at 0 0 270)
					(length 0)
					(name "GND"
						(effects
							(font
								(size 1.27 1.27)
							)
						)
					)
					(number "1"
						(effects
							(font
								(size 1.27 1.27)
							)
						)
					)
				)
			)
		)
	(symbol "jetson-orin-baseboard:GND_33"
			(power)
			(pin_numbers hide)
			(pin_names hide)
			(exclude_from_sim no)
			(in_bom yes)
			(on_board yes)
			(property "Reference" "#PWR"
				(at 8.89 -2.54 0)
				(effects
					(font
						(size 1.27 1.27)
						(thickness 0.15)
					)
					(justify left bottom)
				)
			)
			(property "Value" "GND_33"
				(at 8.89 -5.08 0)
				(effects
					(font
						(size 1.27 1.27)
						(thickness 0.15)
					)
					(justify left bottom)
					(hide yes)
				)
			)
			(property "Footprint" ""
				(at 8.89 -7.62 0)
				(effects
					(font
						(size 1.27 1.27)
						(thickness 0.15)
					)
					(justify left bottom)
					(hide yes)
				)
			)
			(property "Datasheet" ""
				(at 8.89 -12.7 0)
				(effects
					(font
						(size 1.27 1.27)
						(thickness 0.15)
					)
					(justify left bottom)
					(hide yes)
				)
			)
			(property "Description" ""
				(at 0 0 0)
				(effects
					(font
						(size 1.27 1.27)
					)
					(hide yes)
				)
			)
			(property "Author" "Antmicro"
				(at 8.89 -7.62 0)
				(effects
					(font
						(size 1.27 1.27)
						(thickness 0.15)
					)
					(justify left bottom)
					(hide yes)
				)
			)
			(property "License" "Apache-2.0"
				(at 8.89 -10.16 0)
				(effects
					(font
						(size 1.27 1.27)
						(thickness 0.15)
					)
					(justify left bottom)
					(hide yes)
				)
			)
			(symbol "GND_33_1_1"
				(polyline
					(pts
						(xy 0 0) (xy 0 -1.27) (xy 1.27 -1.27) (xy 0 -2.54) (xy -1.27 -1.27) (xy 0 -1.27)
					)
					(stroke
						(width 0.254)
						(type default)
					)
					(fill
						(type none)
					)
				)
				(pin power_in line
					(at 0 0 270)
					(length 0)
					(name "GND"
						(effects
							(font
								(size 1.27 1.27)
							)
						)
					)
					(number "1"
						(effects
							(font
								(size 1.27 1.27)
							)
						)
					)
				)
			)
		)
	(symbol "jetson-orin-baseboard:GND_34"
			(power)
			(pin_numbers hide)
			(pin_names hide)
			(exclude_from_sim no)
			(in_bom yes)
			(on_board yes)
			(property "Reference" "#PWR"
				(at 8.89 -2.54 0)
				(effects
					(font
						(size 1.27 1.27)
						(thickness 0.15)
					)
					(justify left bottom)
				)
			)
			(property "Value" "GND_34"
				(at 8.89 -5.08 0)
				(effects
					(font
						(size 1.27 1.27)
						(thickness 0.15)
					)
					(justify left bottom)
					(hide yes)
				)
			)
			(property "Footprint" ""
				(at 8.89 -7.62 0)
				(effects
					(font
						(size 1.27 1.27)
						(thickness 0.15)
					)
					(justify left bottom)
					(hide yes)
				)
			)
			(property "Datasheet" ""
				(at 8.89 -12.7 0)
				(effects
					(font
						(size 1.27 1.27)
						(thickness 0.15)
					)
					(justify left bottom)
					(hide yes)
				)
			)
			(property "Description" ""
				(at 0 0 0)
				(effects
					(font
						(size 1.27 1.27)
					)
					(hide yes)
				)
			)
			(property "Author" "Antmicro"
				(at 8.89 -7.62 0)
				(effects
					(font
						(size 1.27 1.27)
						(thickness 0.15)
					)
					(justify left bottom)
					(hide yes)
				)
			)
			(property "License" "Apache-2.0"
				(at 8.89 -10.16 0)
				(effects
					(font
						(size 1.27 1.27)
						(thickness 0.15)
					)
					(justify left bottom)
					(hide yes)
				)
			)
			(symbol "GND_34_1_1"
				(polyline
					(pts
						(xy 0 0) (xy 0 -1.27) (xy 1.27 -1.27) (xy 0 -2.54) (xy -1.27 -1.27) (xy 0 -1.27)
					)
					(stroke
						(width 0.254)
						(type default)
					)
					(fill
						(type none)
					)
				)
				(pin power_in line
					(at 0 0 270)
					(length 0)
					(name "GND"
						(effects
							(font
								(size 1.27 1.27)
							)
						)
					)
					(number "1"
						(effects
							(font
								(size 1.27 1.27)
							)
						)
					)
				)
			)
		)
	(symbol "jetson-orin-baseboard:GND_35"
			(power)
			(pin_numbers hide)
			(pin_names hide)
			(exclude_from_sim no)
			(in_bom yes)
			(on_board yes)
			(property "Reference" "#PWR"
				(at 8.89 -2.54 0)
				(effects
					(font
						(size 1.27 1.27)
						(thickness 0.15)
					)
					(justify left bottom)
				)
			)
			(property "Value" "GND_35"
				(at 8.89 -5.08 0)
				(effects
					(font
						(size 1.27 1.27)
						(thickness 0.15)
					)
					(justify left bottom)
					(hide yes)
				)
			)
			(property "Footprint" ""
				(at 8.89 -7.62 0)
				(effects
					(font
						(size 1.27 1.27)
						(thickness 0.15)
					)
					(justify left bottom)
					(hide yes)
				)
			)
			(property "Datasheet" ""
				(at 8.89 -12.7 0)
				(effects
					(font
						(size 1.27 1.27)
						(thickness 0.15)
					)
					(justify left bottom)
					(hide yes)
				)
			)
			(property "Description" ""
				(at 0 0 0)
				(effects
					(font
						(size 1.27 1.27)
					)
					(hide yes)
				)
			)
			(property "Author" "Antmicro"
				(at 8.89 -7.62 0)
				(effects
					(font
						(size 1.27 1.27)
						(thickness 0.15)
					)
					(justify left bottom)
					(hide yes)
				)
			)
			(property "License" "Apache-2.0"
				(at 8.89 -10.16 0)
				(effects
					(font
						(size 1.27 1.27)
						(thickness 0.15)
					)
					(justify left bottom)
					(hide yes)
				)
			)
			(symbol "GND_35_1_1"
				(polyline
					(pts
						(xy 0 0) (xy 0 -1.27) (xy 1.27 -1.27) (xy 0 -2.54) (xy -1.27 -1.27) (xy 0 -1.27)
					)
					(stroke
						(width 0.254)
						(type default)
					)
					(fill
						(type none)
					)
				)
				(pin power_in line
					(at 0 0 270)
					(length 0)
					(name "GND"
						(effects
							(font
								(size 1.27 1.27)
							)
						)
					)
					(number "1"
						(effects
							(font
								(size 1.27 1.27)
							)
						)
					)
				)
			)
		)
	(symbol "jetson-orin-baseboard:GND_36"
			(power)
			(pin_numbers hide)
			(pin_names hide)
			(exclude_from_sim no)
			(in_bom yes)
			(on_board yes)
			(property "Reference" "#PWR"
				(at 8.89 -2.54 0)
				(effects
					(font
						(size 1.27 1.27)
						(thickness 0.15)
					)
					(justify left bottom)
				)
			)
			(property "Value" "GND_36"
				(at 8.89 -5.08 0)
				(effects
					(font
						(size 1.27 1.27)
						(thickness 0.15)
					)
					(justify left bottom)
					(hide yes)
				)
			)
			(property "Footprint" ""
				(at 8.89 -7.62 0)
				(effects
					(font
						(size 1.27 1.27)
						(thickness 0.15)
					)
					(justify left bottom)
					(hide yes)
				)
			)
			(property "Datasheet" ""
				(at 8.89 -12.7 0)
				(effects
					(font
						(size 1.27 1.27)
						(thickness 0.15)
					)
					(justify left bottom)
					(hide yes)
				)
			)
			(property "Description" ""
				(at 0 0 0)
				(effects
					(font
						(size 1.27 1.27)
					)
					(hide yes)
				)
			)
			(property "Author" "Antmicro"
				(at 8.89 -7.62 0)
				(effects
					(font
						(size 1.27 1.27)
						(thickness 0.15)
					)
					(justify left bottom)
					(hide yes)
				)
			)
			(property "License" "Apache-2.0"
				(at 8.89 -10.16 0)
				(effects
					(font
						(size 1.27 1.27)
						(thickness 0.15)
					)
					(justify left bottom)
					(hide yes)
				)
			)
			(symbol "GND_36_1_1"
				(polyline
					(pts
						(xy 0 0) (xy 0 -1.27) (xy 1.27 -1.27) (xy 0 -2.54) (xy -1.27 -1.27) (xy 0 -1.27)
					)
					(stroke
						(width 0.254)
						(type default)
					)
					(fill
						(type none)
					)
				)
				(pin power_in line
					(at 0 0 270)
					(length 0)
					(name "GND"
						(effects
							(font
								(size 1.27 1.27)
							)
						)
					)
					(number "1"
						(effects
							(font
								(size 1.27 1.27)
							)
						)
					)
				)
			)
		)
	(symbol "jetson-orin-baseboard:GND_37"
			(power)
			(pin_numbers hide)
			(pin_names hide)
			(exclude_from_sim no)
			(in_bom yes)
			(on_board yes)
			(property "Reference" "#PWR"
				(at 8.89 -2.54 0)
				(effects
					(font
						(size 1.27 1.27)
						(thickness 0.15)
					)
					(justify left bottom)
				)
			)
			(property "Value" "GND_37"
				(at 8.89 -5.08 0)
				(effects
					(font
						(size 1.27 1.27)
						(thickness 0.15)
					)
					(justify left bottom)
					(hide yes)
				)
			)
			(property "Footprint" ""
				(at 8.89 -7.62 0)
				(effects
					(font
						(size 1.27 1.27)
						(thickness 0.15)
					)
					(justify left bottom)
					(hide yes)
				)
			)
			(property "Datasheet" ""
				(at 8.89 -12.7 0)
				(effects
					(font
						(size 1.27 1.27)
						(thickness 0.15)
					)
					(justify left bottom)
					(hide yes)
				)
			)
			(property "Description" ""
				(at 0 0 0)
				(effects
					(font
						(size 1.27 1.27)
					)
					(hide yes)
				)
			)
			(property "Author" "Antmicro"
				(at 8.89 -7.62 0)
				(effects
					(font
						(size 1.27 1.27)
						(thickness 0.15)
					)
					(justify left bottom)
					(hide yes)
				)
			)
			(property "License" "Apache-2.0"
				(at 8.89 -10.16 0)
				(effects
					(font
						(size 1.27 1.27)
						(thickness 0.15)
					)
					(justify left bottom)
					(hide yes)
				)
			)
			(symbol "GND_37_1_1"
				(polyline
					(pts
						(xy 0 0) (xy 0 -1.27) (xy 1.27 -1.27) (xy 0 -2.54) (xy -1.27 -1.27) (xy 0 -1.27)
					)
					(stroke
						(width 0.254)
						(type default)
					)
					(fill
						(type none)
					)
				)
				(pin power_in line
					(at 0 0 270)
					(length 0)
					(name "GND"
						(effects
							(font
								(size 1.27 1.27)
							)
						)
					)
					(number "1"
						(effects
							(font
								(size 1.27 1.27)
							)
						)
					)
				)
			)
		)
	(symbol "jetson-orin-baseboard:GND_38"
			(power)
			(pin_numbers hide)
			(pin_names hide)
			(exclude_from_sim no)
			(in_bom yes)
			(on_board yes)
			(property "Reference" "#PWR"
				(at 8.89 -2.54 0)
				(effects
					(font
						(size 1.27 1.27)
						(thickness 0.15)
					)
					(justify left bottom)
				)
			)
			(property "Value" "GND_38"
				(at 8.89 -5.08 0)
				(effects
					(font
						(size 1.27 1.27)
						(thickness 0.15)
					)
					(justify left bottom)
					(hide yes)
				)
			)
			(property "Footprint" ""
				(at 8.89 -7.62 0)
				(effects
					(font
						(size 1.27 1.27)
						(thickness 0.15)
					)
					(justify left bottom)
					(hide yes)
				)
			)
			(property "Datasheet" ""
				(at 8.89 -12.7 0)
				(effects
					(font
						(size 1.27 1.27)
						(thickness 0.15)
					)
					(justify left bottom)
					(hide yes)
				)
			)
			(property "Description" ""
				(at 0 0 0)
				(effects
					(font
						(size 1.27 1.27)
					)
					(hide yes)
				)
			)
			(property "Author" "Antmicro"
				(at 8.89 -7.62 0)
				(effects
					(font
						(size 1.27 1.27)
						(thickness 0.15)
					)
					(justify left bottom)
					(hide yes)
				)
			)
			(property "License" "Apache-2.0"
				(at 8.89 -10.16 0)
				(effects
					(font
						(size 1.27 1.27)
						(thickness 0.15)
					)
					(justify left bottom)
					(hide yes)
				)
			)
			(symbol "GND_38_1_1"
				(polyline
					(pts
						(xy 0 0) (xy 0 -1.27) (xy 1.27 -1.27) (xy 0 -2.54) (xy -1.27 -1.27) (xy 0 -1.27)
					)
					(stroke
						(width 0.254)
						(type default)
					)
					(fill
						(type none)
					)
				)
				(pin power_in line
					(at 0 0 270)
					(length 0)
					(name "GND"
						(effects
							(font
								(size 1.27 1.27)
							)
						)
					)
					(number "1"
						(effects
							(font
								(size 1.27 1.27)
							)
						)
					)
				)
			)
		)
	(symbol "jetson-orin-baseboard:GND_39"
			(power)
			(pin_numbers hide)
			(pin_names hide)
			(exclude_from_sim no)
			(in_bom yes)
			(on_board yes)
			(property "Reference" "#PWR"
				(at 8.89 -2.54 0)
				(effects
					(font
						(size 1.27 1.27)
						(thickness 0.15)
					)
					(justify left bottom)
				)
			)
			(property "Value" "GND_39"
				(at 8.89 -5.08 0)
				(effects
					(font
						(size 1.27 1.27)
						(thickness 0.15)
					)
					(justify left bottom)
					(hide yes)
				)
			)
			(property "Footprint" ""
				(at 8.89 -7.62 0)
				(effects
					(font
						(size 1.27 1.27)
						(thickness 0.15)
					)
					(justify left bottom)
					(hide yes)
				)
			)
			(property "Datasheet" ""
				(at 8.89 -12.7 0)
				(effects
					(font
						(size 1.27 1.27)
						(thickness 0.15)
					)
					(justify left bottom)
					(hide yes)
				)
			)
			(property "Description" ""
				(at 0 0 0)
				(effects
					(font
						(size 1.27 1.27)
					)
					(hide yes)
				)
			)
			(property "Author" "Antmicro"
				(at 8.89 -7.62 0)
				(effects
					(font
						(size 1.27 1.27)
						(thickness 0.15)
					)
					(justify left bottom)
					(hide yes)
				)
			)
			(property "License" "Apache-2.0"
				(at 8.89 -10.16 0)
				(effects
					(font
						(size 1.27 1.27)
						(thickness 0.15)
					)
					(justify left bottom)
					(hide yes)
				)
			)
			(symbol "GND_39_1_1"
				(polyline
					(pts
						(xy 0 0) (xy 0 -1.27) (xy 1.27 -1.27) (xy 0 -2.54) (xy -1.27 -1.27) (xy 0 -1.27)
					)
					(stroke
						(width 0.254)
						(type default)
					)
					(fill
						(type none)
					)
				)
				(pin power_in line
					(at 0 0 270)
					(length 0)
					(name "GND"
						(effects
							(font
								(size 1.27 1.27)
							)
						)
					)
					(number "1"
						(effects
							(font
								(size 1.27 1.27)
							)
						)
					)
				)
			)
		)
	(symbol "jetson-orin-baseboard:GND_40"
			(power)
			(pin_numbers hide)
			(pin_names hide)
			(exclude_from_sim no)
			(in_bom yes)
			(on_board yes)
			(property "Reference" "#PWR"
				(at 8.89 -2.54 0)
				(effects
					(font
						(size 1.27 1.27)
						(thickness 0.15)
					)
					(justify left bottom)
				)
			)
			(property "Value" "GND_40"
				(at 8.89 -5.08 0)
				(effects
					(font
						(size 1.27 1.27)
						(thickness 0.15)
					)
					(justify left bottom)
					(hide yes)
				)
			)
			(property "Footprint" ""
				(at 8.89 -7.62 0)
				(effects
					(font
						(size 1.27 1.27)
						(thickness 0.15)
					)
					(justify left bottom)
					(hide yes)
				)
			)
			(property "Datasheet" ""
				(at 8.89 -12.7 0)
				(effects
					(font
						(size 1.27 1.27)
						(thickness 0.15)
					)
					(justify left bottom)
					(hide yes)
				)
			)
			(property "Description" ""
				(at 0 0 0)
				(effects
					(font
						(size 1.27 1.27)
					)
					(hide yes)
				)
			)
			(property "Author" "Antmicro"
				(at 8.89 -7.62 0)
				(effects
					(font
						(size 1.27 1.27)
						(thickness 0.15)
					)
					(justify left bottom)
					(hide yes)
				)
			)
			(property "License" "Apache-2.0"
				(at 8.89 -10.16 0)
				(effects
					(font
						(size 1.27 1.27)
						(thickness 0.15)
					)
					(justify left bottom)
					(hide yes)
				)
			)
			(symbol "GND_40_1_1"
				(polyline
					(pts
						(xy 0 0) (xy 0 -1.27) (xy 1.27 -1.27) (xy 0 -2.54) (xy -1.27 -1.27) (xy 0 -1.27)
					)
					(stroke
						(width 0.254)
						(type default)
					)
					(fill
						(type none)
					)
				)
				(pin power_in line
					(at 0 0 270)
					(length 0)
					(name "GND"
						(effects
							(font
								(size 1.27 1.27)
							)
						)
					)
					(number "1"
						(effects
							(font
								(size 1.27 1.27)
							)
						)
					)
				)
			)
		)
	(symbol "jetson-orin-baseboard:GND_41"
			(power)
			(pin_numbers hide)
			(pin_names hide)
			(exclude_from_sim no)
			(in_bom yes)
			(on_board yes)
			(property "Reference" "#PWR"
				(at 8.89 -2.54 0)
				(effects
					(font
						(size 1.27 1.27)
						(thickness 0.15)
					)
					(justify left bottom)
				)
			)
			(property "Value" "GND_41"
				(at 8.89 -5.08 0)
				(effects
					(font
						(size 1.27 1.27)
						(thickness 0.15)
					)
					(justify left bottom)
					(hide yes)
				)
			)
			(property "Footprint" ""
				(at 8.89 -7.62 0)
				(effects
					(font
						(size 1.27 1.27)
						(thickness 0.15)
					)
					(justify left bottom)
					(hide yes)
				)
			)
			(property "Datasheet" ""
				(at 8.89 -12.7 0)
				(effects
					(font
						(size 1.27 1.27)
						(thickness 0.15)
					)
					(justify left bottom)
					(hide yes)
				)
			)
			(property "Description" ""
				(at 0 0 0)
				(effects
					(font
						(size 1.27 1.27)
					)
					(hide yes)
				)
			)
			(property "Author" "Antmicro"
				(at 8.89 -7.62 0)
				(effects
					(font
						(size 1.27 1.27)
						(thickness 0.15)
					)
					(justify left bottom)
					(hide yes)
				)
			)
			(property "License" "Apache-2.0"
				(at 8.89 -10.16 0)
				(effects
					(font
						(size 1.27 1.27)
						(thickness 0.15)
					)
					(justify left bottom)
					(hide yes)
				)
			)
			(symbol "GND_41_1_1"
				(polyline
					(pts
						(xy 0 0) (xy 0 -1.27) (xy 1.27 -1.27) (xy 0 -2.54) (xy -1.27 -1.27) (xy 0 -1.27)
					)
					(stroke
						(width 0.254)
						(type default)
					)
					(fill
						(type none)
					)
				)
				(pin power_in line
					(at 0 0 270)
					(length 0)
					(name "GND"
						(effects
							(font
								(size 1.27 1.27)
							)
						)
					)
					(number "1"
						(effects
							(font
								(size 1.27 1.27)
							)
						)
					)
				)
			)
		)
	(symbol "jetson-orin-baseboard:GND_42"
			(power)
			(pin_numbers hide)
			(pin_names hide)
			(exclude_from_sim no)
			(in_bom yes)
			(on_board yes)
			(property "Reference" "#PWR"
				(at 8.89 -2.54 0)
				(effects
					(font
						(size 1.27 1.27)
						(thickness 0.15)
					)
					(justify left bottom)
				)
			)
			(property "Value" "GND_42"
				(at 8.89 -5.08 0)
				(effects
					(font
						(size 1.27 1.27)
						(thickness 0.15)
					)
					(justify left bottom)
					(hide yes)
				)
			)
			(property "Footprint" ""
				(at 8.89 -7.62 0)
				(effects
					(font
						(size 1.27 1.27)
						(thickness 0.15)
					)
					(justify left bottom)
					(hide yes)
				)
			)
			(property "Datasheet" ""
				(at 8.89 -12.7 0)
				(effects
					(font
						(size 1.27 1.27)
						(thickness 0.15)
					)
					(justify left bottom)
					(hide yes)
				)
			)
			(property "Description" ""
				(at 0 0 0)
				(effects
					(font
						(size 1.27 1.27)
					)
					(hide yes)
				)
			)
			(property "Author" "Antmicro"
				(at 8.89 -7.62 0)
				(effects
					(font
						(size 1.27 1.27)
						(thickness 0.15)
					)
					(justify left bottom)
					(hide yes)
				)
			)
			(property "License" "Apache-2.0"
				(at 8.89 -10.16 0)
				(effects
					(font
						(size 1.27 1.27)
						(thickness 0.15)
					)
					(justify left bottom)
					(hide yes)
				)
			)
			(symbol "GND_42_1_1"
				(polyline
					(pts
						(xy 0 0) (xy 0 -1.27) (xy 1.27 -1.27) (xy 0 -2.54) (xy -1.27 -1.27) (xy 0 -1.27)
					)
					(stroke
						(width 0.254)
						(type default)
					)
					(fill
						(type none)
					)
				)
				(pin power_in line
					(at 0 0 270)
					(length 0)
					(name "GND"
						(effects
							(font
								(size 1.27 1.27)
							)
						)
					)
					(number "1"
						(effects
							(font
								(size 1.27 1.27)
							)
						)
					)
				)
			)
		)
	(symbol "jetson-orin-baseboard:GND_43"
			(power)
			(pin_numbers hide)
			(pin_names hide)
			(exclude_from_sim no)
			(in_bom yes)
			(on_board yes)
			(property "Reference" "#PWR"
				(at 8.89 -2.54 0)
				(effects
					(font
						(size 1.27 1.27)
						(thickness 0.15)
					)
					(justify left bottom)
				)
			)
			(property "Value" "GND_43"
				(at 8.89 -5.08 0)
				(effects
					(font
						(size 1.27 1.27)
						(thickness 0.15)
					)
					(justify left bottom)
					(hide yes)
				)
			)
			(property "Footprint" ""
				(at 8.89 -7.62 0)
				(effects
					(font
						(size 1.27 1.27)
						(thickness 0.15)
					)
					(justify left bottom)
					(hide yes)
				)
			)
			(property "Datasheet" ""
				(at 8.89 -12.7 0)
				(effects
					(font
						(size 1.27 1.27)
						(thickness 0.15)
					)
					(justify left bottom)
					(hide yes)
				)
			)
			(property "Description" ""
				(at 0 0 0)
				(effects
					(font
						(size 1.27 1.27)
					)
					(hide yes)
				)
			)
			(property "Author" "Antmicro"
				(at 8.89 -7.62 0)
				(effects
					(font
						(size 1.27 1.27)
						(thickness 0.15)
					)
					(justify left bottom)
					(hide yes)
				)
			)
			(property "License" "Apache-2.0"
				(at 8.89 -10.16 0)
				(effects
					(font
						(size 1.27 1.27)
						(thickness 0.15)
					)
					(justify left bottom)
					(hide yes)
				)
			)
			(symbol "GND_43_1_1"
				(polyline
					(pts
						(xy 0 0) (xy 0 -1.27) (xy 1.27 -1.27) (xy 0 -2.54) (xy -1.27 -1.27) (xy 0 -1.27)
					)
					(stroke
						(width 0.254)
						(type default)
					)
					(fill
						(type none)
					)
				)
				(pin power_in line
					(at 0 0 270)
					(length 0)
					(name "GND"
						(effects
							(font
								(size 1.27 1.27)
							)
						)
					)
					(number "1"
						(effects
							(font
								(size 1.27 1.27)
							)
						)
					)
				)
			)
		)
	(symbol "jetson-orin-baseboard:GND_44"
			(power)
			(pin_numbers hide)
			(pin_names hide)
			(exclude_from_sim no)
			(in_bom yes)
			(on_board yes)
			(property "Reference" "#PWR"
				(at 8.89 -2.54 0)
				(effects
					(font
						(size 1.27 1.27)
						(thickness 0.15)
					)
					(justify left bottom)
				)
			)
			(property "Value" "GND_44"
				(at 8.89 -5.08 0)
				(effects
					(font
						(size 1.27 1.27)
						(thickness 0.15)
					)
					(justify left bottom)
					(hide yes)
				)
			)
			(property "Footprint" ""
				(at 8.89 -7.62 0)
				(effects
					(font
						(size 1.27 1.27)
						(thickness 0.15)
					)
					(justify left bottom)
					(hide yes)
				)
			)
			(property "Datasheet" ""
				(at 8.89 -12.7 0)
				(effects
					(font
						(size 1.27 1.27)
						(thickness 0.15)
					)
					(justify left bottom)
					(hide yes)
				)
			)
			(property "Description" ""
				(at 0 0 0)
				(effects
					(font
						(size 1.27 1.27)
					)
					(hide yes)
				)
			)
			(property "Author" "Antmicro"
				(at 8.89 -7.62 0)
				(effects
					(font
						(size 1.27 1.27)
						(thickness 0.15)
					)
					(justify left bottom)
					(hide yes)
				)
			)
			(property "License" "Apache-2.0"
				(at 8.89 -10.16 0)
				(effects
					(font
						(size 1.27 1.27)
						(thickness 0.15)
					)
					(justify left bottom)
					(hide yes)
				)
			)
			(symbol "GND_44_1_1"
				(polyline
					(pts
						(xy 0 0) (xy 0 -1.27) (xy 1.27 -1.27) (xy 0 -2.54) (xy -1.27 -1.27) (xy 0 -1.27)
					)
					(stroke
						(width 0.254)
						(type default)
					)
					(fill
						(type none)
					)
				)
				(pin power_in line
					(at 0 0 270)
					(length 0)
					(name "GND"
						(effects
							(font
								(size 1.27 1.27)
							)
						)
					)
					(number "1"
						(effects
							(font
								(size 1.27 1.27)
							)
						)
					)
				)
			)
		)
	(symbol "jetson-orin-baseboard:GND_45"
			(power)
			(pin_numbers hide)
			(pin_names hide)
			(exclude_from_sim no)
			(in_bom yes)
			(on_board yes)
			(property "Reference" "#PWR"
				(at 8.89 -2.54 0)
				(effects
					(font
						(size 1.27 1.27)
						(thickness 0.15)
					)
					(justify left bottom)
				)
			)
			(property "Value" "GND_45"
				(at 8.89 -5.08 0)
				(effects
					(font
						(size 1.27 1.27)
						(thickness 0.15)
					)
					(justify left bottom)
					(hide yes)
				)
			)
			(property "Footprint" ""
				(at 8.89 -7.62 0)
				(effects
					(font
						(size 1.27 1.27)
						(thickness 0.15)
					)
					(justify left bottom)
					(hide yes)
				)
			)
			(property "Datasheet" ""
				(at 8.89 -12.7 0)
				(effects
					(font
						(size 1.27 1.27)
						(thickness 0.15)
					)
					(justify left bottom)
					(hide yes)
				)
			)
			(property "Description" ""
				(at 0 0 0)
				(effects
					(font
						(size 1.27 1.27)
					)
					(hide yes)
				)
			)
			(property "Author" "Antmicro"
				(at 8.89 -7.62 0)
				(effects
					(font
						(size 1.27 1.27)
						(thickness 0.15)
					)
					(justify left bottom)
					(hide yes)
				)
			)
			(property "License" "Apache-2.0"
				(at 8.89 -10.16 0)
				(effects
					(font
						(size 1.27 1.27)
						(thickness 0.15)
					)
					(justify left bottom)
					(hide yes)
				)
			)
			(symbol "GND_45_1_1"
				(polyline
					(pts
						(xy 0 0) (xy 0 -1.27) (xy 1.27 -1.27) (xy 0 -2.54) (xy -1.27 -1.27) (xy 0 -1.27)
					)
					(stroke
						(width 0.254)
						(type default)
					)
					(fill
						(type none)
					)
				)
				(pin power_in line
					(at 0 0 270)
					(length 0)
					(name "GND"
						(effects
							(font
								(size 1.27 1.27)
							)
						)
					)
					(number "1"
						(effects
							(font
								(size 1.27 1.27)
							)
						)
					)
				)
			)
		)
	(symbol "jetson-orin-baseboard:GND_46"
			(power)
			(pin_numbers hide)
			(pin_names hide)
			(exclude_from_sim no)
			(in_bom yes)
			(on_board yes)
			(property "Reference" "#PWR"
				(at 8.89 -2.54 0)
				(effects
					(font
						(size 1.27 1.27)
						(thickness 0.15)
					)
					(justify left bottom)
				)
			)
			(property "Value" "GND_46"
				(at 8.89 -5.08 0)
				(effects
					(font
						(size 1.27 1.27)
						(thickness 0.15)
					)
					(justify left bottom)
					(hide yes)
				)
			)
			(property "Footprint" ""
				(at 8.89 -7.62 0)
				(effects
					(font
						(size 1.27 1.27)
						(thickness 0.15)
					)
					(justify left bottom)
					(hide yes)
				)
			)
			(property "Datasheet" ""
				(at 8.89 -12.7 0)
				(effects
					(font
						(size 1.27 1.27)
						(thickness 0.15)
					)
					(justify left bottom)
					(hide yes)
				)
			)
			(property "Description" ""
				(at 0 0 0)
				(effects
					(font
						(size 1.27 1.27)
					)
					(hide yes)
				)
			)
			(property "Author" "Antmicro"
				(at 8.89 -7.62 0)
				(effects
					(font
						(size 1.27 1.27)
						(thickness 0.15)
					)
					(justify left bottom)
					(hide yes)
				)
			)
			(property "License" "Apache-2.0"
				(at 8.89 -10.16 0)
				(effects
					(font
						(size 1.27 1.27)
						(thickness 0.15)
					)
					(justify left bottom)
					(hide yes)
				)
			)
			(symbol "GND_46_1_1"
				(polyline
					(pts
						(xy 0 0) (xy 0 -1.27) (xy 1.27 -1.27) (xy 0 -2.54) (xy -1.27 -1.27) (xy 0 -1.27)
					)
					(stroke
						(width 0.254)
						(type default)
					)
					(fill
						(type none)
					)
				)
				(pin power_in line
					(at 0 0 270)
					(length 0)
					(name "GND"
						(effects
							(font
								(size 1.27 1.27)
							)
						)
					)
					(number "1"
						(effects
							(font
								(size 1.27 1.27)
							)
						)
					)
				)
			)
		)
	(symbol "jetson-orin-baseboard:GND_47"
			(power)
			(pin_numbers hide)
			(pin_names hide)
			(exclude_from_sim no)
			(in_bom yes)
			(on_board yes)
			(property "Reference" "#PWR"
				(at 8.89 -2.54 0)
				(effects
					(font
						(size 1.27 1.27)
						(thickness 0.15)
					)
					(justify left bottom)
				)
			)
			(property "Value" "GND_47"
				(at 8.89 -5.08 0)
				(effects
					(font
						(size 1.27 1.27)
						(thickness 0.15)
					)
					(justify left bottom)
					(hide yes)
				)
			)
			(property "Footprint" ""
				(at 8.89 -7.62 0)
				(effects
					(font
						(size 1.27 1.27)
						(thickness 0.15)
					)
					(justify left bottom)
					(hide yes)
				)
			)
			(property "Datasheet" ""
				(at 8.89 -12.7 0)
				(effects
					(font
						(size 1.27 1.27)
						(thickness 0.15)
					)
					(justify left bottom)
					(hide yes)
				)
			)
			(property "Description" ""
				(at 0 0 0)
				(effects
					(font
						(size 1.27 1.27)
					)
					(hide yes)
				)
			)
			(property "Author" "Antmicro"
				(at 8.89 -7.62 0)
				(effects
					(font
						(size 1.27 1.27)
						(thickness 0.15)
					)
					(justify left bottom)
					(hide yes)
				)
			)
			(property "License" "Apache-2.0"
				(at 8.89 -10.16 0)
				(effects
					(font
						(size 1.27 1.27)
						(thickness 0.15)
					)
					(justify left bottom)
					(hide yes)
				)
			)
			(symbol "GND_47_1_1"
				(polyline
					(pts
						(xy 0 0) (xy 0 -1.27) (xy 1.27 -1.27) (xy 0 -2.54) (xy -1.27 -1.27) (xy 0 -1.27)
					)
					(stroke
						(width 0.254)
						(type default)
					)
					(fill
						(type none)
					)
				)
				(pin power_in line
					(at 0 0 270)
					(length 0)
					(name "GND"
						(effects
							(font
								(size 1.27 1.27)
							)
						)
					)
					(number "1"
						(effects
							(font
								(size 1.27 1.27)
							)
						)
					)
				)
			)
		)
	(symbol "jetson-orin-baseboard:GND_48"
			(power)
			(pin_numbers hide)
			(pin_names hide)
			(exclude_from_sim no)
			(in_bom yes)
			(on_board yes)
			(property "Reference" "#PWR"
				(at 8.89 -2.54 0)
				(effects
					(font
						(size 1.27 1.27)
						(thickness 0.15)
					)
					(justify left bottom)
				)
			)
			(property "Value" "GND_48"
				(at 8.89 -5.08 0)
				(effects
					(font
						(size 1.27 1.27)
						(thickness 0.15)
					)
					(justify left bottom)
					(hide yes)
				)
			)
			(property "Footprint" ""
				(at 8.89 -7.62 0)
				(effects
					(font
						(size 1.27 1.27)
						(thickness 0.15)
					)
					(justify left bottom)
					(hide yes)
				)
			)
			(property "Datasheet" ""
				(at 8.89 -12.7 0)
				(effects
					(font
						(size 1.27 1.27)
						(thickness 0.15)
					)
					(justify left bottom)
					(hide yes)
				)
			)
			(property "Description" ""
				(at 0 0 0)
				(effects
					(font
						(size 1.27 1.27)
					)
					(hide yes)
				)
			)
			(property "Author" "Antmicro"
				(at 8.89 -7.62 0)
				(effects
					(font
						(size 1.27 1.27)
						(thickness 0.15)
					)
					(justify left bottom)
					(hide yes)
				)
			)
			(property "License" "Apache-2.0"
				(at 8.89 -10.16 0)
				(effects
					(font
						(size 1.27 1.27)
						(thickness 0.15)
					)
					(justify left bottom)
					(hide yes)
				)
			)
			(symbol "GND_48_1_1"
				(polyline
					(pts
						(xy 0 0) (xy 0 -1.27) (xy 1.27 -1.27) (xy 0 -2.54) (xy -1.27 -1.27) (xy 0 -1.27)
					)
					(stroke
						(width 0.254)
						(type default)
					)
					(fill
						(type none)
					)
				)
				(pin power_in line
					(at 0 0 270)
					(length 0)
					(name "GND"
						(effects
							(font
								(size 1.27 1.27)
							)
						)
					)
					(number "1"
						(effects
							(font
								(size 1.27 1.27)
							)
						)
					)
				)
			)
		)
	(symbol "jetson-orin-baseboard:GND_49"
			(power)
			(pin_numbers hide)
			(pin_names hide)
			(exclude_from_sim no)
			(in_bom yes)
			(on_board yes)
			(property "Reference" "#PWR"
				(at 8.89 -2.54 0)
				(effects
					(font
						(size 1.27 1.27)
						(thickness 0.15)
					)
					(justify left bottom)
				)
			)
			(property "Value" "GND_49"
				(at 8.89 -5.08 0)
				(effects
					(font
						(size 1.27 1.27)
						(thickness 0.15)
					)
					(justify left bottom)
					(hide yes)
				)
			)
			(property "Footprint" ""
				(at 8.89 -7.62 0)
				(effects
					(font
						(size 1.27 1.27)
						(thickness 0.15)
					)
					(justify left bottom)
					(hide yes)
				)
			)
			(property "Datasheet" ""
				(at 8.89 -12.7 0)
				(effects
					(font
						(size 1.27 1.27)
						(thickness 0.15)
					)
					(justify left bottom)
					(hide yes)
				)
			)
			(property "Description" ""
				(at 0 0 0)
				(effects
					(font
						(size 1.27 1.27)
					)
					(hide yes)
				)
			)
			(property "Author" "Antmicro"
				(at 8.89 -7.62 0)
				(effects
					(font
						(size 1.27 1.27)
						(thickness 0.15)
					)
					(justify left bottom)
					(hide yes)
				)
			)
			(property "License" "Apache-2.0"
				(at 8.89 -10.16 0)
				(effects
					(font
						(size 1.27 1.27)
						(thickness 0.15)
					)
					(justify left bottom)
					(hide yes)
				)
			)
			(symbol "GND_49_1_1"
				(polyline
					(pts
						(xy 0 0) (xy 0 -1.27) (xy 1.27 -1.27) (xy 0 -2.54) (xy -1.27 -1.27) (xy 0 -1.27)
					)
					(stroke
						(width 0.254)
						(type default)
					)
					(fill
						(type none)
					)
				)
				(pin power_in line
					(at 0 0 270)
					(length 0)
					(name "GND"
						(effects
							(font
								(size 1.27 1.27)
							)
						)
					)
					(number "1"
						(effects
							(font
								(size 1.27 1.27)
							)
						)
					)
				)
			)
		)
	(symbol "jetson-orin-baseboard:GND_50"
			(power)
			(pin_numbers hide)
			(pin_names hide)
			(exclude_from_sim no)
			(in_bom yes)
			(on_board yes)
			(property "Reference" "#PWR"
				(at 8.89 -2.54 0)
				(effects
					(font
						(size 1.27 1.27)
						(thickness 0.15)
					)
					(justify left bottom)
				)
			)
			(property "Value" "GND_50"
				(at 8.89 -5.08 0)
				(effects
					(font
						(size 1.27 1.27)
						(thickness 0.15)
					)
					(justify left bottom)
					(hide yes)
				)
			)
			(property "Footprint" ""
				(at 8.89 -7.62 0)
				(effects
					(font
						(size 1.27 1.27)
						(thickness 0.15)
					)
					(justify left bottom)
					(hide yes)
				)
			)
			(property "Datasheet" ""
				(at 8.89 -12.7 0)
				(effects
					(font
						(size 1.27 1.27)
						(thickness 0.15)
					)
					(justify left bottom)
					(hide yes)
				)
			)
			(property "Description" ""
				(at 0 0 0)
				(effects
					(font
						(size 1.27 1.27)
					)
					(hide yes)
				)
			)
			(property "Author" "Antmicro"
				(at 8.89 -7.62 0)
				(effects
					(font
						(size 1.27 1.27)
						(thickness 0.15)
					)
					(justify left bottom)
					(hide yes)
				)
			)
			(property "License" "Apache-2.0"
				(at 8.89 -10.16 0)
				(effects
					(font
						(size 1.27 1.27)
						(thickness 0.15)
					)
					(justify left bottom)
					(hide yes)
				)
			)
			(symbol "GND_50_1_1"
				(polyline
					(pts
						(xy 0 0) (xy 0 -1.27) (xy 1.27 -1.27) (xy 0 -2.54) (xy -1.27 -1.27) (xy 0 -1.27)
					)
					(stroke
						(width 0.254)
						(type default)
					)
					(fill
						(type none)
					)
				)
				(pin power_in line
					(at 0 0 270)
					(length 0)
					(name "GND"
						(effects
							(font
								(size 1.27 1.27)
							)
						)
					)
					(number "1"
						(effects
							(font
								(size 1.27 1.27)
							)
						)
					)
				)
			)
		)
	(symbol "jetson-orin-baseboard:GND_51"
			(power)
			(pin_numbers hide)
			(pin_names hide)
			(exclude_from_sim no)
			(in_bom yes)
			(on_board yes)
			(property "Reference" "#PWR"
				(at 8.89 -2.54 0)
				(effects
					(font
						(size 1.27 1.27)
						(thickness 0.15)
					)
					(justify left bottom)
				)
			)
			(property "Value" "GND_51"
				(at 8.89 -5.08 0)
				(effects
					(font
						(size 1.27 1.27)
						(thickness 0.15)
					)
					(justify left bottom)
					(hide yes)
				)
			)
			(property "Footprint" ""
				(at 8.89 -7.62 0)
				(effects
					(font
						(size 1.27 1.27)
						(thickness 0.15)
					)
					(justify left bottom)
					(hide yes)
				)
			)
			(property "Datasheet" ""
				(at 8.89 -12.7 0)
				(effects
					(font
						(size 1.27 1.27)
						(thickness 0.15)
					)
					(justify left bottom)
					(hide yes)
				)
			)
			(property "Description" ""
				(at 0 0 0)
				(effects
					(font
						(size 1.27 1.27)
					)
					(hide yes)
				)
			)
			(property "Author" "Antmicro"
				(at 8.89 -7.62 0)
				(effects
					(font
						(size 1.27 1.27)
						(thickness 0.15)
					)
					(justify left bottom)
					(hide yes)
				)
			)
			(property "License" "Apache-2.0"
				(at 8.89 -10.16 0)
				(effects
					(font
						(size 1.27 1.27)
						(thickness 0.15)
					)
					(justify left bottom)
					(hide yes)
				)
			)
			(symbol "GND_51_1_1"
				(polyline
					(pts
						(xy 0 0) (xy 0 -1.27) (xy 1.27 -1.27) (xy 0 -2.54) (xy -1.27 -1.27) (xy 0 -1.27)
					)
					(stroke
						(width 0.254)
						(type default)
					)
					(fill
						(type none)
					)
				)
				(pin power_in line
					(at 0 0 270)
					(length 0)
					(name "GND"
						(effects
							(font
								(size 1.27 1.27)
							)
						)
					)
					(number "1"
						(effects
							(font
								(size 1.27 1.27)
							)
						)
					)
				)
			)
		)
	(symbol "jetson-orin-baseboard:GND_52"
			(power)
			(pin_numbers hide)
			(pin_names hide)
			(exclude_from_sim no)
			(in_bom yes)
			(on_board yes)
			(property "Reference" "#PWR"
				(at 8.89 -2.54 0)
				(effects
					(font
						(size 1.27 1.27)
						(thickness 0.15)
					)
					(justify left bottom)
				)
			)
			(property "Value" "GND_52"
				(at 8.89 -5.08 0)
				(effects
					(font
						(size 1.27 1.27)
						(thickness 0.15)
					)
					(justify left bottom)
					(hide yes)
				)
			)
			(property "Footprint" ""
				(at 8.89 -7.62 0)
				(effects
					(font
						(size 1.27 1.27)
						(thickness 0.15)
					)
					(justify left bottom)
					(hide yes)
				)
			)
			(property "Datasheet" ""
				(at 8.89 -12.7 0)
				(effects
					(font
						(size 1.27 1.27)
						(thickness 0.15)
					)
					(justify left bottom)
					(hide yes)
				)
			)
			(property "Description" ""
				(at 0 0 0)
				(effects
					(font
						(size 1.27 1.27)
					)
					(hide yes)
				)
			)
			(property "Author" "Antmicro"
				(at 8.89 -7.62 0)
				(effects
					(font
						(size 1.27 1.27)
						(thickness 0.15)
					)
					(justify left bottom)
					(hide yes)
				)
			)
			(property "License" "Apache-2.0"
				(at 8.89 -10.16 0)
				(effects
					(font
						(size 1.27 1.27)
						(thickness 0.15)
					)
					(justify left bottom)
					(hide yes)
				)
			)
			(symbol "GND_52_1_1"
				(polyline
					(pts
						(xy 0 0) (xy 0 -1.27) (xy 1.27 -1.27) (xy 0 -2.54) (xy -1.27 -1.27) (xy 0 -1.27)
					)
					(stroke
						(width 0.254)
						(type default)
					)
					(fill
						(type none)
					)
				)
				(pin power_in line
					(at 0 0 270)
					(length 0)
					(name "GND"
						(effects
							(font
								(size 1.27 1.27)
							)
						)
					)
					(number "1"
						(effects
							(font
								(size 1.27 1.27)
							)
						)
					)
				)
			)
		)
	(symbol "jetson-orin-baseboard:GND_53"
			(power)
			(pin_numbers hide)
			(pin_names hide)
			(exclude_from_sim no)
			(in_bom yes)
			(on_board yes)
			(property "Reference" "#PWR"
				(at 8.89 -2.54 0)
				(effects
					(font
						(size 1.27 1.27)
						(thickness 0.15)
					)
					(justify left bottom)
				)
			)
			(property "Value" "GND_53"
				(at 8.89 -5.08 0)
				(effects
					(font
						(size 1.27 1.27)
						(thickness 0.15)
					)
					(justify left bottom)
					(hide yes)
				)
			)
			(property "Footprint" ""
				(at 8.89 -7.62 0)
				(effects
					(font
						(size 1.27 1.27)
						(thickness 0.15)
					)
					(justify left bottom)
					(hide yes)
				)
			)
			(property "Datasheet" ""
				(at 8.89 -12.7 0)
				(effects
					(font
						(size 1.27 1.27)
						(thickness 0.15)
					)
					(justify left bottom)
					(hide yes)
				)
			)
			(property "Description" ""
				(at 0 0 0)
				(effects
					(font
						(size 1.27 1.27)
					)
					(hide yes)
				)
			)
			(property "Author" "Antmicro"
				(at 8.89 -7.62 0)
				(effects
					(font
						(size 1.27 1.27)
						(thickness 0.15)
					)
					(justify left bottom)
					(hide yes)
				)
			)
			(property "License" "Apache-2.0"
				(at 8.89 -10.16 0)
				(effects
					(font
						(size 1.27 1.27)
						(thickness 0.15)
					)
					(justify left bottom)
					(hide yes)
				)
			)
			(symbol "GND_53_1_1"
				(polyline
					(pts
						(xy 0 0) (xy 0 -1.27) (xy 1.27 -1.27) (xy 0 -2.54) (xy -1.27 -1.27) (xy 0 -1.27)
					)
					(stroke
						(width 0.254)
						(type default)
					)
					(fill
						(type none)
					)
				)
				(pin power_in line
					(at 0 0 270)
					(length 0)
					(name "GND"
						(effects
							(font
								(size 1.27 1.27)
							)
						)
					)
					(number "1"
						(effects
							(font
								(size 1.27 1.27)
							)
						)
					)
				)
			)
		)
	(symbol "jetson-orin-baseboard:GND_54"
			(power)
			(pin_numbers hide)
			(pin_names hide)
			(exclude_from_sim no)
			(in_bom yes)
			(on_board yes)
			(property "Reference" "#PWR"
				(at 8.89 -2.54 0)
				(effects
					(font
						(size 1.27 1.27)
						(thickness 0.15)
					)
					(justify left bottom)
				)
			)
			(property "Value" "GND_54"
				(at 8.89 -5.08 0)
				(effects
					(font
						(size 1.27 1.27)
						(thickness 0.15)
					)
					(justify left bottom)
					(hide yes)
				)
			)
			(property "Footprint" ""
				(at 8.89 -7.62 0)
				(effects
					(font
						(size 1.27 1.27)
						(thickness 0.15)
					)
					(justify left bottom)
					(hide yes)
				)
			)
			(property "Datasheet" ""
				(at 8.89 -12.7 0)
				(effects
					(font
						(size 1.27 1.27)
						(thickness 0.15)
					)
					(justify left bottom)
					(hide yes)
				)
			)
			(property "Description" ""
				(at 0 0 0)
				(effects
					(font
						(size 1.27 1.27)
					)
					(hide yes)
				)
			)
			(property "Author" "Antmicro"
				(at 8.89 -7.62 0)
				(effects
					(font
						(size 1.27 1.27)
						(thickness 0.15)
					)
					(justify left bottom)
					(hide yes)
				)
			)
			(property "License" "Apache-2.0"
				(at 8.89 -10.16 0)
				(effects
					(font
						(size 1.27 1.27)
						(thickness 0.15)
					)
					(justify left bottom)
					(hide yes)
				)
			)
			(symbol "GND_54_1_1"
				(polyline
					(pts
						(xy 0 0) (xy 0 -1.27) (xy 1.27 -1.27) (xy 0 -2.54) (xy -1.27 -1.27) (xy 0 -1.27)
					)
					(stroke
						(width 0.254)
						(type default)
					)
					(fill
						(type none)
					)
				)
				(pin power_in line
					(at 0 0 270)
					(length 0)
					(name "GND"
						(effects
							(font
								(size 1.27 1.27)
							)
						)
					)
					(number "1"
						(effects
							(font
								(size 1.27 1.27)
							)
						)
					)
				)
			)
		)
	(symbol "jetson-orin-baseboard:GND_55"
			(power)
			(pin_numbers hide)
			(pin_names hide)
			(exclude_from_sim no)
			(in_bom yes)
			(on_board yes)
			(property "Reference" "#PWR"
				(at 8.89 -2.54 0)
				(effects
					(font
						(size 1.27 1.27)
						(thickness 0.15)
					)
					(justify left bottom)
				)
			)
			(property "Value" "GND_55"
				(at 8.89 -5.08 0)
				(effects
					(font
						(size 1.27 1.27)
						(thickness 0.15)
					)
					(justify left bottom)
					(hide yes)
				)
			)
			(property "Footprint" ""
				(at 8.89 -7.62 0)
				(effects
					(font
						(size 1.27 1.27)
						(thickness 0.15)
					)
					(justify left bottom)
					(hide yes)
				)
			)
			(property "Datasheet" ""
				(at 8.89 -12.7 0)
				(effects
					(font
						(size 1.27 1.27)
						(thickness 0.15)
					)
					(justify left bottom)
					(hide yes)
				)
			)
			(property "Description" ""
				(at 0 0 0)
				(effects
					(font
						(size 1.27 1.27)
					)
					(hide yes)
				)
			)
			(property "Author" "Antmicro"
				(at 8.89 -7.62 0)
				(effects
					(font
						(size 1.27 1.27)
						(thickness 0.15)
					)
					(justify left bottom)
					(hide yes)
				)
			)
			(property "License" "Apache-2.0"
				(at 8.89 -10.16 0)
				(effects
					(font
						(size 1.27 1.27)
						(thickness 0.15)
					)
					(justify left bottom)
					(hide yes)
				)
			)
			(symbol "GND_55_1_1"
				(polyline
					(pts
						(xy 0 0) (xy 0 -1.27) (xy 1.27 -1.27) (xy 0 -2.54) (xy -1.27 -1.27) (xy 0 -1.27)
					)
					(stroke
						(width 0.254)
						(type default)
					)
					(fill
						(type none)
					)
				)
				(pin power_in line
					(at 0 0 270)
					(length 0)
					(name "GND"
						(effects
							(font
								(size 1.27 1.27)
							)
						)
					)
					(number "1"
						(effects
							(font
								(size 1.27 1.27)
							)
						)
					)
				)
			)
		)
	(symbol "jetson-orin-baseboard:GND_56"
			(power)
			(pin_numbers hide)
			(pin_names hide)
			(exclude_from_sim no)
			(in_bom yes)
			(on_board yes)
			(property "Reference" "#PWR"
				(at 8.89 -2.54 0)
				(effects
					(font
						(size 1.27 1.27)
						(thickness 0.15)
					)
					(justify left bottom)
				)
			)
			(property "Value" "GND_56"
				(at 8.89 -5.08 0)
				(effects
					(font
						(size 1.27 1.27)
						(thickness 0.15)
					)
					(justify left bottom)
					(hide yes)
				)
			)
			(property "Footprint" ""
				(at 8.89 -7.62 0)
				(effects
					(font
						(size 1.27 1.27)
						(thickness 0.15)
					)
					(justify left bottom)
					(hide yes)
				)
			)
			(property "Datasheet" ""
				(at 8.89 -12.7 0)
				(effects
					(font
						(size 1.27 1.27)
						(thickness 0.15)
					)
					(justify left bottom)
					(hide yes)
				)
			)
			(property "Description" ""
				(at 0 0 0)
				(effects
					(font
						(size 1.27 1.27)
					)
					(hide yes)
				)
			)
			(property "Author" "Antmicro"
				(at 8.89 -7.62 0)
				(effects
					(font
						(size 1.27 1.27)
						(thickness 0.15)
					)
					(justify left bottom)
					(hide yes)
				)
			)
			(property "License" "Apache-2.0"
				(at 8.89 -10.16 0)
				(effects
					(font
						(size 1.27 1.27)
						(thickness 0.15)
					)
					(justify left bottom)
					(hide yes)
				)
			)
			(symbol "GND_56_1_1"
				(polyline
					(pts
						(xy 0 0) (xy 0 -1.27) (xy 1.27 -1.27) (xy 0 -2.54) (xy -1.27 -1.27) (xy 0 -1.27)
					)
					(stroke
						(width 0.254)
						(type default)
					)
					(fill
						(type none)
					)
				)
				(pin power_in line
					(at 0 0 270)
					(length 0)
					(name "GND"
						(effects
							(font
								(size 1.27 1.27)
							)
						)
					)
					(number "1"
						(effects
							(font
								(size 1.27 1.27)
							)
						)
					)
				)
			)
		)
	(symbol "jetson-orin-baseboard:GND_57"
			(power)
			(pin_numbers hide)
			(pin_names hide)
			(exclude_from_sim no)
			(in_bom yes)
			(on_board yes)
			(property "Reference" "#PWR"
				(at 8.89 -2.54 0)
				(effects
					(font
						(size 1.27 1.27)
						(thickness 0.15)
					)
					(justify left bottom)
				)
			)
			(property "Value" "GND_57"
				(at 8.89 -5.08 0)
				(effects
					(font
						(size 1.27 1.27)
						(thickness 0.15)
					)
					(justify left bottom)
					(hide yes)
				)
			)
			(property "Footprint" ""
				(at 8.89 -7.62 0)
				(effects
					(font
						(size 1.27 1.27)
						(thickness 0.15)
					)
					(justify left bottom)
					(hide yes)
				)
			)
			(property "Datasheet" ""
				(at 8.89 -12.7 0)
				(effects
					(font
						(size 1.27 1.27)
						(thickness 0.15)
					)
					(justify left bottom)
					(hide yes)
				)
			)
			(property "Description" ""
				(at 0 0 0)
				(effects
					(font
						(size 1.27 1.27)
					)
					(hide yes)
				)
			)
			(property "Author" "Antmicro"
				(at 8.89 -7.62 0)
				(effects
					(font
						(size 1.27 1.27)
						(thickness 0.15)
					)
					(justify left bottom)
					(hide yes)
				)
			)
			(property "License" "Apache-2.0"
				(at 8.89 -10.16 0)
				(effects
					(font
						(size 1.27 1.27)
						(thickness 0.15)
					)
					(justify left bottom)
					(hide yes)
				)
			)
			(symbol "GND_57_1_1"
				(polyline
					(pts
						(xy 0 0) (xy 0 -1.27) (xy 1.27 -1.27) (xy 0 -2.54) (xy -1.27 -1.27) (xy 0 -1.27)
					)
					(stroke
						(width 0.254)
						(type default)
					)
					(fill
						(type none)
					)
				)
				(pin power_in line
					(at 0 0 270)
					(length 0)
					(name "GND"
						(effects
							(font
								(size 1.27 1.27)
							)
						)
					)
					(number "1"
						(effects
							(font
								(size 1.27 1.27)
							)
						)
					)
				)
			)
		)
	(symbol "jetson-orin-baseboard:GND_58"
			(power)
			(pin_numbers hide)
			(pin_names hide)
			(exclude_from_sim no)
			(in_bom yes)
			(on_board yes)
			(property "Reference" "#PWR"
				(at 8.89 -2.54 0)
				(effects
					(font
						(size 1.27 1.27)
						(thickness 0.15)
					)
					(justify left bottom)
				)
			)
			(property "Value" "GND_58"
				(at 8.89 -5.08 0)
				(effects
					(font
						(size 1.27 1.27)
						(thickness 0.15)
					)
					(justify left bottom)
					(hide yes)
				)
			)
			(property "Footprint" ""
				(at 8.89 -7.62 0)
				(effects
					(font
						(size 1.27 1.27)
						(thickness 0.15)
					)
					(justify left bottom)
					(hide yes)
				)
			)
			(property "Datasheet" ""
				(at 8.89 -12.7 0)
				(effects
					(font
						(size 1.27 1.27)
						(thickness 0.15)
					)
					(justify left bottom)
					(hide yes)
				)
			)
			(property "Description" ""
				(at 0 0 0)
				(effects
					(font
						(size 1.27 1.27)
					)
					(hide yes)
				)
			)
			(property "Author" "Antmicro"
				(at 8.89 -7.62 0)
				(effects
					(font
						(size 1.27 1.27)
						(thickness 0.15)
					)
					(justify left bottom)
					(hide yes)
				)
			)
			(property "License" "Apache-2.0"
				(at 8.89 -10.16 0)
				(effects
					(font
						(size 1.27 1.27)
						(thickness 0.15)
					)
					(justify left bottom)
					(hide yes)
				)
			)
			(symbol "GND_58_1_1"
				(polyline
					(pts
						(xy 0 0) (xy 0 -1.27) (xy 1.27 -1.27) (xy 0 -2.54) (xy -1.27 -1.27) (xy 0 -1.27)
					)
					(stroke
						(width 0.254)
						(type default)
					)
					(fill
						(type none)
					)
				)
				(pin power_in line
					(at 0 0 270)
					(length 0)
					(name "GND"
						(effects
							(font
								(size 1.27 1.27)
							)
						)
					)
					(number "1"
						(effects
							(font
								(size 1.27 1.27)
							)
						)
					)
				)
			)
		)
	(symbol "jetson-orin-baseboard:GND_59"
			(power)
			(pin_numbers hide)
			(pin_names hide)
			(exclude_from_sim no)
			(in_bom yes)
			(on_board yes)
			(property "Reference" "#PWR"
				(at 8.89 -2.54 0)
				(effects
					(font
						(size 1.27 1.27)
						(thickness 0.15)
					)
					(justify left bottom)
				)
			)
			(property "Value" "GND_59"
				(at 8.89 -5.08 0)
				(effects
					(font
						(size 1.27 1.27)
						(thickness 0.15)
					)
					(justify left bottom)
					(hide yes)
				)
			)
			(property "Footprint" ""
				(at 8.89 -7.62 0)
				(effects
					(font
						(size 1.27 1.27)
						(thickness 0.15)
					)
					(justify left bottom)
					(hide yes)
				)
			)
			(property "Datasheet" ""
				(at 8.89 -12.7 0)
				(effects
					(font
						(size 1.27 1.27)
						(thickness 0.15)
					)
					(justify left bottom)
					(hide yes)
				)
			)
			(property "Description" ""
				(at 0 0 0)
				(effects
					(font
						(size 1.27 1.27)
					)
					(hide yes)
				)
			)
			(property "Author" "Antmicro"
				(at 8.89 -7.62 0)
				(effects
					(font
						(size 1.27 1.27)
						(thickness 0.15)
					)
					(justify left bottom)
					(hide yes)
				)
			)
			(property "License" "Apache-2.0"
				(at 8.89 -10.16 0)
				(effects
					(font
						(size 1.27 1.27)
						(thickness 0.15)
					)
					(justify left bottom)
					(hide yes)
				)
			)
			(symbol "GND_59_1_1"
				(polyline
					(pts
						(xy 0 0) (xy 0 -1.27) (xy 1.27 -1.27) (xy 0 -2.54) (xy -1.27 -1.27) (xy 0 -1.27)
					)
					(stroke
						(width 0.254)
						(type default)
					)
					(fill
						(type none)
					)
				)
				(pin power_in line
					(at 0 0 270)
					(length 0)
					(name "GND"
						(effects
							(font
								(size 1.27 1.27)
							)
						)
					)
					(number "1"
						(effects
							(font
								(size 1.27 1.27)
							)
						)
					)
				)
			)
		)
	(symbol "jetson-orin-baseboard:Jetson-Orin-9.2H-socket"
			(pin_names
				(offset 1.016)
			)
			(exclude_from_sim no)
			(in_bom yes)
			(on_board yes)
			(property "Reference" "A"
				(at 1.27 1.27 0)
				(effects
					(font
						(size 1.27 1.27)
					)
				)
			)
			(property "Value" "Jetson-Orin-9.2H-socket_1"
				(at 15.24 2.54 0)
				(effects
					(font
						(size 1.27 1.27)
					)
					(hide yes)
				)
			)
			(property "Footprint" "jetson-orin-baseboard-footprints:TE_2309413"
				(at 15.24 5.08 0)
				(effects
					(font
						(size 1.27 1.27)
					)
					(hide yes)
				)
			)
			(property "Datasheet" "https://developer.nvidia.com/jetson-orin-nx-series-data-sheet"
				(at 15.24 7.62 0)
				(effects
					(font
						(size 1.27 1.27)
					)
					(hide yes)
				)
			)
			(property "Description" "NVIDIA Jetson Orin NX/Nano module female socket, 260-pin SODIMM 9.2mm stack height, with all Alternate Pin Functions from Datasheet"
				(at 0 0 0)
				(effects
					(font
						(size 1.27 1.27)
					)
					(hide yes)
				)
			)
			(property "Manufacturer" "TE"
				(at 24.13 1.27 0)
				(effects
					(font
						(size 1.27 1.27)
					)
				)
			)
			(property "MPN" "2309413-1"
				(at 31.75 1.27 0)
				(effects
					(font
						(size 1.27 1.27)
					)
				)
			)
			(property "License" "MIT"
				(at 34.29 3.81 0)
				(effects
					(font
						(size 1.27 1.27)
					)
					(hide yes)
				)
			)
			(property "ki_locked" ""
				(at 0 0 0)
				(effects
					(font
						(size 1.27 1.27)
					)
				)
			)
			(property "ki_keywords" "nvidia jetson orin nx nano som"
				(at 0 0 0)
				(effects
					(font
						(size 1.27 1.27)
					)
					(hide yes)
				)
			)
			(symbol "Jetson-Orin-9.2H-socket_1_1"
				(rectangle
					(start 0 -132.08)
					(end 40.64 0)
					(stroke
						(width 0.254)
						(type default)
					)
					(fill
						(type background)
					)
				)
				(polyline
					(pts
						(xy 8.255 -4.445) (xy 8.255 -28.575)
					)
					(stroke
						(width 0)
						(type default)
					)
					(fill
						(type none)
					)
				)
				(arc
					(start 7.62 -29.21)
					(mid 8.069 -29.024)
					(end 8.255 -28.575)
					(stroke
						(width 0)
						(type default)
					)
					(fill
						(type none)
					)
				)
				(arc
					(start 8.255 -4.445)
					(mid 8.069 -3.996)
					(end 7.62 -3.81)
					(stroke
						(width 0)
						(type default)
					)
					(fill
						(type none)
					)
				)
				(text "1.8V Bidir "
					(at 22.86 -7.62 0)
					(effects
						(font
							(size 0.762 0.762)
						)
						(justify right)
					)
				)
				(text "1.8V Bidir "
					(at 27.305 -10.16 0)
					(effects
						(font
							(size 0.762 0.762)
						)
						(justify right)
					)
				)
				(text "1.8V CMOS Output"
					(at 27.305 -27.94 0)
					(effects
						(font
							(size 0.762 0.762)
						)
						(justify right)
					)
				)
				(text "1.8V-5.5V Input"
					(at 11.43 -43.18 0)
					(effects
						(font
							(size 0.762 0.762)
						)
						(justify left)
					)
				)
				(text "100k PU to 1.8V Input "
					(at 26.67 -25.4 0)
					(effects
						(font
							(size 0.762 0.762)
						)
						(justify right)
					)
				)
				(text "1k PU to 1.8V Output "
					(at 26.67 -33.02 0)
					(effects
						(font
							(size 0.762 0.762)
						)
						(justify right)
					)
				)
				(text "5.0V to 20V"
					(at 9.525 -16.51 900)
					(effects
						(font
							(size 1.27 1.27)
						)
					)
				)
				(text "5V w/ PD Analog Input"
					(at 29.21 -17.78 0)
					(effects
						(font
							(size 0.762 0.762)
						)
						(justify right)
					)
				)
				(text "Floating"
					(at 22.86 -2.54 0)
					(effects
						(font
							(size 0.762 0.762)
						)
						(justify right)
					)
				)
				(text "PU to 1.8V Bidir "
					(at 28.575 -20.32 0)
					(effects
						(font
							(size 0.762 0.762)
						)
						(justify right)
					)
				)
				(text "PU to 1.8V Input"
					(at 21.59 -38.1 0)
					(effects
						(font
							(size 0.762 0.762)
						)
						(justify right)
					)
				)
				(text "PU to VDD_IN Output"
					(at 23.495 -15.24 0)
					(effects
						(font
							(size 0.762 0.762)
						)
						(justify right)
					)
				)
				(pin passive line
					(at -5.08 -48.26 0)
					(length 5.08)
					(name "GND"
						(effects
							(font
								(size 1.27 1.27)
							)
						)
					)
					(number "1"
						(effects
							(font
								(size 1.27 1.27)
							)
						)
					)
				)
				(pin passive line
					(at -5.08 -124.46 0)
					(length 5.08)
					(name "GND"
						(effects
							(font
								(size 1.27 1.27)
							)
						)
					)
					(number "102"
						(effects
							(font
								(size 1.27 1.27)
							)
						)
					)
				)
				(pin passive line
					(at -5.08 -127 0)
					(length 5.08)
					(name "GND"
						(effects
							(font
								(size 1.27 1.27)
							)
						)
					)
					(number "107"
						(effects
							(font
								(size 1.27 1.27)
							)
						)
					)
				)
				(pin passive line
					(at -5.08 -129.54 0)
					(length 5.08)
					(name "GND"
						(effects
							(font
								(size 1.27 1.27)
							)
						)
					)
					(number "113"
						(effects
							(font
								(size 1.27 1.27)
							)
						)
					)
				)
				(pin passive line
					(at 45.72 -116.84 180)
					(length 5.08)
					(name "GND"
						(effects
							(font
								(size 1.27 1.27)
							)
						)
					)
					(number "119"
						(effects
							(font
								(size 1.27 1.27)
							)
						)
					)
				)
				(pin passive line
					(at 45.72 -119.38 180)
					(length 5.08)
					(name "GND"
						(effects
							(font
								(size 1.27 1.27)
							)
						)
					)
					(number "125"
						(effects
							(font
								(size 1.27 1.27)
							)
						)
					)
				)
				(pin passive line
					(at 45.72 -121.92 180)
					(length 5.08)
					(name "GND"
						(effects
							(font
								(size 1.27 1.27)
							)
						)
					)
					(number "129"
						(effects
							(font
								(size 1.27 1.27)
							)
						)
					)
				)
				(pin passive line
					(at -5.08 -58.42 0)
					(length 5.08)
					(name "GND"
						(effects
							(font
								(size 1.27 1.27)
							)
						)
					)
					(number "13"
						(effects
							(font
								(size 1.27 1.27)
							)
						)
					)
				)
				(pin passive line
					(at 45.72 -124.46 180)
					(length 5.08)
					(name "GND"
						(effects
							(font
								(size 1.27 1.27)
							)
						)
					)
					(number "132"
						(effects
							(font
								(size 1.27 1.27)
							)
						)
					)
				)
				(pin passive line
					(at 45.72 -127 180)
					(length 5.08)
					(name "GND"
						(effects
							(font
								(size 1.27 1.27)
							)
						)
					)
					(number "135"
						(effects
							(font
								(size 1.27 1.27)
							)
						)
					)
				)
				(pin passive line
					(at 45.72 -48.26 180)
					(length 5.08)
					(name "GND"
						(effects
							(font
								(size 1.27 1.27)
							)
						)
					)
					(number "138"
						(effects
							(font
								(size 1.27 1.27)
							)
						)
					)
				)
				(pin passive line
					(at -5.08 -60.96 0)
					(length 5.08)
					(name "GND"
						(effects
							(font
								(size 1.27 1.27)
							)
						)
					)
					(number "14"
						(effects
							(font
								(size 1.27 1.27)
							)
						)
					)
				)
				(pin passive line
					(at 45.72 -50.8 180)
					(length 5.08)
					(name "GND"
						(effects
							(font
								(size 1.27 1.27)
							)
						)
					)
					(number "141"
						(effects
							(font
								(size 1.27 1.27)
							)
						)
					)
				)
				(pin passive line
					(at 45.72 -53.34 180)
					(length 5.08)
					(name "GND"
						(effects
							(font
								(size 1.27 1.27)
							)
						)
					)
					(number "144"
						(effects
							(font
								(size 1.27 1.27)
							)
						)
					)
				)
				(pin passive line
					(at 45.72 -55.88 180)
					(length 5.08)
					(name "GND"
						(effects
							(font
								(size 1.27 1.27)
							)
						)
					)
					(number "146"
						(effects
							(font
								(size 1.27 1.27)
							)
						)
					)
				)
				(pin passive line
					(at 45.72 -58.42 180)
					(length 5.08)
					(name "GND"
						(effects
							(font
								(size 1.27 1.27)
							)
						)
					)
					(number "147"
						(effects
							(font
								(size 1.27 1.27)
							)
						)
					)
				)
				(pin passive line
					(at 45.72 -60.96 180)
					(length 5.08)
					(name "GND"
						(effects
							(font
								(size 1.27 1.27)
							)
						)
					)
					(number "152"
						(effects
							(font
								(size 1.27 1.27)
							)
						)
					)
				)
				(pin passive line
					(at 45.72 -63.5 180)
					(length 5.08)
					(name "GND"
						(effects
							(font
								(size 1.27 1.27)
							)
						)
					)
					(number "153"
						(effects
							(font
								(size 1.27 1.27)
							)
						)
					)
				)
				(pin passive line
					(at 45.72 -66.04 180)
					(length 5.08)
					(name "GND"
						(effects
							(font
								(size 1.27 1.27)
							)
						)
					)
					(number "158"
						(effects
							(font
								(size 1.27 1.27)
							)
						)
					)
				)
				(pin passive line
					(at 45.72 -68.58 180)
					(length 5.08)
					(name "GND"
						(effects
							(font
								(size 1.27 1.27)
							)
						)
					)
					(number "159"
						(effects
							(font
								(size 1.27 1.27)
							)
						)
					)
				)
				(pin passive line
					(at 45.72 -71.12 180)
					(length 5.08)
					(name "GND"
						(effects
							(font
								(size 1.27 1.27)
							)
						)
					)
					(number "164"
						(effects
							(font
								(size 1.27 1.27)
							)
						)
					)
				)
				(pin passive line
					(at 45.72 -73.66 180)
					(length 5.08)
					(name "GND"
						(effects
							(font
								(size 1.27 1.27)
							)
						)
					)
					(number "165"
						(effects
							(font
								(size 1.27 1.27)
							)
						)
					)
				)
				(pin passive line
					(at 45.72 -76.2 180)
					(length 5.08)
					(name "GND"
						(effects
							(font
								(size 1.27 1.27)
							)
						)
					)
					(number "170"
						(effects
							(font
								(size 1.27 1.27)
							)
						)
					)
				)
				(pin passive line
					(at 45.72 -78.74 180)
					(length 5.08)
					(name "GND"
						(effects
							(font
								(size 1.27 1.27)
							)
						)
					)
					(number "171"
						(effects
							(font
								(size 1.27 1.27)
							)
						)
					)
				)
				(pin passive line
					(at 45.72 -81.28 180)
					(length 5.08)
					(name "GND"
						(effects
							(font
								(size 1.27 1.27)
							)
						)
					)
					(number "176"
						(effects
							(font
								(size 1.27 1.27)
							)
						)
					)
				)
				(pin passive line
					(at 45.72 -83.82 180)
					(length 5.08)
					(name "GND"
						(effects
							(font
								(size 1.27 1.27)
							)
						)
					)
					(number "177"
						(effects
							(font
								(size 1.27 1.27)
							)
						)
					)
				)
				(pin passive line
					(at 45.72 -27.94 180)
					(length 5.08)
					(name "MOD_SLEEP*"
						(effects
							(font
								(size 1.27 1.27)
							)
						)
					)
					(number "178"
						(effects
							(font
								(size 1.27 1.27)
							)
						)
					)
				)
				(pin passive line
					(at -5.08 -63.5 0)
					(length 5.08)
					(name "GND"
						(effects
							(font
								(size 1.27 1.27)
							)
						)
					)
					(number "19"
						(effects
							(font
								(size 1.27 1.27)
							)
						)
					)
				)
				(pin passive line
					(at -5.08 -50.8 0)
					(length 5.08)
					(name "GND"
						(effects
							(font
								(size 1.27 1.27)
							)
						)
					)
					(number "2"
						(effects
							(font
								(size 1.27 1.27)
							)
						)
					)
				)
				(pin passive line
					(at -5.08 -66.04 0)
					(length 5.08)
					(name "GND"
						(effects
							(font
								(size 1.27 1.27)
							)
						)
					)
					(number "20"
						(effects
							(font
								(size 1.27 1.27)
							)
						)
					)
				)
				(pin passive line
					(at 45.72 -86.36 180)
					(length 5.08)
					(name "GND"
						(effects
							(font
								(size 1.27 1.27)
							)
						)
					)
					(number "200"
						(effects
							(font
								(size 1.27 1.27)
							)
						)
					)
				)
				(pin passive line
					(at 45.72 -88.9 180)
					(length 5.08)
					(name "GND"
						(effects
							(font
								(size 1.27 1.27)
							)
						)
					)
					(number "201"
						(effects
							(font
								(size 1.27 1.27)
							)
						)
					)
				)
				(pin passive line
					(at 45.72 -7.62 180)
					(length 5.08)
					(name "Fan_Tach/GPIO08"
						(effects
							(font
								(size 1.27 1.27)
							)
						)
					)
					(number "208"
						(effects
							(font
								(size 1.27 1.27)
							)
						)
					)
					(alternate "GPIO08" passive line)
					(alternate "GPIO08(Fan_Tach)" passive line)
				)
				(pin passive line
					(at 45.72 -33.02 180)
					(length 5.08)
					(name "CLK_32K_OUT"
						(effects
							(font
								(size 1.27 1.27)
							)
						)
					)
					(number "210"
						(effects
							(font
								(size 1.27 1.27)
							)
						)
					)
				)
				(pin passive line
					(at 45.72 -38.1 180)
					(length 5.08)
					(name "FORCE_RECOVERY*"
						(effects
							(font
								(size 1.27 1.27)
							)
						)
					)
					(number "214"
						(effects
							(font
								(size 1.27 1.27)
							)
						)
					)
				)
				(pin passive line
					(at 45.72 -2.54 180)
					(length 5.08)
					(name "GND(MODULE_ID)"
						(effects
							(font
								(size 1.27 1.27)
							)
						)
					)
					(number "217"
						(effects
							(font
								(size 1.27 1.27)
							)
						)
					)
				)
				(pin passive line
					(at 45.72 -10.16 180)
					(length 5.08)
					(name "GPIO14/PWM"
						(effects
							(font
								(size 1.27 1.27)
							)
						)
					)
					(number "230"
						(effects
							(font
								(size 1.27 1.27)
							)
						)
					)
					(alternate "GPIO14" passive line)
					(alternate "GPIO14(PWM)" passive line)
				)
				(pin passive line
					(at 45.72 -91.44 180)
					(length 5.08)
					(name "GND"
						(effects
							(font
								(size 1.27 1.27)
							)
						)
					)
					(number "231"
						(effects
							(font
								(size 1.27 1.27)
							)
						)
					)
				)
				(pin passive line
					(at 45.72 -15.24 180)
					(length 5.08)
					(name "SHUTDOWN_REQ*"
						(effects
							(font
								(size 1.27 1.27)
							)
						)
					)
					(number "233"
						(effects
							(font
								(size 1.27 1.27)
							)
						)
					)
				)
				(pin passive line
					(at -5.08 -43.18 0)
					(length 5.08)
					(name "PMIC_BBAT"
						(effects
							(font
								(size 1.27 1.27)
							)
						)
					)
					(number "235"
						(effects
							(font
								(size 1.27 1.27)
							)
						)
					)
				)
				(pin passive line
					(at 45.72 -17.78 180)
					(length 5.08)
					(name "POWER_EN"
						(effects
							(font
								(size 1.27 1.27)
							)
						)
					)
					(number "237"
						(effects
							(font
								(size 1.27 1.27)
							)
						)
					)
				)
				(pin passive line
					(at 45.72 -20.32 180)
					(length 5.08)
					(name "SYS_RESET*"
						(effects
							(font
								(size 1.27 1.27)
							)
						)
					)
					(number "239"
						(effects
							(font
								(size 1.27 1.27)
							)
						)
					)
				)
				(pin passive line
					(at 45.72 -25.4 180)
					(length 5.08)
					(name "SLEEP/WAKE*"
						(effects
							(font
								(size 1.27 1.27)
							)
						)
					)
					(number "240"
						(effects
							(font
								(size 1.27 1.27)
							)
						)
					)
				)
				(pin passive line
					(at 45.72 -93.98 180)
					(length 5.08)
					(name "GND"
						(effects
							(font
								(size 1.27 1.27)
							)
						)
					)
					(number "241"
						(effects
							(font
								(size 1.27 1.27)
							)
						)
					)
				)
				(pin passive line
					(at 45.72 -96.52 180)
					(length 5.08)
					(name "GND"
						(effects
							(font
								(size 1.27 1.27)
							)
						)
					)
					(number "242"
						(effects
							(font
								(size 1.27 1.27)
							)
						)
					)
				)
				(pin passive line
					(at 45.72 -99.06 180)
					(length 5.08)
					(name "GND"
						(effects
							(font
								(size 1.27 1.27)
							)
						)
					)
					(number "243"
						(effects
							(font
								(size 1.27 1.27)
							)
						)
					)
				)
				(pin passive line
					(at 45.72 -101.6 180)
					(length 5.08)
					(name "GND"
						(effects
							(font
								(size 1.27 1.27)
							)
						)
					)
					(number "244"
						(effects
							(font
								(size 1.27 1.27)
							)
						)
					)
				)
				(pin passive line
					(at 45.72 -104.14 180)
					(length 5.08)
					(name "GND"
						(effects
							(font
								(size 1.27 1.27)
							)
						)
					)
					(number "245"
						(effects
							(font
								(size 1.27 1.27)
							)
						)
					)
				)
				(pin passive line
					(at 45.72 -106.68 180)
					(length 5.08)
					(name "GND"
						(effects
							(font
								(size 1.27 1.27)
							)
						)
					)
					(number "246"
						(effects
							(font
								(size 1.27 1.27)
							)
						)
					)
				)
				(pin passive line
					(at 45.72 -109.22 180)
					(length 5.08)
					(name "GND"
						(effects
							(font
								(size 1.27 1.27)
							)
						)
					)
					(number "247"
						(effects
							(font
								(size 1.27 1.27)
							)
						)
					)
				)
				(pin passive line
					(at 45.72 -111.76 180)
					(length 5.08)
					(name "GND"
						(effects
							(font
								(size 1.27 1.27)
							)
						)
					)
					(number "248"
						(effects
							(font
								(size 1.27 1.27)
							)
						)
					)
				)
				(pin passive line
					(at 45.72 -114.3 180)
					(length 5.08)
					(name "GND"
						(effects
							(font
								(size 1.27 1.27)
							)
						)
					)
					(number "249"
						(effects
							(font
								(size 1.27 1.27)
							)
						)
					)
				)
				(pin passive line
					(at -5.08 -68.58 0)
					(length 5.08)
					(name "GND"
						(effects
							(font
								(size 1.27 1.27)
							)
						)
					)
					(number "25"
						(effects
							(font
								(size 1.27 1.27)
							)
						)
					)
				)
				(pin passive line
					(at 45.72 -129.54 180)
					(length 5.08)
					(name "GND"
						(effects
							(font
								(size 1.27 1.27)
							)
						)
					)
					(number "250"
						(effects
							(font
								(size 1.27 1.27)
							)
						)
					)
				)
				(pin passive line
					(at -5.08 -5.08 0)
					(length 5.08)
					(name "VDD_IN"
						(effects
							(font
								(size 1.27 1.27)
							)
						)
					)
					(number "251"
						(effects
							(font
								(size 1.27 1.27)
							)
						)
					)
				)
				(pin passive line
					(at -5.08 -7.62 0)
					(length 5.08)
					(name "VDD_IN"
						(effects
							(font
								(size 1.27 1.27)
							)
						)
					)
					(number "252"
						(effects
							(font
								(size 1.27 1.27)
							)
						)
					)
				)
				(pin passive line
					(at -5.08 -10.16 0)
					(length 5.08)
					(name "VDD_IN"
						(effects
							(font
								(size 1.27 1.27)
							)
						)
					)
					(number "253"
						(effects
							(font
								(size 1.27 1.27)
							)
						)
					)
				)
				(pin passive line
					(at -5.08 -12.7 0)
					(length 5.08)
					(name "VDD_IN"
						(effects
							(font
								(size 1.27 1.27)
							)
						)
					)
					(number "254"
						(effects
							(font
								(size 1.27 1.27)
							)
						)
					)
				)
				(pin passive line
					(at -5.08 -15.24 0)
					(length 5.08)
					(name "VDD_IN"
						(effects
							(font
								(size 1.27 1.27)
							)
						)
					)
					(number "255"
						(effects
							(font
								(size 1.27 1.27)
							)
						)
					)
				)
				(pin passive line
					(at -5.08 -17.78 0)
					(length 5.08)
					(name "VDD_IN"
						(effects
							(font
								(size 1.27 1.27)
							)
						)
					)
					(number "256"
						(effects
							(font
								(size 1.27 1.27)
							)
						)
					)
				)
				(pin passive line
					(at -5.08 -20.32 0)
					(length 5.08)
					(name "VDD_IN"
						(effects
							(font
								(size 1.27 1.27)
							)
						)
					)
					(number "257"
						(effects
							(font
								(size 1.27 1.27)
							)
						)
					)
				)
				(pin passive line
					(at -5.08 -22.86 0)
					(length 5.08)
					(name "VDD_IN"
						(effects
							(font
								(size 1.27 1.27)
							)
						)
					)
					(number "258"
						(effects
							(font
								(size 1.27 1.27)
							)
						)
					)
				)
				(pin passive line
					(at -5.08 -25.4 0)
					(length 5.08)
					(name "VDD_IN"
						(effects
							(font
								(size 1.27 1.27)
							)
						)
					)
					(number "259"
						(effects
							(font
								(size 1.27 1.27)
							)
						)
					)
				)
				(pin passive line
					(at -5.08 -71.12 0)
					(length 5.08)
					(name "GND"
						(effects
							(font
								(size 1.27 1.27)
							)
						)
					)
					(number "26"
						(effects
							(font
								(size 1.27 1.27)
							)
						)
					)
				)
				(pin passive line
					(at -5.08 -27.94 0)
					(length 5.08)
					(name "VDD_IN"
						(effects
							(font
								(size 1.27 1.27)
							)
						)
					)
					(number "260"
						(effects
							(font
								(size 1.27 1.27)
							)
						)
					)
				)
				(pin no_connect line
					(at 45.72 -45.72 180)
					(length 5.08)
					(name "MP"
						(effects
							(font
								(size 1.27 1.27)
							)
						)
					)
					(number "261"
						(effects
							(font
								(size 1.27 1.27)
							)
						)
					)
				)
				(pin no_connect line
					(at 45.72 -43.18 180)
					(length 5.08)
					(name "MP"
						(effects
							(font
								(size 1.27 1.27)
							)
						)
					)
					(number "262"
						(effects
							(font
								(size 1.27 1.27)
							)
						)
					)
				)
				(pin passive line
					(at -5.08 -73.66 0)
					(length 5.08)
					(name "GND"
						(effects
							(font
								(size 1.27 1.27)
							)
						)
					)
					(number "31"
						(effects
							(font
								(size 1.27 1.27)
							)
						)
					)
				)
				(pin passive line
					(at -5.08 -76.2 0)
					(length 5.08)
					(name "GND"
						(effects
							(font
								(size 1.27 1.27)
							)
						)
					)
					(number "32"
						(effects
							(font
								(size 1.27 1.27)
							)
						)
					)
				)
				(pin passive line
					(at -5.08 -78.74 0)
					(length 5.08)
					(name "GND"
						(effects
							(font
								(size 1.27 1.27)
							)
						)
					)
					(number "37"
						(effects
							(font
								(size 1.27 1.27)
							)
						)
					)
				)
				(pin passive line
					(at -5.08 -81.28 0)
					(length 5.08)
					(name "GND"
						(effects
							(font
								(size 1.27 1.27)
							)
						)
					)
					(number "38"
						(effects
							(font
								(size 1.27 1.27)
							)
						)
					)
				)
				(pin passive line
					(at -5.08 -83.82 0)
					(length 5.08)
					(name "GND"
						(effects
							(font
								(size 1.27 1.27)
							)
						)
					)
					(number "43"
						(effects
							(font
								(size 1.27 1.27)
							)
						)
					)
				)
				(pin passive line
					(at -5.08 -86.36 0)
					(length 5.08)
					(name "GND"
						(effects
							(font
								(size 1.27 1.27)
							)
						)
					)
					(number "44"
						(effects
							(font
								(size 1.27 1.27)
							)
						)
					)
				)
				(pin passive line
					(at -5.08 -88.9 0)
					(length 5.08)
					(name "GND"
						(effects
							(font
								(size 1.27 1.27)
							)
						)
					)
					(number "49"
						(effects
							(font
								(size 1.27 1.27)
							)
						)
					)
				)
				(pin passive line
					(at -5.08 -91.44 0)
					(length 5.08)
					(name "GND"
						(effects
							(font
								(size 1.27 1.27)
							)
						)
					)
					(number "50"
						(effects
							(font
								(size 1.27 1.27)
							)
						)
					)
				)
				(pin passive line
					(at -5.08 -93.98 0)
					(length 5.08)
					(name "GND"
						(effects
							(font
								(size 1.27 1.27)
							)
						)
					)
					(number "55"
						(effects
							(font
								(size 1.27 1.27)
							)
						)
					)
				)
				(pin passive line
					(at -5.08 -96.52 0)
					(length 5.08)
					(name "GND"
						(effects
							(font
								(size 1.27 1.27)
							)
						)
					)
					(number "56"
						(effects
							(font
								(size 1.27 1.27)
							)
						)
					)
				)
				(pin passive line
					(at -5.08 -99.06 0)
					(length 5.08)
					(name "GND"
						(effects
							(font
								(size 1.27 1.27)
							)
						)
					)
					(number "61"
						(effects
							(font
								(size 1.27 1.27)
							)
						)
					)
				)
				(pin passive line
					(at -5.08 -101.6 0)
					(length 5.08)
					(name "GND"
						(effects
							(font
								(size 1.27 1.27)
							)
						)
					)
					(number "62"
						(effects
							(font
								(size 1.27 1.27)
							)
						)
					)
				)
				(pin passive line
					(at -5.08 -104.14 0)
					(length 5.08)
					(name "GND"
						(effects
							(font
								(size 1.27 1.27)
							)
						)
					)
					(number "67"
						(effects
							(font
								(size 1.27 1.27)
							)
						)
					)
				)
				(pin passive line
					(at -5.08 -106.68 0)
					(length 5.08)
					(name "GND"
						(effects
							(font
								(size 1.27 1.27)
							)
						)
					)
					(number "68"
						(effects
							(font
								(size 1.27 1.27)
							)
						)
					)
				)
				(pin passive line
					(at -5.08 -53.34 0)
					(length 5.08)
					(name "GND"
						(effects
							(font
								(size 1.27 1.27)
							)
						)
					)
					(number "7"
						(effects
							(font
								(size 1.27 1.27)
							)
						)
					)
				)
				(pin passive line
					(at -5.08 -109.22 0)
					(length 5.08)
					(name "GND"
						(effects
							(font
								(size 1.27 1.27)
							)
						)
					)
					(number "73"
						(effects
							(font
								(size 1.27 1.27)
							)
						)
					)
				)
				(pin passive line
					(at -5.08 -111.76 0)
					(length 5.08)
					(name "GND"
						(effects
							(font
								(size 1.27 1.27)
							)
						)
					)
					(number "74"
						(effects
							(font
								(size 1.27 1.27)
							)
						)
					)
				)
				(pin passive line
					(at -5.08 -114.3 0)
					(length 5.08)
					(name "GND"
						(effects
							(font
								(size 1.27 1.27)
							)
						)
					)
					(number "79"
						(effects
							(font
								(size 1.27 1.27)
							)
						)
					)
				)
				(pin passive line
					(at -5.08 -55.88 0)
					(length 5.08)
					(name "GND"
						(effects
							(font
								(size 1.27 1.27)
							)
						)
					)
					(number "8"
						(effects
							(font
								(size 1.27 1.27)
							)
						)
					)
				)
				(pin passive line
					(at -5.08 -116.84 0)
					(length 5.08)
					(name "GND"
						(effects
							(font
								(size 1.27 1.27)
							)
						)
					)
					(number "80"
						(effects
							(font
								(size 1.27 1.27)
							)
						)
					)
				)
				(pin passive line
					(at -5.08 -119.38 0)
					(length 5.08)
					(name "GND"
						(effects
							(font
								(size 1.27 1.27)
							)
						)
					)
					(number "85"
						(effects
							(font
								(size 1.27 1.27)
							)
						)
					)
				)
				(pin passive line
					(at -5.08 -121.92 0)
					(length 5.08)
					(name "GND"
						(effects
							(font
								(size 1.27 1.27)
							)
						)
					)
					(number "86"
						(effects
							(font
								(size 1.27 1.27)
							)
						)
					)
				)
			)
			(symbol "Jetson-Orin-9.2H-socket_2_1"
				(polyline
					(pts
						(xy 0 -93.98) (xy 31.75 -93.98)
					)
					(stroke
						(width 0)
						(type default)
					)
					(fill
						(type none)
					)
				)
				(polyline
					(pts
						(xy 14.605 -88.265) (xy 14.605 -92.075)
					)
					(stroke
						(width 0)
						(type default)
					)
					(fill
						(type none)
					)
				)
				(polyline
					(pts
						(xy 14.605 -75.565) (xy 14.605 -84.455)
					)
					(stroke
						(width 0)
						(type default)
					)
					(fill
						(type none)
					)
				)
				(polyline
					(pts
						(xy 14.605 -4.445) (xy 14.605 -71.755)
					)
					(stroke
						(width 0)
						(type default)
					)
					(fill
						(type none)
					)
				)
				(rectangle
					(start 0 0)
					(end 31.75 -114.3)
					(stroke
						(width 0.254)
						(type default)
					)
					(fill
						(type background)
					)
				)
				(arc
					(start 13.97 -92.71)
					(mid 14.4198 -92.5248)
					(end 14.605 -92.075)
					(stroke
						(width 0)
						(type default)
					)
					(fill
						(type none)
					)
				)
				(arc
					(start 13.97 -85.09)
					(mid 14.4198 -84.9048)
					(end 14.605 -84.455)
					(stroke
						(width 0)
						(type default)
					)
					(fill
						(type none)
					)
				)
				(arc
					(start 13.97 -72.39)
					(mid 14.4198 -72.2048)
					(end 14.605 -71.755)
					(stroke
						(width 0)
						(type default)
					)
					(fill
						(type none)
					)
				)
				(arc
					(start 14.605 -88.265)
					(mid 14.419 -87.816)
					(end 13.97 -87.63)
					(stroke
						(width 0)
						(type default)
					)
					(fill
						(type none)
					)
				)
				(arc
					(start 14.605 -75.565)
					(mid 14.419 -75.116)
					(end 13.97 -74.93)
					(stroke
						(width 0)
						(type default)
					)
					(fill
						(type none)
					)
				)
				(arc
					(start 14.605 -4.445)
					(mid 14.419 -3.996)
					(end 13.97 -3.81)
					(stroke
						(width 0)
						(type default)
					)
					(fill
						(type none)
					)
				)
				(text "1.8V Bidir"
					(at 15.24 -80.01 0)
					(effects
						(font
							(size 1.27 1.27)
						)
						(justify left)
					)
				)
				(text "3.3V PU Bidir"
					(at 15.24 -90.17 0)
					(effects
						(font
							(size 1.27 1.27)
						)
						(justify left)
					)
				)
				(text "MIPI Input"
					(at 15.24 -38.1 0)
					(effects
						(font
							(size 1.27 1.27)
						)
						(justify left)
					)
				)
				(text "RSVD"
					(at 26.67 -95.25 0)
					(effects
						(font
							(size 1.27 1.27)
							(bold yes)
						)
					)
				)
				(pin passive line
					(at -5.08 -5.08 0)
					(length 5.08)
					(name "CSI0_CLK_N"
						(effects
							(font
								(size 1.27 1.27)
							)
						)
					)
					(number "10"
						(effects
							(font
								(size 1.27 1.27)
							)
						)
					)
				)
				(pin passive line
					(at -5.08 -25.4 0)
					(length 5.08)
					(name "CSI1_CLK_P"
						(effects
							(font
								(size 1.27 1.27)
							)
						)
					)
					(number "11"
						(effects
							(font
								(size 1.27 1.27)
							)
						)
					)
				)
				(pin passive line
					(at -5.08 -83.82 0)
					(length 5.08)
					(name "CAM0_PWDN"
						(effects
							(font
								(size 1.27 1.27)
							)
						)
					)
					(number "114"
						(effects
							(font
								(size 1.27 1.27)
							)
						)
					)
				)
				(pin passive line
					(at -5.08 -81.28 0)
					(length 5.08)
					(name "CAM0_MCLK"
						(effects
							(font
								(size 1.27 1.27)
							)
						)
					)
					(number "116"
						(effects
							(font
								(size 1.27 1.27)
							)
						)
					)
				)
				(pin passive line
					(at -5.08 -7.62 0)
					(length 5.08)
					(name "CSI0_CLK_P"
						(effects
							(font
								(size 1.27 1.27)
							)
						)
					)
					(number "12"
						(effects
							(font
								(size 1.27 1.27)
							)
						)
					)
				)
				(pin passive line
					(at -5.08 -78.74 0)
					(length 5.08)
					(name "CAM1_PWDN"
						(effects
							(font
								(size 1.27 1.27)
							)
						)
					)
					(number "120"
						(effects
							(font
								(size 1.27 1.27)
							)
						)
					)
				)
				(pin passive line
					(at -5.08 -76.2 0)
					(length 5.08)
					(name "CAM1_MCLK"
						(effects
							(font
								(size 1.27 1.27)
							)
						)
					)
					(number "122"
						(effects
							(font
								(size 1.27 1.27)
							)
						)
					)
				)
				(pin passive line
					(at -5.08 -33.02 0)
					(length 5.08)
					(name "CSI1_D1_N"
						(effects
							(font
								(size 1.27 1.27)
							)
						)
					)
					(number "15"
						(effects
							(font
								(size 1.27 1.27)
							)
						)
					)
				)
				(pin passive line
					(at -5.08 -15.24 0)
					(length 5.08)
					(name "CSI0_D1_N"
						(effects
							(font
								(size 1.27 1.27)
							)
						)
					)
					(number "16"
						(effects
							(font
								(size 1.27 1.27)
							)
						)
					)
				)
				(pin passive line
					(at -5.08 -35.56 0)
					(length 5.08)
					(name "CSI1_D1_P"
						(effects
							(font
								(size 1.27 1.27)
							)
						)
					)
					(number "17"
						(effects
							(font
								(size 1.27 1.27)
							)
						)
					)
				)
				(pin passive line
					(at -5.08 -17.78 0)
					(length 5.08)
					(name "CSI0_D1_P"
						(effects
							(font
								(size 1.27 1.27)
							)
						)
					)
					(number "18"
						(effects
							(font
								(size 1.27 1.27)
							)
						)
					)
				)
				(pin passive line
					(at -5.08 -63.5 0)
					(length 5.08)
					(name "CSI3_D0_N"
						(effects
							(font
								(size 1.27 1.27)
							)
						)
					)
					(number "21"
						(effects
							(font
								(size 1.27 1.27)
							)
						)
					)
				)
				(pin passive line
					(at -5.08 -88.9 0)
					(length 5.08)
					(name "CAM_I2C_SCL"
						(effects
							(font
								(size 1.27 1.27)
							)
						)
					)
					(number "213"
						(effects
							(font
								(size 1.27 1.27)
							)
						)
					)
				)
				(pin passive line
					(at -5.08 -91.44 0)
					(length 5.08)
					(name "CAM_I2C_SDA"
						(effects
							(font
								(size 1.27 1.27)
							)
						)
					)
					(number "215"
						(effects
							(font
								(size 1.27 1.27)
							)
						)
					)
				)
				(pin passive line
					(at -5.08 -45.72 0)
					(length 5.08)
					(name "CSI2_D0_N"
						(effects
							(font
								(size 1.27 1.27)
							)
						)
					)
					(number "22"
						(effects
							(font
								(size 1.27 1.27)
							)
						)
					)
				)
				(pin passive line
					(at -5.08 -66.04 0)
					(length 5.08)
					(name "CSI3_D0_P"
						(effects
							(font
								(size 1.27 1.27)
							)
						)
					)
					(number "23"
						(effects
							(font
								(size 1.27 1.27)
							)
						)
					)
				)
				(pin passive line
					(at -5.08 -48.26 0)
					(length 5.08)
					(name "CSI2_D0_P"
						(effects
							(font
								(size 1.27 1.27)
							)
						)
					)
					(number "24"
						(effects
							(font
								(size 1.27 1.27)
							)
						)
					)
				)
				(pin passive line
					(at -5.08 -58.42 0)
					(length 5.08)
					(name "CSI3_CLK_N"
						(effects
							(font
								(size 1.27 1.27)
							)
						)
					)
					(number "27"
						(effects
							(font
								(size 1.27 1.27)
							)
						)
					)
				)
				(pin passive line
					(at -5.08 -40.64 0)
					(length 5.08)
					(name "CSI2_CLK_N"
						(effects
							(font
								(size 1.27 1.27)
							)
						)
					)
					(number "28"
						(effects
							(font
								(size 1.27 1.27)
							)
						)
					)
				)
				(pin passive line
					(at -5.08 -60.96 0)
					(length 5.08)
					(name "CSI3_CLK_P"
						(effects
							(font
								(size 1.27 1.27)
							)
						)
					)
					(number "29"
						(effects
							(font
								(size 1.27 1.27)
							)
						)
					)
				)
				(pin passive line
					(at -5.08 -27.94 0)
					(length 5.08)
					(name "CSI1_D0_N"
						(effects
							(font
								(size 1.27 1.27)
							)
						)
					)
					(number "3"
						(effects
							(font
								(size 1.27 1.27)
							)
						)
					)
				)
				(pin passive line
					(at -5.08 -43.18 0)
					(length 5.08)
					(name "CSI2_CLK_P"
						(effects
							(font
								(size 1.27 1.27)
							)
						)
					)
					(number "30"
						(effects
							(font
								(size 1.27 1.27)
							)
						)
					)
				)
				(pin passive line
					(at -5.08 -68.58 0)
					(length 5.08)
					(name "CSI3_D1_N"
						(effects
							(font
								(size 1.27 1.27)
							)
						)
					)
					(number "33"
						(effects
							(font
								(size 1.27 1.27)
							)
						)
					)
				)
				(pin passive line
					(at -5.08 -50.8 0)
					(length 5.08)
					(name "CSI2_D1_N"
						(effects
							(font
								(size 1.27 1.27)
							)
						)
					)
					(number "34"
						(effects
							(font
								(size 1.27 1.27)
							)
						)
					)
				)
				(pin passive line
					(at -5.08 -71.12 0)
					(length 5.08)
					(name "CSI3_D1_P"
						(effects
							(font
								(size 1.27 1.27)
							)
						)
					)
					(number "35"
						(effects
							(font
								(size 1.27 1.27)
							)
						)
					)
				)
				(pin passive line
					(at -5.08 -53.34 0)
					(length 5.08)
					(name "CSI2_D1_P"
						(effects
							(font
								(size 1.27 1.27)
							)
						)
					)
					(number "36"
						(effects
							(font
								(size 1.27 1.27)
							)
						)
					)
				)
				(pin passive line
					(at -5.08 -10.16 0)
					(length 5.08)
					(name "CSI0_D0_N"
						(effects
							(font
								(size 1.27 1.27)
							)
						)
					)
					(number "4"
						(effects
							(font
								(size 1.27 1.27)
							)
						)
					)
				)
				(pin passive line
					(at -5.08 -30.48 0)
					(length 5.08)
					(name "CSI1_D0_P"
						(effects
							(font
								(size 1.27 1.27)
							)
						)
					)
					(number "5"
						(effects
							(font
								(size 1.27 1.27)
							)
						)
					)
				)
				(pin passive line
					(at -5.08 -12.7 0)
					(length 5.08)
					(name "CSI0_D0_P"
						(effects
							(font
								(size 1.27 1.27)
							)
						)
					)
					(number "6"
						(effects
							(font
								(size 1.27 1.27)
							)
						)
					)
				)
				(pin passive line
					(at -5.08 -96.52 0)
					(length 5.08)
					(name "DSI_D0_N"
						(effects
							(font
								(size 1.27 1.27)
							)
						)
					)
					(number "70"
						(effects
							(font
								(size 1.27 1.27)
							)
						)
					)
				)
				(pin passive line
					(at -5.08 -99.06 0)
					(length 5.08)
					(name "DSI_D0_P"
						(effects
							(font
								(size 1.27 1.27)
							)
						)
					)
					(number "72"
						(effects
							(font
								(size 1.27 1.27)
							)
						)
					)
				)
				(pin passive line
					(at -5.08 -101.6 0)
					(length 5.08)
					(name "DSI_CLK_N"
						(effects
							(font
								(size 1.27 1.27)
							)
						)
					)
					(number "76"
						(effects
							(font
								(size 1.27 1.27)
							)
						)
					)
				)
				(pin passive line
					(at -5.08 -104.14 0)
					(length 5.08)
					(name "DSI_CLK_P"
						(effects
							(font
								(size 1.27 1.27)
							)
						)
					)
					(number "78"
						(effects
							(font
								(size 1.27 1.27)
							)
						)
					)
				)
				(pin passive line
					(at -5.08 -106.68 0)
					(length 5.08)
					(name "DSI_D1_N"
						(effects
							(font
								(size 1.27 1.27)
							)
						)
					)
					(number "82"
						(effects
							(font
								(size 1.27 1.27)
							)
						)
					)
				)
				(pin passive line
					(at -5.08 -109.22 0)
					(length 5.08)
					(name "DSI_D1_P"
						(effects
							(font
								(size 1.27 1.27)
							)
						)
					)
					(number "84"
						(effects
							(font
								(size 1.27 1.27)
							)
						)
					)
				)
				(pin passive line
					(at -5.08 -22.86 0)
					(length 5.08)
					(name "CSI1_CLK_N"
						(effects
							(font
								(size 1.27 1.27)
							)
						)
					)
					(number "9"
						(effects
							(font
								(size 1.27 1.27)
							)
						)
					)
				)
			)
			(symbol "Jetson-Orin-9.2H-socket_3_1"
				(polyline
					(pts
						(xy 13.335 -116.2) (xy 13.335 -120.01)
					)
					(stroke
						(width 0)
						(type default)
					)
					(fill
						(type none)
					)
				)
				(polyline
					(pts
						(xy 13.335 -103.505) (xy 13.335 -112.395)
					)
					(stroke
						(width 0)
						(type default)
					)
					(fill
						(type none)
					)
				)
				(polyline
					(pts
						(xy 13.335 -90.805) (xy 13.335 -99.695)
					)
					(stroke
						(width 0)
						(type default)
					)
					(fill
						(type none)
					)
				)
				(polyline
					(pts
						(xy 13.335 -75.565) (xy 13.335 -87)
					)
					(stroke
						(width 0)
						(type default)
					)
					(fill
						(type none)
					)
				)
				(polyline
					(pts
						(xy 13.335 -60.32) (xy 13.335 -71.755)
					)
					(stroke
						(width 0)
						(type default)
					)
					(fill
						(type none)
					)
				)
				(polyline
					(pts
						(xy 13.335 -52.7) (xy 13.335 -56.51)
					)
					(stroke
						(width 0)
						(type default)
					)
					(fill
						(type none)
					)
				)
				(polyline
					(pts
						(xy 13.335 -45.085) (xy 13.335 -48.895)
					)
					(stroke
						(width 0)
						(type default)
					)
					(fill
						(type none)
					)
				)
				(polyline
					(pts
						(xy 13.335 -37.46) (xy 13.335 -41.27)
					)
					(stroke
						(width 0)
						(type default)
					)
					(fill
						(type none)
					)
				)
				(polyline
					(pts
						(xy 13.335 -29.845) (xy 13.335 -33.655)
					)
					(stroke
						(width 0)
						(type default)
					)
					(fill
						(type none)
					)
				)
				(polyline
					(pts
						(xy 13.335 -17.145) (xy 13.335 -26.035)
					)
					(stroke
						(width 0)
						(type default)
					)
					(fill
						(type none)
					)
				)
				(polyline
					(pts
						(xy 13.335 -4.44) (xy 13.335 -13.33)
					)
					(stroke
						(width 0)
						(type default)
					)
					(fill
						(type none)
					)
				)
				(rectangle
					(start 0 0)
					(end 31.75 -124.46)
					(stroke
						(width 0.254)
						(type default)
					)
					(fill
						(type background)
					)
				)
				(arc
					(start 12.7 -120.645)
					(mid 13.149 -120.459)
					(end 13.335 -120.01)
					(stroke
						(width 0)
						(type default)
					)
					(fill
						(type none)
					)
				)
				(arc
					(start 12.7 -113.03)
					(mid 13.1498 -112.8448)
					(end 13.335 -112.395)
					(stroke
						(width 0)
						(type default)
					)
					(fill
						(type none)
					)
				)
				(arc
					(start 12.7 -100.33)
					(mid 13.1498 -100.1448)
					(end 13.335 -99.695)
					(stroke
						(width 0)
						(type default)
					)
					(fill
						(type none)
					)
				)
				(arc
					(start 12.7 -87.63)
					(mid 13.1498 -87.4448)
					(end 13.335 -86.995)
					(stroke
						(width 0)
						(type default)
					)
					(fill
						(type none)
					)
				)
				(arc
					(start 12.7 -72.385)
					(mid 13.149 -72.199)
					(end 13.335 -71.75)
					(stroke
						(width 0)
						(type default)
					)
					(fill
						(type none)
					)
				)
				(arc
					(start 12.7 -57.145)
					(mid 13.149 -56.959)
					(end 13.335 -56.51)
					(stroke
						(width 0)
						(type default)
					)
					(fill
						(type none)
					)
				)
				(arc
					(start 12.7 -49.53)
					(mid 13.1498 -49.3448)
					(end 13.335 -48.895)
					(stroke
						(width 0)
						(type default)
					)
					(fill
						(type none)
					)
				)
				(arc
					(start 12.7 -41.905)
					(mid 13.149 -41.719)
					(end 13.335 -41.27)
					(stroke
						(width 0)
						(type default)
					)
					(fill
						(type none)
					)
				)
				(arc
					(start 12.7 -34.29)
					(mid 13.1498 -34.1048)
					(end 13.335 -33.655)
					(stroke
						(width 0)
						(type default)
					)
					(fill
						(type none)
					)
				)
				(arc
					(start 12.7 -26.67)
					(mid 13.1498 -26.4848)
					(end 13.335 -26.035)
					(stroke
						(width 0)
						(type default)
					)
					(fill
						(type none)
					)
				)
				(arc
					(start 12.7 -13.965)
					(mid 13.149 -13.779)
					(end 13.335 -13.33)
					(stroke
						(width 0)
						(type default)
					)
					(fill
						(type none)
					)
				)
				(arc
					(start 13.335 -116.2)
					(mid 13.149 -115.751)
					(end 12.7 -115.565)
					(stroke
						(width 0)
						(type default)
					)
					(fill
						(type none)
					)
				)
				(arc
					(start 13.335 -103.505)
					(mid 13.149 -103.056)
					(end 12.7 -102.87)
					(stroke
						(width 0)
						(type default)
					)
					(fill
						(type none)
					)
				)
				(arc
					(start 13.335 -90.805)
					(mid 13.149 -90.356)
					(end 12.7 -90.17)
					(stroke
						(width 0)
						(type default)
					)
					(fill
						(type none)
					)
				)
				(arc
					(start 13.335 -75.565)
					(mid 13.149 -75.116)
					(end 12.7 -74.93)
					(stroke
						(width 0)
						(type default)
					)
					(fill
						(type none)
					)
				)
				(arc
					(start 13.335 -60.32)
					(mid 13.149 -59.871)
					(end 12.7 -59.685)
					(stroke
						(width 0)
						(type default)
					)
					(fill
						(type none)
					)
				)
				(arc
					(start 13.335 -52.7)
					(mid 13.149 -52.251)
					(end 12.7 -52.065)
					(stroke
						(width 0)
						(type default)
					)
					(fill
						(type none)
					)
				)
				(arc
					(start 13.335 -45.085)
					(mid 13.149 -44.636)
					(end 12.7 -44.45)
					(stroke
						(width 0)
						(type default)
					)
					(fill
						(type none)
					)
				)
				(arc
					(start 13.335 -37.46)
					(mid 13.149 -37.011)
					(end 12.7 -36.825)
					(stroke
						(width 0)
						(type default)
					)
					(fill
						(type none)
					)
				)
				(arc
					(start 13.335 -29.845)
					(mid 13.149 -29.396)
					(end 12.7 -29.21)
					(stroke
						(width 0)
						(type default)
					)
					(fill
						(type none)
					)
				)
				(arc
					(start 13.335 -17.145)
					(mid 13.149 -16.696)
					(end 12.7 -16.51)
					(stroke
						(width 0)
						(type default)
					)
					(fill
						(type none)
					)
				)
				(arc
					(start 13.335 -4.44)
					(mid 13.149 -3.991)
					(end 12.7 -3.805)
					(stroke
						(width 0)
						(type default)
					)
					(fill
						(type none)
					)
				)
				(text "1.8V CMOS"
					(at 13.97 -107.95 0)
					(effects
						(font
							(size 1.27 1.27)
						)
						(justify left)
					)
				)
				(text "1.8V CMOS"
					(at 13.97 -95.25 0)
					(effects
						(font
							(size 1.27 1.27)
						)
						(justify left)
					)
				)
				(text "1.8V CMOS"
					(at 13.97 -81.285 0)
					(effects
						(font
							(size 1.27 1.27)
						)
						(justify left)
					)
				)
				(text "1.8V CMOS"
					(at 13.97 -66.04 0)
					(effects
						(font
							(size 1.27 1.27)
						)
						(justify left)
					)
				)
				(text "1.8V CMOS"
					(at 13.97 -31.75 0)
					(effects
						(font
							(size 1.27 1.27)
						)
						(justify left)
					)
				)
				(text "1.8V CMOS"
					(at 13.97 -21.59 0)
					(effects
						(font
							(size 1.27 1.27)
						)
						(justify left)
					)
				)
				(text "1.8V CMOS"
					(at 13.97 -8.885 0)
					(effects
						(font
							(size 1.27 1.27)
						)
						(justify left)
					)
				)
				(text "1.8V PU Bidir"
					(at 13.97 -54.605 0)
					(effects
						(font
							(size 1.27 1.27)
						)
						(justify left)
					)
				)
				(text "3.3V CMOS"
					(at 13.97 -118.105 0)
					(effects
						(font
							(size 1.27 1.27)
						)
						(justify left)
					)
				)
				(text "3.3V PU Bidir"
					(at 13.97 -46.99 0)
					(effects
						(font
							(size 1.27 1.27)
						)
						(justify left)
					)
				)
				(text "3.3V PU Bidir"
					(at 13.97 -39.365 0)
					(effects
						(font
							(size 1.27 1.27)
						)
						(justify left)
					)
				)
				(pin passive line
					(at -5.08 -12.7 0)
					(length 5.08)
					(name "UART0_RXD"
						(effects
							(font
								(size 1.27 1.27)
							)
						)
					)
					(number "101"
						(effects
							(font
								(size 1.27 1.27)
							)
						)
					)
				)
				(pin passive line
					(at -5.08 -5.08 0)
					(length 5.08)
					(name "UART0_RTS*"
						(effects
							(font
								(size 1.27 1.27)
							)
						)
					)
					(number "103"
						(effects
							(font
								(size 1.27 1.27)
							)
						)
					)
				)
				(pin passive line
					(at -5.08 -78.74 0)
					(length 5.08)
					(name "SPI1_MOSI"
						(effects
							(font
								(size 1.27 1.27)
							)
						)
					)
					(number "104"
						(effects
							(font
								(size 1.27 1.27)
							)
						)
					)
				)
				(pin passive line
					(at -5.08 -7.62 0)
					(length 5.08)
					(name "UART0_CTS*"
						(effects
							(font
								(size 1.27 1.27)
							)
						)
					)
					(number "105"
						(effects
							(font
								(size 1.27 1.27)
							)
						)
					)
				)
				(pin passive line
					(at -5.08 -76.2 0)
					(length 5.08)
					(name "SPI1_SCK"
						(effects
							(font
								(size 1.27 1.27)
							)
						)
					)
					(number "106"
						(effects
							(font
								(size 1.27 1.27)
							)
						)
					)
				)
				(pin passive line
					(at -5.08 -81.28 0)
					(length 5.08)
					(name "SPI1_MISO"
						(effects
							(font
								(size 1.27 1.27)
							)
						)
					)
					(number "108"
						(effects
							(font
								(size 1.27 1.27)
							)
						)
					)
				)
				(pin passive line
					(at -5.08 -83.82 0)
					(length 5.08)
					(name "SPI1_CS0*"
						(effects
							(font
								(size 1.27 1.27)
							)
						)
					)
					(number "110"
						(effects
							(font
								(size 1.27 1.27)
							)
						)
					)
				)
				(pin passive line
					(at -5.08 -86.36 0)
					(length 5.08)
					(name "SPI1_CS1*"
						(effects
							(font
								(size 1.27 1.27)
							)
						)
					)
					(number "112"
						(effects
							(font
								(size 1.27 1.27)
							)
						)
					)
				)
				(pin passive line
					(at -5.08 -116.84 0)
					(length 5.08)
					(name "CAN_RX"
						(effects
							(font
								(size 1.27 1.27)
							)
						)
					)
					(number "143"
						(effects
							(font
								(size 1.27 1.27)
							)
						)
					)
				)
				(pin passive line
					(at -5.08 -119.38 0)
					(length 5.08)
					(name "CAN_TX"
						(effects
							(font
								(size 1.27 1.27)
							)
						)
					)
					(number "145"
						(effects
							(font
								(size 1.27 1.27)
							)
						)
					)
				)
				(pin passive line
					(at -5.08 -38.1 0)
					(length 5.08)
					(name "I2C0_SCL"
						(effects
							(font
								(size 1.27 1.27)
							)
						)
					)
					(number "185"
						(effects
							(font
								(size 1.27 1.27)
							)
						)
					)
				)
				(pin passive line
					(at -5.08 -40.64 0)
					(length 5.08)
					(name "I2C0_SDA"
						(effects
							(font
								(size 1.27 1.27)
							)
						)
					)
					(number "187"
						(effects
							(font
								(size 1.27 1.27)
							)
						)
					)
				)
				(pin passive line
					(at -5.08 -45.72 0)
					(length 5.08)
					(name "I2C1_SCL"
						(effects
							(font
								(size 1.27 1.27)
							)
						)
					)
					(number "189"
						(effects
							(font
								(size 1.27 1.27)
							)
						)
					)
				)
				(pin passive line
					(at -5.08 -48.26 0)
					(length 5.08)
					(name "I2C1_SDA"
						(effects
							(font
								(size 1.27 1.27)
							)
						)
					)
					(number "191"
						(effects
							(font
								(size 1.27 1.27)
							)
						)
					)
				)
				(pin passive line
					(at -5.08 -93.98 0)
					(length 5.08)
					(name "I2S0_DOUT"
						(effects
							(font
								(size 1.27 1.27)
							)
						)
					)
					(number "193"
						(effects
							(font
								(size 1.27 1.27)
							)
						)
					)
				)
				(pin passive line
					(at -5.08 -96.52 0)
					(length 5.08)
					(name "I2S0_DIN"
						(effects
							(font
								(size 1.27 1.27)
							)
						)
					)
					(number "195"
						(effects
							(font
								(size 1.27 1.27)
							)
						)
					)
				)
				(pin passive line
					(at -5.08 -99.06 0)
					(length 5.08)
					(name "I2S0_FS"
						(effects
							(font
								(size 1.27 1.27)
							)
						)
					)
					(number "197"
						(effects
							(font
								(size 1.27 1.27)
							)
						)
					)
				)
				(pin passive line
					(at -5.08 -91.44 0)
					(length 5.08)
					(name "I2S0_SCLK"
						(effects
							(font
								(size 1.27 1.27)
							)
						)
					)
					(number "199"
						(effects
							(font
								(size 1.27 1.27)
							)
						)
					)
				)
				(pin passive line
					(at -5.08 -22.86 0)
					(length 5.08)
					(name "UART1_TXD"
						(effects
							(font
								(size 1.27 1.27)
							)
						)
					)
					(number "203"
						(effects
							(font
								(size 1.27 1.27)
							)
						)
					)
				)
				(pin passive line
					(at -5.08 -25.4 0)
					(length 5.08)
					(name "UART1_RXD"
						(effects
							(font
								(size 1.27 1.27)
							)
						)
					)
					(number "205"
						(effects
							(font
								(size 1.27 1.27)
							)
						)
					)
				)
				(pin passive line
					(at -5.08 -17.78 0)
					(length 5.08)
					(name "UART1_RTS*"
						(effects
							(font
								(size 1.27 1.27)
							)
						)
					)
					(number "207"
						(effects
							(font
								(size 1.27 1.27)
							)
						)
					)
				)
				(pin passive line
					(at -5.08 -20.32 0)
					(length 5.08)
					(name "UART1_CTS*"
						(effects
							(font
								(size 1.27 1.27)
							)
						)
					)
					(number "209"
						(effects
							(font
								(size 1.27 1.27)
							)
						)
					)
				)
				(pin passive line
					(at -5.08 -106.68 0)
					(length 5.08)
					(name "I2S1_DOUT"
						(effects
							(font
								(size 1.27 1.27)
							)
						)
					)
					(number "220"
						(effects
							(font
								(size 1.27 1.27)
							)
						)
					)
				)
				(pin passive line
					(at -5.08 -109.22 0)
					(length 5.08)
					(name "I2S1_DIN"
						(effects
							(font
								(size 1.27 1.27)
							)
						)
					)
					(number "222"
						(effects
							(font
								(size 1.27 1.27)
							)
						)
					)
				)
				(pin passive line
					(at -5.08 -111.76 0)
					(length 5.08)
					(name "I2S1_FS"
						(effects
							(font
								(size 1.27 1.27)
							)
						)
					)
					(number "224"
						(effects
							(font
								(size 1.27 1.27)
							)
						)
					)
				)
				(pin passive line
					(at -5.08 -104.14 0)
					(length 5.08)
					(name "I2S1_SCLK"
						(effects
							(font
								(size 1.27 1.27)
							)
						)
					)
					(number "226"
						(effects
							(font
								(size 1.27 1.27)
							)
						)
					)
				)
				(pin passive line
					(at -5.08 -53.34 0)
					(length 5.08)
					(name "I2C2_SCL"
						(effects
							(font
								(size 1.27 1.27)
							)
						)
					)
					(number "232"
						(effects
							(font
								(size 1.27 1.27)
							)
						)
					)
				)
				(pin passive line
					(at -5.08 -55.88 0)
					(length 5.08)
					(name "I2C2_SDA"
						(effects
							(font
								(size 1.27 1.27)
							)
						)
					)
					(number "234"
						(effects
							(font
								(size 1.27 1.27)
							)
						)
					)
				)
				(pin passive line
					(at -5.08 -30.48 0)
					(length 5.08)
					(name "UART2_TXD"
						(effects
							(font
								(size 1.27 1.27)
							)
						)
					)
					(number "236"
						(effects
							(font
								(size 1.27 1.27)
							)
						)
					)
				)
				(pin passive line
					(at -5.08 -33.02 0)
					(length 5.08)
					(name "UART2_RXD"
						(effects
							(font
								(size 1.27 1.27)
							)
						)
					)
					(number "238"
						(effects
							(font
								(size 1.27 1.27)
							)
						)
					)
				)
				(pin passive line
					(at -5.08 -63.5 0)
					(length 5.08)
					(name "SPI0_MOSI"
						(effects
							(font
								(size 1.27 1.27)
							)
						)
					)
					(number "89"
						(effects
							(font
								(size 1.27 1.27)
							)
						)
					)
				)
				(pin passive line
					(at -5.08 -60.96 0)
					(length 5.08)
					(name "SPI0_SCK"
						(effects
							(font
								(size 1.27 1.27)
							)
						)
					)
					(number "91"
						(effects
							(font
								(size 1.27 1.27)
							)
						)
					)
				)
				(pin passive line
					(at -5.08 -66.04 0)
					(length 5.08)
					(name "SPI0_MISO"
						(effects
							(font
								(size 1.27 1.27)
							)
						)
					)
					(number "93"
						(effects
							(font
								(size 1.27 1.27)
							)
						)
					)
				)
				(pin passive line
					(at -5.08 -68.58 0)
					(length 5.08)
					(name "SPI0_CS0*"
						(effects
							(font
								(size 1.27 1.27)
							)
						)
					)
					(number "95"
						(effects
							(font
								(size 1.27 1.27)
							)
						)
					)
				)
				(pin passive line
					(at -5.08 -71.12 0)
					(length 5.08)
					(name "SPI0_CS1*"
						(effects
							(font
								(size 1.27 1.27)
							)
						)
					)
					(number "97"
						(effects
							(font
								(size 1.27 1.27)
							)
						)
					)
				)
				(pin passive line
					(at -5.08 -10.16 0)
					(length 5.08)
					(name "UART0_TXD"
						(effects
							(font
								(size 1.27 1.27)
							)
						)
					)
					(number "99"
						(effects
							(font
								(size 1.27 1.27)
							)
						)
					)
				)
			)
			(symbol "Jetson-Orin-9.2H-socket_4_1"
				(rectangle
					(start 0 0)
					(end 31.75 -71.12)
					(stroke
						(width 0.254)
						(type default)
					)
					(fill
						(type background)
					)
				)
				(arc
					(start 13.335 -6.35)
					(mid 13.521 -6.799)
					(end 13.97 -6.985)
					(stroke
						(width 0)
						(type default)
					)
					(fill
						(type none)
					)
				)
				(text "1.8V OD Bidir, 3.3V Tolerant"
					(at 13.97 -6.985 0)
					(effects
						(font
							(size 0.762 0.762)
						)
						(justify left)
					)
				)
				(pin passive line
					(at -5.08 -48.26 0)
					(length 5.08)
					(name "USB0_D_N"
						(effects
							(font
								(size 1.27 1.27)
							)
						)
					)
					(number "109"
						(effects
							(font
								(size 1.27 1.27)
							)
						)
					)
				)
				(pin passive line
					(at -5.08 -50.8 0)
					(length 5.08)
					(name "USB0_D_P"
						(effects
							(font
								(size 1.27 1.27)
							)
						)
					)
					(number "111"
						(effects
							(font
								(size 1.27 1.27)
							)
						)
					)
				)
				(pin passive line
					(at -5.08 -55.88 0)
					(length 5.08)
					(name "USB1_D_N"
						(effects
							(font
								(size 1.27 1.27)
							)
						)
					)
					(number "115"
						(effects
							(font
								(size 1.27 1.27)
							)
						)
					)
				)
				(pin passive line
					(at -5.08 -58.42 0)
					(length 5.08)
					(name "USB1_D_P"
						(effects
							(font
								(size 1.27 1.27)
							)
						)
					)
					(number "117"
						(effects
							(font
								(size 1.27 1.27)
							)
						)
					)
				)
				(pin passive line
					(at -5.08 -63.5 0)
					(length 5.08)
					(name "USB2_D_N"
						(effects
							(font
								(size 1.27 1.27)
							)
						)
					)
					(number "121"
						(effects
							(font
								(size 1.27 1.27)
							)
						)
					)
				)
				(pin passive line
					(at -5.08 -66.04 0)
					(length 5.08)
					(name "USB2_D_P"
						(effects
							(font
								(size 1.27 1.27)
							)
						)
					)
					(number "123"
						(effects
							(font
								(size 1.27 1.27)
							)
						)
					)
				)
				(pin passive line
					(at -5.08 -15.24 0)
					(length 5.08)
					(name "USBSS0_RX_N"
						(effects
							(font
								(size 1.27 1.27)
							)
						)
					)
					(number "161"
						(effects
							(font
								(size 1.27 1.27)
							)
						)
					)
				)
				(pin passive line
					(at -5.08 -17.78 0)
					(length 5.08)
					(name "USBSS0_RX_P"
						(effects
							(font
								(size 1.27 1.27)
							)
						)
					)
					(number "163"
						(effects
							(font
								(size 1.27 1.27)
							)
						)
					)
				)
				(pin passive line
					(at -5.08 -10.16 0)
					(length 5.08)
					(name "USBSS0_TX_N"
						(effects
							(font
								(size 1.27 1.27)
							)
						)
					)
					(number "166"
						(effects
							(font
								(size 1.27 1.27)
							)
						)
					)
				)
				(pin passive line
					(at -5.08 -12.7 0)
					(length 5.08)
					(name "USBSS0_TX_P"
						(effects
							(font
								(size 1.27 1.27)
							)
						)
					)
					(number "168"
						(effects
							(font
								(size 1.27 1.27)
							)
						)
					)
				)
				(pin passive line
					(at -5.08 -27.94 0)
					(length 5.08)
					(name "USBSS1_RX_N"
						(effects
							(font
								(size 1.27 1.27)
							)
						)
					)
					(number "39"
						(effects
							(font
								(size 1.27 1.27)
							)
						)
					)
				)
				(pin passive line
					(at -5.08 -30.48 0)
					(length 5.08)
					(name "USBSS1_RX_P"
						(effects
							(font
								(size 1.27 1.27)
							)
						)
					)
					(number "41"
						(effects
							(font
								(size 1.27 1.27)
							)
						)
					)
				)
				(pin passive line
					(at -5.08 -22.86 0)
					(length 5.08)
					(name "USBSS1_TX_N"
						(effects
							(font
								(size 1.27 1.27)
							)
						)
					)
					(number "45"
						(effects
							(font
								(size 1.27 1.27)
							)
						)
					)
				)
				(pin passive line
					(at -5.08 -25.4 0)
					(length 5.08)
					(name "USBSS1_TX_P"
						(effects
							(font
								(size 1.27 1.27)
							)
						)
					)
					(number "47"
						(effects
							(font
								(size 1.27 1.27)
							)
						)
					)
				)
				(pin passive line
					(at -5.08 -40.64 0)
					(length 5.08)
					(name "USBSS2_RX_N"
						(effects
							(font
								(size 1.27 1.27)
							)
						)
					)
					(number "51"
						(effects
							(font
								(size 1.27 1.27)
							)
						)
					)
				)
				(pin passive line
					(at -5.08 -43.18 0)
					(length 5.08)
					(name "USBSS2_RX_P"
						(effects
							(font
								(size 1.27 1.27)
							)
						)
					)
					(number "53"
						(effects
							(font
								(size 1.27 1.27)
							)
						)
					)
				)
				(pin passive line
					(at -5.08 -35.56 0)
					(length 5.08)
					(name "USBSS2_TX_N"
						(effects
							(font
								(size 1.27 1.27)
							)
						)
					)
					(number "57"
						(effects
							(font
								(size 1.27 1.27)
							)
						)
					)
				)
				(pin passive line
					(at -5.08 -38.1 0)
					(length 5.08)
					(name "USBSS2_TX_P"
						(effects
							(font
								(size 1.27 1.27)
							)
						)
					)
					(number "59"
						(effects
							(font
								(size 1.27 1.27)
							)
						)
					)
				)
				(pin passive line
					(at -5.08 -5.08 0)
					(length 5.08)
					(name "USB_VBUS_EN0/GPIO00"
						(effects
							(font
								(size 1.27 1.27)
							)
						)
					)
					(number "87"
						(effects
							(font
								(size 1.27 1.27)
							)
						)
					)
					(alternate "GPIO00" passive line)
					(alternate "GPIO00(USB_VBUS_EN0)" passive line)
				)
			)
			(symbol "Jetson-Orin-9.2H-socket_5_1"
				(polyline
					(pts
						(xy 0 -48.26) (xy 31.75 -48.26)
					)
					(stroke
						(width 0)
						(type default)
					)
					(fill
						(type none)
					)
				)
				(rectangle
					(start 0 0)
					(end 31.75 -60.96)
					(stroke
						(width 0.254)
						(type default)
					)
					(fill
						(type background)
					)
				)
				(text "1.8V Input"
					(at 10.795 -7.62 0)
					(effects
						(font
							(size 0.762 0.762)
						)
						(justify left)
					)
				)
				(text "1k PU to 1.8V Bidir"
					(at 10.795 -5.08 0)
					(effects
						(font
							(size 0.762 0.762)
						)
						(justify left)
					)
				)
				(text "RSVD"
					(at 26.67 -49.53 0)
					(effects
						(font
							(size 1.27 1.27)
							(bold yes)
						)
					)
				)
				(pin passive line
					(at -5.08 -15.24 0)
					(length 5.08)
					(name "DP1_AUX_P"
						(effects
							(font
								(size 1.27 1.27)
							)
						)
					)
					(number "100"
						(effects
							(font
								(size 1.27 1.27)
							)
						)
					)
				)
				(pin passive line
					(at -5.08 -20.32 0)
					(length 5.08)
					(name "DP1_TXD0_N"
						(effects
							(font
								(size 1.27 1.27)
							)
						)
					)
					(number "63"
						(effects
							(font
								(size 1.27 1.27)
							)
						)
					)
				)
				(pin passive line
					(at -5.08 -22.86 0)
					(length 5.08)
					(name "DP1_TXD0_P"
						(effects
							(font
								(size 1.27 1.27)
							)
						)
					)
					(number "65"
						(effects
							(font
								(size 1.27 1.27)
							)
						)
					)
				)
				(pin passive line
					(at -5.08 -27.94 0)
					(length 5.08)
					(name "DP1_TXD1_N"
						(effects
							(font
								(size 1.27 1.27)
							)
						)
					)
					(number "69"
						(effects
							(font
								(size 1.27 1.27)
							)
						)
					)
				)
				(pin passive line
					(at -5.08 -30.48 0)
					(length 5.08)
					(name "DP1_TXD1_P"
						(effects
							(font
								(size 1.27 1.27)
							)
						)
					)
					(number "71"
						(effects
							(font
								(size 1.27 1.27)
							)
						)
					)
				)
				(pin passive line
					(at -5.08 -35.56 0)
					(length 5.08)
					(name "DP1_TXD2_N"
						(effects
							(font
								(size 1.27 1.27)
							)
						)
					)
					(number "75"
						(effects
							(font
								(size 1.27 1.27)
							)
						)
					)
				)
				(pin passive line
					(at -5.08 -38.1 0)
					(length 5.08)
					(name "DP1_TXD2_P"
						(effects
							(font
								(size 1.27 1.27)
							)
						)
					)
					(number "77"
						(effects
							(font
								(size 1.27 1.27)
							)
						)
					)
				)
				(pin passive line
					(at -5.08 -43.18 0)
					(length 5.08)
					(name "DP1_TXD3_N"
						(effects
							(font
								(size 1.27 1.27)
							)
						)
					)
					(number "81"
						(effects
							(font
								(size 1.27 1.27)
							)
						)
					)
				)
				(pin passive line
					(at -5.08 -45.72 0)
					(length 5.08)
					(name "DP1_TXD3_P"
						(effects
							(font
								(size 1.27 1.27)
							)
						)
					)
					(number "83"
						(effects
							(font
								(size 1.27 1.27)
							)
						)
					)
				)
				(pin passive line
					(at -5.08 -50.8 0)
					(length 5.08)
					(name "DP0_HPD"
						(effects
							(font
								(size 1.27 1.27)
							)
						)
					)
					(number "88"
						(effects
							(font
								(size 1.27 1.27)
							)
						)
					)
				)
				(pin passive line
					(at -5.08 -53.34 0)
					(length 5.08)
					(name "DP0_AUX_N"
						(effects
							(font
								(size 1.27 1.27)
							)
						)
					)
					(number "90"
						(effects
							(font
								(size 1.27 1.27)
							)
						)
					)
				)
				(pin passive line
					(at -5.08 -55.88 0)
					(length 5.08)
					(name "DP0_AUX_P"
						(effects
							(font
								(size 1.27 1.27)
							)
						)
					)
					(number "92"
						(effects
							(font
								(size 1.27 1.27)
							)
						)
					)
				)
				(pin passive line
					(at -5.08 -5.08 0)
					(length 5.08)
					(name "HDMI_CEC"
						(effects
							(font
								(size 1.27 1.27)
							)
						)
					)
					(number "94"
						(effects
							(font
								(size 1.27 1.27)
							)
						)
					)
				)
				(pin passive line
					(at -5.08 -7.62 0)
					(length 5.08)
					(name "DP1_HPD"
						(effects
							(font
								(size 1.27 1.27)
							)
						)
					)
					(number "96"
						(effects
							(font
								(size 1.27 1.27)
							)
						)
					)
				)
				(pin passive line
					(at -5.08 -12.7 0)
					(length 5.08)
					(name "DP1_AUX_N"
						(effects
							(font
								(size 1.27 1.27)
							)
						)
					)
					(number "98"
						(effects
							(font
								(size 1.27 1.27)
							)
						)
					)
				)
			)
			(symbol "Jetson-Orin-9.2H-socket_6_1"
				(rectangle
					(start 0 0)
					(end 31.75 -149.86)
					(stroke
						(width 0.254)
						(type default)
					)
					(fill
						(type background)
					)
				)
				(text "47k PU to 3.3V"
					(at 12.7 -5.08 0)
					(effects
						(font
							(size 0.762 0.762)
						)
						(justify left)
					)
				)
				(pin passive line
					(at -5.08 -27.94 0)
					(length 5.08)
					(name "PCIE0_RX0_N"
						(effects
							(font
								(size 1.27 1.27)
							)
						)
					)
					(number "131"
						(effects
							(font
								(size 1.27 1.27)
							)
						)
					)
				)
				(pin passive line
					(at -5.08 -30.48 0)
					(length 5.08)
					(name "PCIE0_RX0_P"
						(effects
							(font
								(size 1.27 1.27)
							)
						)
					)
					(number "133"
						(effects
							(font
								(size 1.27 1.27)
							)
						)
					)
				)
				(pin passive line
					(at -5.08 -22.86 0)
					(length 5.08)
					(name "PCIE0_TX0_N"
						(effects
							(font
								(size 1.27 1.27)
							)
						)
					)
					(number "134"
						(effects
							(font
								(size 1.27 1.27)
							)
						)
					)
				)
				(pin passive line
					(at -5.08 -25.4 0)
					(length 5.08)
					(name "PCIE0_TX0_P"
						(effects
							(font
								(size 1.27 1.27)
							)
						)
					)
					(number "136"
						(effects
							(font
								(size 1.27 1.27)
							)
						)
					)
				)
				(pin passive line
					(at -5.08 -40.64 0)
					(length 5.08)
					(name "PCIE0_RX1_N"
						(effects
							(font
								(size 1.27 1.27)
							)
						)
					)
					(number "137"
						(effects
							(font
								(size 1.27 1.27)
							)
						)
					)
				)
				(pin passive line
					(at -5.08 -43.18 0)
					(length 5.08)
					(name "PCIE0_RX1_P"
						(effects
							(font
								(size 1.27 1.27)
							)
						)
					)
					(number "139"
						(effects
							(font
								(size 1.27 1.27)
							)
						)
					)
				)
				(pin passive line
					(at -5.08 -35.56 0)
					(length 5.08)
					(name "PCIE0_TX1_N"
						(effects
							(font
								(size 1.27 1.27)
							)
						)
					)
					(number "140"
						(effects
							(font
								(size 1.27 1.27)
							)
						)
					)
				)
				(pin passive line
					(at -5.08 -38.1 0)
					(length 5.08)
					(name "PCIE0_TX1_P"
						(effects
							(font
								(size 1.27 1.27)
							)
						)
					)
					(number "142"
						(effects
							(font
								(size 1.27 1.27)
							)
						)
					)
				)
				(pin passive line
					(at -5.08 -48.26 0)
					(length 5.08)
					(name "PCIE0_TX2_N"
						(effects
							(font
								(size 1.27 1.27)
							)
						)
					)
					(number "148"
						(effects
							(font
								(size 1.27 1.27)
							)
						)
					)
				)
				(pin passive line
					(at -5.08 -53.34 0)
					(length 5.08)
					(name "PCIE0_RX2_N"
						(effects
							(font
								(size 1.27 1.27)
							)
						)
					)
					(number "149"
						(effects
							(font
								(size 1.27 1.27)
							)
						)
					)
				)
				(pin passive line
					(at -5.08 -50.8 0)
					(length 5.08)
					(name "PCIE0_TX2_P"
						(effects
							(font
								(size 1.27 1.27)
							)
						)
					)
					(number "150"
						(effects
							(font
								(size 1.27 1.27)
							)
						)
					)
				)
				(pin passive line
					(at -5.08 -55.88 0)
					(length 5.08)
					(name "PCIE0_RX2_P"
						(effects
							(font
								(size 1.27 1.27)
							)
						)
					)
					(number "151"
						(effects
							(font
								(size 1.27 1.27)
							)
						)
					)
				)
				(pin passive line
					(at -5.08 -60.96 0)
					(length 5.08)
					(name "PCIE0_TX3_N"
						(effects
							(font
								(size 1.27 1.27)
							)
						)
					)
					(number "154"
						(effects
							(font
								(size 1.27 1.27)
							)
						)
					)
				)
				(pin passive line
					(at -5.08 -66.04 0)
					(length 5.08)
					(name "PCIE0_RX3_N"
						(effects
							(font
								(size 1.27 1.27)
							)
						)
					)
					(number "155"
						(effects
							(font
								(size 1.27 1.27)
							)
						)
					)
				)
				(pin passive line
					(at -5.08 -63.5 0)
					(length 5.08)
					(name "PCIE0_TX3_P"
						(effects
							(font
								(size 1.27 1.27)
							)
						)
					)
					(number "156"
						(effects
							(font
								(size 1.27 1.27)
							)
						)
					)
				)
				(pin passive line
					(at -5.08 -68.58 0)
					(length 5.08)
					(name "PCIE0_RX3_P"
						(effects
							(font
								(size 1.27 1.27)
							)
						)
					)
					(number "157"
						(effects
							(font
								(size 1.27 1.27)
							)
						)
					)
				)
				(pin passive line
					(at -5.08 -15.24 0)
					(length 5.08)
					(name "PCIE0_CLK_N"
						(effects
							(font
								(size 1.27 1.27)
							)
						)
					)
					(number "160"
						(effects
							(font
								(size 1.27 1.27)
							)
						)
					)
				)
				(pin passive line
					(at -5.08 -17.78 0)
					(length 5.08)
					(name "PCIE0_CLK_P"
						(effects
							(font
								(size 1.27 1.27)
							)
						)
					)
					(number "162"
						(effects
							(font
								(size 1.27 1.27)
							)
						)
					)
				)
				(pin passive line
					(at -5.08 -91.44 0)
					(length 5.08)
					(name "PCIE1_RX0_N"
						(effects
							(font
								(size 1.27 1.27)
							)
						)
					)
					(number "167"
						(effects
							(font
								(size 1.27 1.27)
							)
						)
					)
				)
				(pin passive line
					(at -5.08 -93.98 0)
					(length 5.08)
					(name "PCIE1_RX0_P"
						(effects
							(font
								(size 1.27 1.27)
							)
						)
					)
					(number "169"
						(effects
							(font
								(size 1.27 1.27)
							)
						)
					)
				)
				(pin passive line
					(at -5.08 -86.36 0)
					(length 5.08)
					(name "PCIE1_TX0_N"
						(effects
							(font
								(size 1.27 1.27)
							)
						)
					)
					(number "172"
						(effects
							(font
								(size 1.27 1.27)
							)
						)
					)
				)
				(pin passive line
					(at -5.08 -78.74 0)
					(length 5.08)
					(name "PCIE1_CLK_N"
						(effects
							(font
								(size 1.27 1.27)
							)
						)
					)
					(number "173"
						(effects
							(font
								(size 1.27 1.27)
							)
						)
					)
				)
				(pin passive line
					(at -5.08 -88.9 0)
					(length 5.08)
					(name "PCIE1_TX0_P"
						(effects
							(font
								(size 1.27 1.27)
							)
						)
					)
					(number "174"
						(effects
							(font
								(size 1.27 1.27)
							)
						)
					)
				)
				(pin passive line
					(at -5.08 -81.28 0)
					(length 5.08)
					(name "PCIE1_CLK_P"
						(effects
							(font
								(size 1.27 1.27)
							)
						)
					)
					(number "175"
						(effects
							(font
								(size 1.27 1.27)
							)
						)
					)
				)
				(pin passive line
					(at -5.08 -5.08 0)
					(length 5.08)
					(name "PCIE_WAKE*"
						(effects
							(font
								(size 1.27 1.27)
							)
						)
					)
					(number "179"
						(effects
							(font
								(size 1.27 1.27)
							)
						)
					)
				)
				(pin passive line
					(at -5.08 -12.7 0)
					(length 5.08)
					(name "PCIE0_CLKREQ*"
						(effects
							(font
								(size 1.27 1.27)
							)
						)
					)
					(number "180"
						(effects
							(font
								(size 1.27 1.27)
							)
						)
					)
				)
				(pin passive line
					(at -5.08 -10.16 0)
					(length 5.08)
					(name "PCIE0_RST*"
						(effects
							(font
								(size 1.27 1.27)
							)
						)
					)
					(number "181"
						(effects
							(font
								(size 1.27 1.27)
							)
						)
					)
				)
				(pin passive line
					(at -5.08 -76.2 0)
					(length 5.08)
					(name "PCIE1_CLKREQ*"
						(effects
							(font
								(size 1.27 1.27)
							)
						)
					)
					(number "182"
						(effects
							(font
								(size 1.27 1.27)
							)
						)
					)
				)
				(pin passive line
					(at -5.08 -73.66 0)
					(length 5.08)
					(name "PCIE1_RST*"
						(effects
							(font
								(size 1.27 1.27)
							)
						)
					)
					(number "183"
						(effects
							(font
								(size 1.27 1.27)
							)
						)
					)
				)
				(pin passive line
					(at -5.08 -99.06 0)
					(length 5.08)
					(name "PCIE2_RST*"
						(effects
							(font
								(size 1.27 1.27)
							)
						)
					)
					(number "219"
						(effects
							(font
								(size 1.27 1.27)
							)
						)
					)
				)
				(pin passive line
					(at -5.08 -101.6 0)
					(length 5.08)
					(name "PCIE2_CLKREQ*"
						(effects
							(font
								(size 1.27 1.27)
							)
						)
					)
					(number "221"
						(effects
							(font
								(size 1.27 1.27)
							)
						)
					)
				)
				(pin passive line
					(at -5.08 -124.46 0)
					(length 5.08)
					(name "PCIE3_RST*"
						(effects
							(font
								(size 1.27 1.27)
							)
						)
					)
					(number "223"
						(effects
							(font
								(size 1.27 1.27)
							)
						)
					)
				)
				(pin passive line
					(at -5.08 -127 0)
					(length 5.08)
					(name "PCIE3_CLKREQ*"
						(effects
							(font
								(size 1.27 1.27)
							)
						)
					)
					(number "225"
						(effects
							(font
								(size 1.27 1.27)
							)
						)
					)
				)
				(pin passive line
					(at -5.08 -129.54 0)
					(length 5.08)
					(name "PCIE3_CLK_N"
						(effects
							(font
								(size 1.27 1.27)
							)
						)
					)
					(number "227"
						(effects
							(font
								(size 1.27 1.27)
							)
						)
					)
				)
				(pin passive line
					(at -5.08 -132.08 0)
					(length 5.08)
					(name "PCIE3_CLK_P"
						(effects
							(font
								(size 1.27 1.27)
							)
						)
					)
					(number "229"
						(effects
							(font
								(size 1.27 1.27)
							)
						)
					)
				)
				(pin passive line
					(at -5.08 -116.84 0)
					(length 5.08)
					(name "PCIE2_RX0_N"
						(effects
							(font
								(size 1.27 1.27)
							)
						)
					)
					(number "40"
						(effects
							(font
								(size 1.27 1.27)
							)
						)
					)
				)
				(pin passive line
					(at -5.08 -119.38 0)
					(length 5.08)
					(name "PCIE2_RX0_P"
						(effects
							(font
								(size 1.27 1.27)
							)
						)
					)
					(number "42"
						(effects
							(font
								(size 1.27 1.27)
							)
						)
					)
				)
				(pin passive line
					(at -5.08 -111.76 0)
					(length 5.08)
					(name "PCIE2_TX0_N"
						(effects
							(font
								(size 1.27 1.27)
							)
						)
					)
					(number "46"
						(effects
							(font
								(size 1.27 1.27)
							)
						)
					)
				)
				(pin passive line
					(at -5.08 -114.3 0)
					(length 5.08)
					(name "PCIE2_TX0_P"
						(effects
							(font
								(size 1.27 1.27)
							)
						)
					)
					(number "48"
						(effects
							(font
								(size 1.27 1.27)
							)
						)
					)
				)
				(pin passive line
					(at -5.08 -104.14 0)
					(length 5.08)
					(name "PCIE2_CLK_N"
						(effects
							(font
								(size 1.27 1.27)
							)
						)
					)
					(number "52"
						(effects
							(font
								(size 1.27 1.27)
							)
						)
					)
				)
				(pin passive line
					(at -5.08 -106.68 0)
					(length 5.08)
					(name "PCIE2_CLK_P"
						(effects
							(font
								(size 1.27 1.27)
							)
						)
					)
					(number "54"
						(effects
							(font
								(size 1.27 1.27)
							)
						)
					)
				)
				(pin passive line
					(at -5.08 -142.24 0)
					(length 5.08)
					(name "PCIE2_RX1_N/PCIE3_RX0_N"
						(effects
							(font
								(size 1.27 1.27)
							)
						)
					)
					(number "58"
						(effects
							(font
								(size 1.27 1.27)
							)
						)
					)
					(alternate "PCIE2_RX1_N" passive line)
					(alternate "PCIE3_RX0_N" passive line)
				)
				(pin passive line
					(at -5.08 -144.78 0)
					(length 5.08)
					(name "PCIE2_RX1_P/PCIE3_RX0_P"
						(effects
							(font
								(size 1.27 1.27)
							)
						)
					)
					(number "60"
						(effects
							(font
								(size 1.27 1.27)
							)
						)
					)
					(alternate "PCIE2_RX1_P" passive line)
					(alternate "PCIE3_RX0_P" passive line)
				)
				(pin passive line
					(at -5.08 -137.16 0)
					(length 5.08)
					(name "PCIE2_TX1_N/PCIE3_TX0_N"
						(effects
							(font
								(size 1.27 1.27)
							)
						)
					)
					(number "64"
						(effects
							(font
								(size 1.27 1.27)
							)
						)
					)
					(alternate "PCIE2_TX1_N" passive line)
					(alternate "PCIE3_TX0_N" passive line)
				)
				(pin passive line
					(at -5.08 -139.7 0)
					(length 5.08)
					(name "PCIE2_TX1_P/PCIE3_TX0_P"
						(effects
							(font
								(size 1.27 1.27)
							)
						)
					)
					(number "66"
						(effects
							(font
								(size 1.27 1.27)
							)
						)
					)
					(alternate "PCIE2_TX1_P" passive line)
					(alternate "PCIE3_TX0_P" passive line)
				)
			)
			(symbol "Jetson-Orin-9.2H-socket_7_1"
				(rectangle
					(start 0 0)
					(end 31.75 -43.18)
					(stroke
						(width 0.254)
						(type default)
					)
					(fill
						(type background)
					)
				)
				(pin passive line
					(at -5.08 -12.7 0)
					(length 5.08)
					(name "GBE_MDI0_N"
						(effects
							(font
								(size 1.27 1.27)
							)
						)
					)
					(number "184"
						(effects
							(font
								(size 1.27 1.27)
							)
						)
					)
				)
				(pin passive line
					(at -5.08 -15.24 0)
					(length 5.08)
					(name "GBE_MDI0_P"
						(effects
							(font
								(size 1.27 1.27)
							)
						)
					)
					(number "186"
						(effects
							(font
								(size 1.27 1.27)
							)
						)
					)
				)
				(pin passive line
					(at -5.08 -5.08 0)
					(length 5.08)
					(name "GBE_LED_LINK"
						(effects
							(font
								(size 1.27 1.27)
							)
						)
					)
					(number "188"
						(effects
							(font
								(size 1.27 1.27)
							)
						)
					)
				)
				(pin passive line
					(at -5.08 -20.32 0)
					(length 5.08)
					(name "GBE_MDI1_N"
						(effects
							(font
								(size 1.27 1.27)
							)
						)
					)
					(number "190"
						(effects
							(font
								(size 1.27 1.27)
							)
						)
					)
				)
				(pin passive line
					(at -5.08 -22.86 0)
					(length 5.08)
					(name "GBE_MDI1_P"
						(effects
							(font
								(size 1.27 1.27)
							)
						)
					)
					(number "192"
						(effects
							(font
								(size 1.27 1.27)
							)
						)
					)
				)
				(pin passive line
					(at -5.08 -7.62 0)
					(length 5.08)
					(name "GBE_LED_ACT"
						(effects
							(font
								(size 1.27 1.27)
							)
						)
					)
					(number "194"
						(effects
							(font
								(size 1.27 1.27)
							)
						)
					)
				)
				(pin passive line
					(at -5.08 -27.94 0)
					(length 5.08)
					(name "GBE_MDI2_N"
						(effects
							(font
								(size 1.27 1.27)
							)
						)
					)
					(number "196"
						(effects
							(font
								(size 1.27 1.27)
							)
						)
					)
				)
				(pin passive line
					(at -5.08 -30.48 0)
					(length 5.08)
					(name "GBE_MDI2_P"
						(effects
							(font
								(size 1.27 1.27)
							)
						)
					)
					(number "198"
						(effects
							(font
								(size 1.27 1.27)
							)
						)
					)
				)
				(pin passive line
					(at -5.08 -35.56 0)
					(length 5.08)
					(name "GBE_MDI3_N"
						(effects
							(font
								(size 1.27 1.27)
							)
						)
					)
					(number "202"
						(effects
							(font
								(size 1.27 1.27)
							)
						)
					)
				)
				(pin passive line
					(at -5.08 -38.1 0)
					(length 5.08)
					(name "GBE_MDI3_P"
						(effects
							(font
								(size 1.27 1.27)
							)
						)
					)
					(number "204"
						(effects
							(font
								(size 1.27 1.27)
							)
						)
					)
				)
			)
			(symbol "Jetson-Orin-9.2H-socket_8_1"
				(polyline
					(pts
						(xy 19.685 -4.445) (xy 19.685 -33.655)
					)
					(stroke
						(width 0)
						(type default)
					)
					(fill
						(type none)
					)
				)
				(rectangle
					(start 0 0)
					(end 31.75 -38.1)
					(stroke
						(width 0.254)
						(type default)
					)
					(fill
						(type background)
					)
				)
				(arc
					(start 19.05 -34.29)
					(mid 19.4998 -34.1048)
					(end 19.685 -33.655)
					(stroke
						(width 0)
						(type default)
					)
					(fill
						(type none)
					)
				)
				(arc
					(start 19.685 -4.445)
					(mid 19.499 -3.996)
					(end 19.05 -3.81)
					(stroke
						(width 0)
						(type default)
					)
					(fill
						(type none)
					)
				)
				(text "1.8V CMOS"
					(at 20.32 -17.78 0)
					(effects
						(font
							(size 1.27 1.27)
						)
						(justify left)
					)
				)
				(pin passive line
					(at -5.08 -5.08 0)
					(length 5.08)
					(name "GPIO01/CLK"
						(effects
							(font
								(size 1.27 1.27)
							)
						)
					)
					(number "118"
						(effects
							(font
								(size 1.27 1.27)
							)
						)
					)
					(alternate "GPIO01" passive line)
					(alternate "GPIO01(CLK)" passive line)
				)
				(pin passive line
					(at -5.08 -7.62 0)
					(length 5.08)
					(name "GPIO02"
						(effects
							(font
								(size 1.27 1.27)
							)
						)
					)
					(number "124"
						(effects
							(font
								(size 1.27 1.27)
							)
						)
					)
				)
				(pin passive line
					(at -5.08 -10.16 0)
					(length 5.08)
					(name "GPIO03"
						(effects
							(font
								(size 1.27 1.27)
							)
						)
					)
					(number "126"
						(effects
							(font
								(size 1.27 1.27)
							)
						)
					)
				)
				(pin passive line
					(at -5.08 -12.7 0)
					(length 5.08)
					(name "GPIO04"
						(effects
							(font
								(size 1.27 1.27)
							)
						)
					)
					(number "127"
						(effects
							(font
								(size 1.27 1.27)
							)
						)
					)
				)
				(pin passive line
					(at -5.08 -15.24 0)
					(length 5.08)
					(name "GPIO05"
						(effects
							(font
								(size 1.27 1.27)
							)
						)
					)
					(number "128"
						(effects
							(font
								(size 1.27 1.27)
							)
						)
					)
				)
				(pin passive line
					(at -5.08 -17.78 0)
					(length 5.08)
					(name "GPIO06"
						(effects
							(font
								(size 1.27 1.27)
							)
						)
					)
					(number "130"
						(effects
							(font
								(size 1.27 1.27)
							)
						)
					)
				)
				(pin passive line
					(at -5.08 -20.32 0)
					(length 5.08)
					(name "GPIO07/PWM"
						(effects
							(font
								(size 1.27 1.27)
							)
						)
					)
					(number "206"
						(effects
							(font
								(size 1.27 1.27)
							)
						)
					)
					(alternate "GPIO07" passive line)
					(alternate "GPIO07(PWM)" passive line)
				)
				(pin passive line
					(at -5.08 -22.86 0)
					(length 5.08)
					(name "GPIO09/AUD_MCLK"
						(effects
							(font
								(size 1.27 1.27)
							)
						)
					)
					(number "211"
						(effects
							(font
								(size 1.27 1.27)
							)
						)
					)
					(alternate "GPIO09" passive line)
					(alternate "GPIO09(AUD_MCLK)" passive line)
				)
				(pin passive line
					(at -5.08 -25.4 0)
					(length 5.08)
					(name "GPIO10"
						(effects
							(font
								(size 1.27 1.27)
							)
						)
					)
					(number "212"
						(effects
							(font
								(size 1.27 1.27)
							)
						)
					)
				)
				(pin passive line
					(at -5.08 -27.94 0)
					(length 5.08)
					(name "GPIO11/CLK"
						(effects
							(font
								(size 1.27 1.27)
							)
						)
					)
					(number "216"
						(effects
							(font
								(size 1.27 1.27)
							)
						)
					)
					(alternate "GPIO11" passive line)
					(alternate "GPIO11(CLK)" passive line)
				)
				(pin passive line
					(at -5.08 -30.48 0)
					(length 5.08)
					(name "GPIO12/PWM"
						(effects
							(font
								(size 1.27 1.27)
							)
						)
					)
					(number "218"
						(effects
							(font
								(size 1.27 1.27)
							)
						)
					)
					(alternate "GPIO12" passive line)
					(alternate "GPIO12(PWM)" passive line)
				)
				(pin passive line
					(at -5.08 -33.02 0)
					(length 5.08)
					(name "GPIO13/PWM"
						(effects
							(font
								(size 1.27 1.27)
							)
						)
					)
					(number "228"
						(effects
							(font
								(size 1.27 1.27)
							)
						)
					)
					(alternate "GPIO13" passive line)
					(alternate "GPIO13(PWM)" passive line)
				)
			)
		)
	(symbol "jetson-orin-baseboard:Jetson-Orin-9.2H-socket_1"
			(pin_names
				(offset 1.016)
			)
			(exclude_from_sim no)
			(in_bom yes)
			(on_board yes)
			(property "Reference" "A"
				(at 1.27 1.27 0)
				(effects
					(font
						(size 1.27 1.27)
					)
				)
			)
			(property "Value" "Jetson-Orin-9.2H-socket_1"
				(at 15.24 2.54 0)
				(effects
					(font
						(size 1.27 1.27)
					)
					(hide yes)
				)
			)
			(property "Footprint" "jetson-orin-baseboard-footprints:TE_2309413"
				(at 15.24 5.08 0)
				(effects
					(font
						(size 1.27 1.27)
					)
					(hide yes)
				)
			)
			(property "Datasheet" "https://developer.nvidia.com/jetson-orin-nx-series-data-sheet"
				(at 15.24 7.62 0)
				(effects
					(font
						(size 1.27 1.27)
					)
					(hide yes)
				)
			)
			(property "Description" "NVIDIA Jetson Orin NX/Nano module female socket, 260-pin SODIMM 9.2mm stack height, with all Alternate Pin Functions from Datasheet"
				(at 0 0 0)
				(effects
					(font
						(size 1.27 1.27)
					)
					(hide yes)
				)
			)
			(property "Manufacturer" "TE"
				(at 24.13 1.27 0)
				(effects
					(font
						(size 1.27 1.27)
					)
				)
			)
			(property "MPN" "2309413-1"
				(at 31.75 1.27 0)
				(effects
					(font
						(size 1.27 1.27)
					)
				)
			)
			(property "License" "MIT"
				(at 34.29 3.81 0)
				(effects
					(font
						(size 1.27 1.27)
					)
					(hide yes)
				)
			)
			(property "ki_locked" ""
				(at 0 0 0)
				(effects
					(font
						(size 1.27 1.27)
					)
				)
			)
			(property "ki_keywords" "nvidia jetson orin nx nano som"
				(at 0 0 0)
				(effects
					(font
						(size 1.27 1.27)
					)
					(hide yes)
				)
			)
			(symbol "Jetson-Orin-9.2H-socket_1_1_1"
				(rectangle
					(start 0 -132.08)
					(end 40.64 0)
					(stroke
						(width 0.254)
						(type default)
					)
					(fill
						(type background)
					)
				)
				(polyline
					(pts
						(xy 8.255 -4.445) (xy 8.255 -28.575)
					)
					(stroke
						(width 0)
						(type default)
					)
					(fill
						(type none)
					)
				)
				(arc
					(start 7.62 -29.21)
					(mid 8.069 -29.024)
					(end 8.255 -28.575)
					(stroke
						(width 0)
						(type default)
					)
					(fill
						(type none)
					)
				)
				(arc
					(start 8.255 -4.445)
					(mid 8.069 -3.996)
					(end 7.62 -3.81)
					(stroke
						(width 0)
						(type default)
					)
					(fill
						(type none)
					)
				)
				(text "1.8V Bidir "
					(at 22.86 -7.62 0)
					(effects
						(font
							(size 0.762 0.762)
						)
						(justify right)
					)
				)
				(text "1.8V Bidir "
					(at 27.305 -10.16 0)
					(effects
						(font
							(size 0.762 0.762)
						)
						(justify right)
					)
				)
				(text "1.8V CMOS Output"
					(at 27.305 -27.94 0)
					(effects
						(font
							(size 0.762 0.762)
						)
						(justify right)
					)
				)
				(text "1.8V-5.5V Input"
					(at 11.43 -43.18 0)
					(effects
						(font
							(size 0.762 0.762)
						)
						(justify left)
					)
				)
				(text "100k PU to 1.8V Input "
					(at 26.67 -25.4 0)
					(effects
						(font
							(size 0.762 0.762)
						)
						(justify right)
					)
				)
				(text "1k PU to 1.8V Output "
					(at 26.67 -33.02 0)
					(effects
						(font
							(size 0.762 0.762)
						)
						(justify right)
					)
				)
				(text "5.0V to 20V"
					(at 9.525 -16.51 900)
					(effects
						(font
							(size 1.27 1.27)
						)
					)
				)
				(text "5V w/ PD Analog Input"
					(at 29.21 -17.78 0)
					(effects
						(font
							(size 0.762 0.762)
						)
						(justify right)
					)
				)
				(text "Floating"
					(at 22.86 -2.54 0)
					(effects
						(font
							(size 0.762 0.762)
						)
						(justify right)
					)
				)
				(text "PU to 1.8V Bidir "
					(at 28.575 -20.32 0)
					(effects
						(font
							(size 0.762 0.762)
						)
						(justify right)
					)
				)
				(text "PU to 1.8V Input"
					(at 21.59 -38.1 0)
					(effects
						(font
							(size 0.762 0.762)
						)
						(justify right)
					)
				)
				(text "PU to VDD_IN Output"
					(at 23.495 -15.24 0)
					(effects
						(font
							(size 0.762 0.762)
						)
						(justify right)
					)
				)
				(pin passive line
					(at -5.08 -48.26 0)
					(length 5.08)
					(name "GND"
						(effects
							(font
								(size 1.27 1.27)
							)
						)
					)
					(number "1"
						(effects
							(font
								(size 1.27 1.27)
							)
						)
					)
				)
				(pin passive line
					(at -5.08 -124.46 0)
					(length 5.08)
					(name "GND"
						(effects
							(font
								(size 1.27 1.27)
							)
						)
					)
					(number "102"
						(effects
							(font
								(size 1.27 1.27)
							)
						)
					)
				)
				(pin passive line
					(at -5.08 -127 0)
					(length 5.08)
					(name "GND"
						(effects
							(font
								(size 1.27 1.27)
							)
						)
					)
					(number "107"
						(effects
							(font
								(size 1.27 1.27)
							)
						)
					)
				)
				(pin passive line
					(at -5.08 -129.54 0)
					(length 5.08)
					(name "GND"
						(effects
							(font
								(size 1.27 1.27)
							)
						)
					)
					(number "113"
						(effects
							(font
								(size 1.27 1.27)
							)
						)
					)
				)
				(pin passive line
					(at 45.72 -116.84 180)
					(length 5.08)
					(name "GND"
						(effects
							(font
								(size 1.27 1.27)
							)
						)
					)
					(number "119"
						(effects
							(font
								(size 1.27 1.27)
							)
						)
					)
				)
				(pin passive line
					(at 45.72 -119.38 180)
					(length 5.08)
					(name "GND"
						(effects
							(font
								(size 1.27 1.27)
							)
						)
					)
					(number "125"
						(effects
							(font
								(size 1.27 1.27)
							)
						)
					)
				)
				(pin passive line
					(at 45.72 -121.92 180)
					(length 5.08)
					(name "GND"
						(effects
							(font
								(size 1.27 1.27)
							)
						)
					)
					(number "129"
						(effects
							(font
								(size 1.27 1.27)
							)
						)
					)
				)
				(pin passive line
					(at -5.08 -58.42 0)
					(length 5.08)
					(name "GND"
						(effects
							(font
								(size 1.27 1.27)
							)
						)
					)
					(number "13"
						(effects
							(font
								(size 1.27 1.27)
							)
						)
					)
				)
				(pin passive line
					(at 45.72 -124.46 180)
					(length 5.08)
					(name "GND"
						(effects
							(font
								(size 1.27 1.27)
							)
						)
					)
					(number "132"
						(effects
							(font
								(size 1.27 1.27)
							)
						)
					)
				)
				(pin passive line
					(at 45.72 -127 180)
					(length 5.08)
					(name "GND"
						(effects
							(font
								(size 1.27 1.27)
							)
						)
					)
					(number "135"
						(effects
							(font
								(size 1.27 1.27)
							)
						)
					)
				)
				(pin passive line
					(at 45.72 -48.26 180)
					(length 5.08)
					(name "GND"
						(effects
							(font
								(size 1.27 1.27)
							)
						)
					)
					(number "138"
						(effects
							(font
								(size 1.27 1.27)
							)
						)
					)
				)
				(pin passive line
					(at -5.08 -60.96 0)
					(length 5.08)
					(name "GND"
						(effects
							(font
								(size 1.27 1.27)
							)
						)
					)
					(number "14"
						(effects
							(font
								(size 1.27 1.27)
							)
						)
					)
				)
				(pin passive line
					(at 45.72 -50.8 180)
					(length 5.08)
					(name "GND"
						(effects
							(font
								(size 1.27 1.27)
							)
						)
					)
					(number "141"
						(effects
							(font
								(size 1.27 1.27)
							)
						)
					)
				)
				(pin passive line
					(at 45.72 -53.34 180)
					(length 5.08)
					(name "GND"
						(effects
							(font
								(size 1.27 1.27)
							)
						)
					)
					(number "144"
						(effects
							(font
								(size 1.27 1.27)
							)
						)
					)
				)
				(pin passive line
					(at 45.72 -55.88 180)
					(length 5.08)
					(name "GND"
						(effects
							(font
								(size 1.27 1.27)
							)
						)
					)
					(number "146"
						(effects
							(font
								(size 1.27 1.27)
							)
						)
					)
				)
				(pin passive line
					(at 45.72 -58.42 180)
					(length 5.08)
					(name "GND"
						(effects
							(font
								(size 1.27 1.27)
							)
						)
					)
					(number "147"
						(effects
							(font
								(size 1.27 1.27)
							)
						)
					)
				)
				(pin passive line
					(at 45.72 -60.96 180)
					(length 5.08)
					(name "GND"
						(effects
							(font
								(size 1.27 1.27)
							)
						)
					)
					(number "152"
						(effects
							(font
								(size 1.27 1.27)
							)
						)
					)
				)
				(pin passive line
					(at 45.72 -63.5 180)
					(length 5.08)
					(name "GND"
						(effects
							(font
								(size 1.27 1.27)
							)
						)
					)
					(number "153"
						(effects
							(font
								(size 1.27 1.27)
							)
						)
					)
				)
				(pin passive line
					(at 45.72 -66.04 180)
					(length 5.08)
					(name "GND"
						(effects
							(font
								(size 1.27 1.27)
							)
						)
					)
					(number "158"
						(effects
							(font
								(size 1.27 1.27)
							)
						)
					)
				)
				(pin passive line
					(at 45.72 -68.58 180)
					(length 5.08)
					(name "GND"
						(effects
							(font
								(size 1.27 1.27)
							)
						)
					)
					(number "159"
						(effects
							(font
								(size 1.27 1.27)
							)
						)
					)
				)
				(pin passive line
					(at 45.72 -71.12 180)
					(length 5.08)
					(name "GND"
						(effects
							(font
								(size 1.27 1.27)
							)
						)
					)
					(number "164"
						(effects
							(font
								(size 1.27 1.27)
							)
						)
					)
				)
				(pin passive line
					(at 45.72 -73.66 180)
					(length 5.08)
					(name "GND"
						(effects
							(font
								(size 1.27 1.27)
							)
						)
					)
					(number "165"
						(effects
							(font
								(size 1.27 1.27)
							)
						)
					)
				)
				(pin passive line
					(at 45.72 -76.2 180)
					(length 5.08)
					(name "GND"
						(effects
							(font
								(size 1.27 1.27)
							)
						)
					)
					(number "170"
						(effects
							(font
								(size 1.27 1.27)
							)
						)
					)
				)
				(pin passive line
					(at 45.72 -78.74 180)
					(length 5.08)
					(name "GND"
						(effects
							(font
								(size 1.27 1.27)
							)
						)
					)
					(number "171"
						(effects
							(font
								(size 1.27 1.27)
							)
						)
					)
				)
				(pin passive line
					(at 45.72 -81.28 180)
					(length 5.08)
					(name "GND"
						(effects
							(font
								(size 1.27 1.27)
							)
						)
					)
					(number "176"
						(effects
							(font
								(size 1.27 1.27)
							)
						)
					)
				)
				(pin passive line
					(at 45.72 -83.82 180)
					(length 5.08)
					(name "GND"
						(effects
							(font
								(size 1.27 1.27)
							)
						)
					)
					(number "177"
						(effects
							(font
								(size 1.27 1.27)
							)
						)
					)
				)
				(pin passive line
					(at 45.72 -27.94 180)
					(length 5.08)
					(name "MOD_SLEEP*"
						(effects
							(font
								(size 1.27 1.27)
							)
						)
					)
					(number "178"
						(effects
							(font
								(size 1.27 1.27)
							)
						)
					)
				)
				(pin passive line
					(at -5.08 -63.5 0)
					(length 5.08)
					(name "GND"
						(effects
							(font
								(size 1.27 1.27)
							)
						)
					)
					(number "19"
						(effects
							(font
								(size 1.27 1.27)
							)
						)
					)
				)
				(pin passive line
					(at -5.08 -50.8 0)
					(length 5.08)
					(name "GND"
						(effects
							(font
								(size 1.27 1.27)
							)
						)
					)
					(number "2"
						(effects
							(font
								(size 1.27 1.27)
							)
						)
					)
				)
				(pin passive line
					(at -5.08 -66.04 0)
					(length 5.08)
					(name "GND"
						(effects
							(font
								(size 1.27 1.27)
							)
						)
					)
					(number "20"
						(effects
							(font
								(size 1.27 1.27)
							)
						)
					)
				)
				(pin passive line
					(at 45.72 -86.36 180)
					(length 5.08)
					(name "GND"
						(effects
							(font
								(size 1.27 1.27)
							)
						)
					)
					(number "200"
						(effects
							(font
								(size 1.27 1.27)
							)
						)
					)
				)
				(pin passive line
					(at 45.72 -88.9 180)
					(length 5.08)
					(name "GND"
						(effects
							(font
								(size 1.27 1.27)
							)
						)
					)
					(number "201"
						(effects
							(font
								(size 1.27 1.27)
							)
						)
					)
				)
				(pin passive line
					(at 45.72 -7.62 180)
					(length 5.08)
					(name "Fan_Tach/GPIO08"
						(effects
							(font
								(size 1.27 1.27)
							)
						)
					)
					(number "208"
						(effects
							(font
								(size 1.27 1.27)
							)
						)
					)
					(alternate "GPIO08" passive line)
					(alternate "GPIO08(Fan_Tach)" passive line)
				)
				(pin passive line
					(at 45.72 -33.02 180)
					(length 5.08)
					(name "CLK_32K_OUT"
						(effects
							(font
								(size 1.27 1.27)
							)
						)
					)
					(number "210"
						(effects
							(font
								(size 1.27 1.27)
							)
						)
					)
				)
				(pin passive line
					(at 45.72 -38.1 180)
					(length 5.08)
					(name "FORCE_RECOVERY*"
						(effects
							(font
								(size 1.27 1.27)
							)
						)
					)
					(number "214"
						(effects
							(font
								(size 1.27 1.27)
							)
						)
					)
				)
				(pin passive line
					(at 45.72 -2.54 180)
					(length 5.08)
					(name "GND(MODULE_ID)"
						(effects
							(font
								(size 1.27 1.27)
							)
						)
					)
					(number "217"
						(effects
							(font
								(size 1.27 1.27)
							)
						)
					)
				)
				(pin passive line
					(at 45.72 -10.16 180)
					(length 5.08)
					(name "GPIO14/PWM"
						(effects
							(font
								(size 1.27 1.27)
							)
						)
					)
					(number "230"
						(effects
							(font
								(size 1.27 1.27)
							)
						)
					)
					(alternate "GPIO14" passive line)
					(alternate "GPIO14(PWM)" passive line)
				)
				(pin passive line
					(at 45.72 -91.44 180)
					(length 5.08)
					(name "GND"
						(effects
							(font
								(size 1.27 1.27)
							)
						)
					)
					(number "231"
						(effects
							(font
								(size 1.27 1.27)
							)
						)
					)
				)
				(pin passive line
					(at 45.72 -15.24 180)
					(length 5.08)
					(name "SHUTDOWN_REQ*"
						(effects
							(font
								(size 1.27 1.27)
							)
						)
					)
					(number "233"
						(effects
							(font
								(size 1.27 1.27)
							)
						)
					)
				)
				(pin passive line
					(at -5.08 -43.18 0)
					(length 5.08)
					(name "PMIC_BBAT"
						(effects
							(font
								(size 1.27 1.27)
							)
						)
					)
					(number "235"
						(effects
							(font
								(size 1.27 1.27)
							)
						)
					)
				)
				(pin passive line
					(at 45.72 -17.78 180)
					(length 5.08)
					(name "POWER_EN"
						(effects
							(font
								(size 1.27 1.27)
							)
						)
					)
					(number "237"
						(effects
							(font
								(size 1.27 1.27)
							)
						)
					)
				)
				(pin passive line
					(at 45.72 -20.32 180)
					(length 5.08)
					(name "SYS_RESET*"
						(effects
							(font
								(size 1.27 1.27)
							)
						)
					)
					(number "239"
						(effects
							(font
								(size 1.27 1.27)
							)
						)
					)
				)
				(pin passive line
					(at 45.72 -25.4 180)
					(length 5.08)
					(name "SLEEP/WAKE*"
						(effects
							(font
								(size 1.27 1.27)
							)
						)
					)
					(number "240"
						(effects
							(font
								(size 1.27 1.27)
							)
						)
					)
				)
				(pin passive line
					(at 45.72 -93.98 180)
					(length 5.08)
					(name "GND"
						(effects
							(font
								(size 1.27 1.27)
							)
						)
					)
					(number "241"
						(effects
							(font
								(size 1.27 1.27)
							)
						)
					)
				)
				(pin passive line
					(at 45.72 -96.52 180)
					(length 5.08)
					(name "GND"
						(effects
							(font
								(size 1.27 1.27)
							)
						)
					)
					(number "242"
						(effects
							(font
								(size 1.27 1.27)
							)
						)
					)
				)
				(pin passive line
					(at 45.72 -99.06 180)
					(length 5.08)
					(name "GND"
						(effects
							(font
								(size 1.27 1.27)
							)
						)
					)
					(number "243"
						(effects
							(font
								(size 1.27 1.27)
							)
						)
					)
				)
				(pin passive line
					(at 45.72 -101.6 180)
					(length 5.08)
					(name "GND"
						(effects
							(font
								(size 1.27 1.27)
							)
						)
					)
					(number "244"
						(effects
							(font
								(size 1.27 1.27)
							)
						)
					)
				)
				(pin passive line
					(at 45.72 -104.14 180)
					(length 5.08)
					(name "GND"
						(effects
							(font
								(size 1.27 1.27)
							)
						)
					)
					(number "245"
						(effects
							(font
								(size 1.27 1.27)
							)
						)
					)
				)
				(pin passive line
					(at 45.72 -106.68 180)
					(length 5.08)
					(name "GND"
						(effects
							(font
								(size 1.27 1.27)
							)
						)
					)
					(number "246"
						(effects
							(font
								(size 1.27 1.27)
							)
						)
					)
				)
				(pin passive line
					(at 45.72 -109.22 180)
					(length 5.08)
					(name "GND"
						(effects
							(font
								(size 1.27 1.27)
							)
						)
					)
					(number "247"
						(effects
							(font
								(size 1.27 1.27)
							)
						)
					)
				)
				(pin passive line
					(at 45.72 -111.76 180)
					(length 5.08)
					(name "GND"
						(effects
							(font
								(size 1.27 1.27)
							)
						)
					)
					(number "248"
						(effects
							(font
								(size 1.27 1.27)
							)
						)
					)
				)
				(pin passive line
					(at 45.72 -114.3 180)
					(length 5.08)
					(name "GND"
						(effects
							(font
								(size 1.27 1.27)
							)
						)
					)
					(number "249"
						(effects
							(font
								(size 1.27 1.27)
							)
						)
					)
				)
				(pin passive line
					(at -5.08 -68.58 0)
					(length 5.08)
					(name "GND"
						(effects
							(font
								(size 1.27 1.27)
							)
						)
					)
					(number "25"
						(effects
							(font
								(size 1.27 1.27)
							)
						)
					)
				)
				(pin passive line
					(at 45.72 -129.54 180)
					(length 5.08)
					(name "GND"
						(effects
							(font
								(size 1.27 1.27)
							)
						)
					)
					(number "250"
						(effects
							(font
								(size 1.27 1.27)
							)
						)
					)
				)
				(pin passive line
					(at -5.08 -5.08 0)
					(length 5.08)
					(name "VDD_IN"
						(effects
							(font
								(size 1.27 1.27)
							)
						)
					)
					(number "251"
						(effects
							(font
								(size 1.27 1.27)
							)
						)
					)
				)
				(pin passive line
					(at -5.08 -7.62 0)
					(length 5.08)
					(name "VDD_IN"
						(effects
							(font
								(size 1.27 1.27)
							)
						)
					)
					(number "252"
						(effects
							(font
								(size 1.27 1.27)
							)
						)
					)
				)
				(pin passive line
					(at -5.08 -10.16 0)
					(length 5.08)
					(name "VDD_IN"
						(effects
							(font
								(size 1.27 1.27)
							)
						)
					)
					(number "253"
						(effects
							(font
								(size 1.27 1.27)
							)
						)
					)
				)
				(pin passive line
					(at -5.08 -12.7 0)
					(length 5.08)
					(name "VDD_IN"
						(effects
							(font
								(size 1.27 1.27)
							)
						)
					)
					(number "254"
						(effects
							(font
								(size 1.27 1.27)
							)
						)
					)
				)
				(pin passive line
					(at -5.08 -15.24 0)
					(length 5.08)
					(name "VDD_IN"
						(effects
							(font
								(size 1.27 1.27)
							)
						)
					)
					(number "255"
						(effects
							(font
								(size 1.27 1.27)
							)
						)
					)
				)
				(pin passive line
					(at -5.08 -17.78 0)
					(length 5.08)
					(name "VDD_IN"
						(effects
							(font
								(size 1.27 1.27)
							)
						)
					)
					(number "256"
						(effects
							(font
								(size 1.27 1.27)
							)
						)
					)
				)
				(pin passive line
					(at -5.08 -20.32 0)
					(length 5.08)
					(name "VDD_IN"
						(effects
							(font
								(size 1.27 1.27)
							)
						)
					)
					(number "257"
						(effects
							(font
								(size 1.27 1.27)
							)
						)
					)
				)
				(pin passive line
					(at -5.08 -22.86 0)
					(length 5.08)
					(name "VDD_IN"
						(effects
							(font
								(size 1.27 1.27)
							)
						)
					)
					(number "258"
						(effects
							(font
								(size 1.27 1.27)
							)
						)
					)
				)
				(pin passive line
					(at -5.08 -25.4 0)
					(length 5.08)
					(name "VDD_IN"
						(effects
							(font
								(size 1.27 1.27)
							)
						)
					)
					(number "259"
						(effects
							(font
								(size 1.27 1.27)
							)
						)
					)
				)
				(pin passive line
					(at -5.08 -71.12 0)
					(length 5.08)
					(name "GND"
						(effects
							(font
								(size 1.27 1.27)
							)
						)
					)
					(number "26"
						(effects
							(font
								(size 1.27 1.27)
							)
						)
					)
				)
				(pin passive line
					(at -5.08 -27.94 0)
					(length 5.08)
					(name "VDD_IN"
						(effects
							(font
								(size 1.27 1.27)
							)
						)
					)
					(number "260"
						(effects
							(font
								(size 1.27 1.27)
							)
						)
					)
				)
				(pin no_connect line
					(at 45.72 -45.72 180)
					(length 5.08)
					(name "MP"
						(effects
							(font
								(size 1.27 1.27)
							)
						)
					)
					(number "261"
						(effects
							(font
								(size 1.27 1.27)
							)
						)
					)
				)
				(pin no_connect line
					(at 45.72 -43.18 180)
					(length 5.08)
					(name "MP"
						(effects
							(font
								(size 1.27 1.27)
							)
						)
					)
					(number "262"
						(effects
							(font
								(size 1.27 1.27)
							)
						)
					)
				)
				(pin passive line
					(at -5.08 -73.66 0)
					(length 5.08)
					(name "GND"
						(effects
							(font
								(size 1.27 1.27)
							)
						)
					)
					(number "31"
						(effects
							(font
								(size 1.27 1.27)
							)
						)
					)
				)
				(pin passive line
					(at -5.08 -76.2 0)
					(length 5.08)
					(name "GND"
						(effects
							(font
								(size 1.27 1.27)
							)
						)
					)
					(number "32"
						(effects
							(font
								(size 1.27 1.27)
							)
						)
					)
				)
				(pin passive line
					(at -5.08 -78.74 0)
					(length 5.08)
					(name "GND"
						(effects
							(font
								(size 1.27 1.27)
							)
						)
					)
					(number "37"
						(effects
							(font
								(size 1.27 1.27)
							)
						)
					)
				)
				(pin passive line
					(at -5.08 -81.28 0)
					(length 5.08)
					(name "GND"
						(effects
							(font
								(size 1.27 1.27)
							)
						)
					)
					(number "38"
						(effects
							(font
								(size 1.27 1.27)
							)
						)
					)
				)
				(pin passive line
					(at -5.08 -83.82 0)
					(length 5.08)
					(name "GND"
						(effects
							(font
								(size 1.27 1.27)
							)
						)
					)
					(number "43"
						(effects
							(font
								(size 1.27 1.27)
							)
						)
					)
				)
				(pin passive line
					(at -5.08 -86.36 0)
					(length 5.08)
					(name "GND"
						(effects
							(font
								(size 1.27 1.27)
							)
						)
					)
					(number "44"
						(effects
							(font
								(size 1.27 1.27)
							)
						)
					)
				)
				(pin passive line
					(at -5.08 -88.9 0)
					(length 5.08)
					(name "GND"
						(effects
							(font
								(size 1.27 1.27)
							)
						)
					)
					(number "49"
						(effects
							(font
								(size 1.27 1.27)
							)
						)
					)
				)
				(pin passive line
					(at -5.08 -91.44 0)
					(length 5.08)
					(name "GND"
						(effects
							(font
								(size 1.27 1.27)
							)
						)
					)
					(number "50"
						(effects
							(font
								(size 1.27 1.27)
							)
						)
					)
				)
				(pin passive line
					(at -5.08 -93.98 0)
					(length 5.08)
					(name "GND"
						(effects
							(font
								(size 1.27 1.27)
							)
						)
					)
					(number "55"
						(effects
							(font
								(size 1.27 1.27)
							)
						)
					)
				)
				(pin passive line
					(at -5.08 -96.52 0)
					(length 5.08)
					(name "GND"
						(effects
							(font
								(size 1.27 1.27)
							)
						)
					)
					(number "56"
						(effects
							(font
								(size 1.27 1.27)
							)
						)
					)
				)
				(pin passive line
					(at -5.08 -99.06 0)
					(length 5.08)
					(name "GND"
						(effects
							(font
								(size 1.27 1.27)
							)
						)
					)
					(number "61"
						(effects
							(font
								(size 1.27 1.27)
							)
						)
					)
				)
				(pin passive line
					(at -5.08 -101.6 0)
					(length 5.08)
					(name "GND"
						(effects
							(font
								(size 1.27 1.27)
							)
						)
					)
					(number "62"
						(effects
							(font
								(size 1.27 1.27)
							)
						)
					)
				)
				(pin passive line
					(at -5.08 -104.14 0)
					(length 5.08)
					(name "GND"
						(effects
							(font
								(size 1.27 1.27)
							)
						)
					)
					(number "67"
						(effects
							(font
								(size 1.27 1.27)
							)
						)
					)
				)
				(pin passive line
					(at -5.08 -106.68 0)
					(length 5.08)
					(name "GND"
						(effects
							(font
								(size 1.27 1.27)
							)
						)
					)
					(number "68"
						(effects
							(font
								(size 1.27 1.27)
							)
						)
					)
				)
				(pin passive line
					(at -5.08 -53.34 0)
					(length 5.08)
					(name "GND"
						(effects
							(font
								(size 1.27 1.27)
							)
						)
					)
					(number "7"
						(effects
							(font
								(size 1.27 1.27)
							)
						)
					)
				)
				(pin passive line
					(at -5.08 -109.22 0)
					(length 5.08)
					(name "GND"
						(effects
							(font
								(size 1.27 1.27)
							)
						)
					)
					(number "73"
						(effects
							(font
								(size 1.27 1.27)
							)
						)
					)
				)
				(pin passive line
					(at -5.08 -111.76 0)
					(length 5.08)
					(name "GND"
						(effects
							(font
								(size 1.27 1.27)
							)
						)
					)
					(number "74"
						(effects
							(font
								(size 1.27 1.27)
							)
						)
					)
				)
				(pin passive line
					(at -5.08 -114.3 0)
					(length 5.08)
					(name "GND"
						(effects
							(font
								(size 1.27 1.27)
							)
						)
					)
					(number "79"
						(effects
							(font
								(size 1.27 1.27)
							)
						)
					)
				)
				(pin passive line
					(at -5.08 -55.88 0)
					(length 5.08)
					(name "GND"
						(effects
							(font
								(size 1.27 1.27)
							)
						)
					)
					(number "8"
						(effects
							(font
								(size 1.27 1.27)
							)
						)
					)
				)
				(pin passive line
					(at -5.08 -116.84 0)
					(length 5.08)
					(name "GND"
						(effects
							(font
								(size 1.27 1.27)
							)
						)
					)
					(number "80"
						(effects
							(font
								(size 1.27 1.27)
							)
						)
					)
				)
				(pin passive line
					(at -5.08 -119.38 0)
					(length 5.08)
					(name "GND"
						(effects
							(font
								(size 1.27 1.27)
							)
						)
					)
					(number "85"
						(effects
							(font
								(size 1.27 1.27)
							)
						)
					)
				)
				(pin passive line
					(at -5.08 -121.92 0)
					(length 5.08)
					(name "GND"
						(effects
							(font
								(size 1.27 1.27)
							)
						)
					)
					(number "86"
						(effects
							(font
								(size 1.27 1.27)
							)
						)
					)
				)
			)
			(symbol "Jetson-Orin-9.2H-socket_1_2_1"
				(polyline
					(pts
						(xy 0 -93.98) (xy 31.75 -93.98)
					)
					(stroke
						(width 0)
						(type default)
					)
					(fill
						(type none)
					)
				)
				(polyline
					(pts
						(xy 14.605 -88.265) (xy 14.605 -92.075)
					)
					(stroke
						(width 0)
						(type default)
					)
					(fill
						(type none)
					)
				)
				(polyline
					(pts
						(xy 14.605 -75.565) (xy 14.605 -84.455)
					)
					(stroke
						(width 0)
						(type default)
					)
					(fill
						(type none)
					)
				)
				(polyline
					(pts
						(xy 14.605 -4.445) (xy 14.605 -71.755)
					)
					(stroke
						(width 0)
						(type default)
					)
					(fill
						(type none)
					)
				)
				(rectangle
					(start 0 0)
					(end 31.75 -114.3)
					(stroke
						(width 0.254)
						(type default)
					)
					(fill
						(type background)
					)
				)
				(arc
					(start 13.97 -92.71)
					(mid 14.4198 -92.5248)
					(end 14.605 -92.075)
					(stroke
						(width 0)
						(type default)
					)
					(fill
						(type none)
					)
				)
				(arc
					(start 13.97 -85.09)
					(mid 14.4198 -84.9048)
					(end 14.605 -84.455)
					(stroke
						(width 0)
						(type default)
					)
					(fill
						(type none)
					)
				)
				(arc
					(start 13.97 -72.39)
					(mid 14.4198 -72.2048)
					(end 14.605 -71.755)
					(stroke
						(width 0)
						(type default)
					)
					(fill
						(type none)
					)
				)
				(arc
					(start 14.605 -88.265)
					(mid 14.419 -87.816)
					(end 13.97 -87.63)
					(stroke
						(width 0)
						(type default)
					)
					(fill
						(type none)
					)
				)
				(arc
					(start 14.605 -75.565)
					(mid 14.419 -75.116)
					(end 13.97 -74.93)
					(stroke
						(width 0)
						(type default)
					)
					(fill
						(type none)
					)
				)
				(arc
					(start 14.605 -4.445)
					(mid 14.419 -3.996)
					(end 13.97 -3.81)
					(stroke
						(width 0)
						(type default)
					)
					(fill
						(type none)
					)
				)
				(text "1.8V Bidir"
					(at 15.24 -80.01 0)
					(effects
						(font
							(size 1.27 1.27)
						)
						(justify left)
					)
				)
				(text "3.3V PU Bidir"
					(at 15.24 -90.17 0)
					(effects
						(font
							(size 1.27 1.27)
						)
						(justify left)
					)
				)
				(text "MIPI Input"
					(at 15.24 -38.1 0)
					(effects
						(font
							(size 1.27 1.27)
						)
						(justify left)
					)
				)
				(text "RSVD"
					(at 26.67 -95.25 0)
					(effects
						(font
							(size 1.27 1.27)
							(bold yes)
						)
					)
				)
				(pin passive line
					(at -5.08 -5.08 0)
					(length 5.08)
					(name "CSI0_CLK_N"
						(effects
							(font
								(size 1.27 1.27)
							)
						)
					)
					(number "10"
						(effects
							(font
								(size 1.27 1.27)
							)
						)
					)
				)
				(pin passive line
					(at -5.08 -25.4 0)
					(length 5.08)
					(name "CSI1_CLK_P"
						(effects
							(font
								(size 1.27 1.27)
							)
						)
					)
					(number "11"
						(effects
							(font
								(size 1.27 1.27)
							)
						)
					)
				)
				(pin passive line
					(at -5.08 -83.82 0)
					(length 5.08)
					(name "CAM0_PWDN"
						(effects
							(font
								(size 1.27 1.27)
							)
						)
					)
					(number "114"
						(effects
							(font
								(size 1.27 1.27)
							)
						)
					)
				)
				(pin passive line
					(at -5.08 -81.28 0)
					(length 5.08)
					(name "CAM0_MCLK"
						(effects
							(font
								(size 1.27 1.27)
							)
						)
					)
					(number "116"
						(effects
							(font
								(size 1.27 1.27)
							)
						)
					)
				)
				(pin passive line
					(at -5.08 -7.62 0)
					(length 5.08)
					(name "CSI0_CLK_P"
						(effects
							(font
								(size 1.27 1.27)
							)
						)
					)
					(number "12"
						(effects
							(font
								(size 1.27 1.27)
							)
						)
					)
				)
				(pin passive line
					(at -5.08 -78.74 0)
					(length 5.08)
					(name "CAM1_PWDN"
						(effects
							(font
								(size 1.27 1.27)
							)
						)
					)
					(number "120"
						(effects
							(font
								(size 1.27 1.27)
							)
						)
					)
				)
				(pin passive line
					(at -5.08 -76.2 0)
					(length 5.08)
					(name "CAM1_MCLK"
						(effects
							(font
								(size 1.27 1.27)
							)
						)
					)
					(number "122"
						(effects
							(font
								(size 1.27 1.27)
							)
						)
					)
				)
				(pin passive line
					(at -5.08 -33.02 0)
					(length 5.08)
					(name "CSI1_D1_N"
						(effects
							(font
								(size 1.27 1.27)
							)
						)
					)
					(number "15"
						(effects
							(font
								(size 1.27 1.27)
							)
						)
					)
				)
				(pin passive line
					(at -5.08 -15.24 0)
					(length 5.08)
					(name "CSI0_D1_N"
						(effects
							(font
								(size 1.27 1.27)
							)
						)
					)
					(number "16"
						(effects
							(font
								(size 1.27 1.27)
							)
						)
					)
				)
				(pin passive line
					(at -5.08 -35.56 0)
					(length 5.08)
					(name "CSI1_D1_P"
						(effects
							(font
								(size 1.27 1.27)
							)
						)
					)
					(number "17"
						(effects
							(font
								(size 1.27 1.27)
							)
						)
					)
				)
				(pin passive line
					(at -5.08 -17.78 0)
					(length 5.08)
					(name "CSI0_D1_P"
						(effects
							(font
								(size 1.27 1.27)
							)
						)
					)
					(number "18"
						(effects
							(font
								(size 1.27 1.27)
							)
						)
					)
				)
				(pin passive line
					(at -5.08 -63.5 0)
					(length 5.08)
					(name "CSI3_D0_N"
						(effects
							(font
								(size 1.27 1.27)
							)
						)
					)
					(number "21"
						(effects
							(font
								(size 1.27 1.27)
							)
						)
					)
				)
				(pin passive line
					(at -5.08 -88.9 0)
					(length 5.08)
					(name "CAM_I2C_SCL"
						(effects
							(font
								(size 1.27 1.27)
							)
						)
					)
					(number "213"
						(effects
							(font
								(size 1.27 1.27)
							)
						)
					)
				)
				(pin passive line
					(at -5.08 -91.44 0)
					(length 5.08)
					(name "CAM_I2C_SDA"
						(effects
							(font
								(size 1.27 1.27)
							)
						)
					)
					(number "215"
						(effects
							(font
								(size 1.27 1.27)
							)
						)
					)
				)
				(pin passive line
					(at -5.08 -45.72 0)
					(length 5.08)
					(name "CSI2_D0_N"
						(effects
							(font
								(size 1.27 1.27)
							)
						)
					)
					(number "22"
						(effects
							(font
								(size 1.27 1.27)
							)
						)
					)
				)
				(pin passive line
					(at -5.08 -66.04 0)
					(length 5.08)
					(name "CSI3_D0_P"
						(effects
							(font
								(size 1.27 1.27)
							)
						)
					)
					(number "23"
						(effects
							(font
								(size 1.27 1.27)
							)
						)
					)
				)
				(pin passive line
					(at -5.08 -48.26 0)
					(length 5.08)
					(name "CSI2_D0_P"
						(effects
							(font
								(size 1.27 1.27)
							)
						)
					)
					(number "24"
						(effects
							(font
								(size 1.27 1.27)
							)
						)
					)
				)
				(pin passive line
					(at -5.08 -58.42 0)
					(length 5.08)
					(name "CSI3_CLK_N"
						(effects
							(font
								(size 1.27 1.27)
							)
						)
					)
					(number "27"
						(effects
							(font
								(size 1.27 1.27)
							)
						)
					)
				)
				(pin passive line
					(at -5.08 -40.64 0)
					(length 5.08)
					(name "CSI2_CLK_N"
						(effects
							(font
								(size 1.27 1.27)
							)
						)
					)
					(number "28"
						(effects
							(font
								(size 1.27 1.27)
							)
						)
					)
				)
				(pin passive line
					(at -5.08 -60.96 0)
					(length 5.08)
					(name "CSI3_CLK_P"
						(effects
							(font
								(size 1.27 1.27)
							)
						)
					)
					(number "29"
						(effects
							(font
								(size 1.27 1.27)
							)
						)
					)
				)
				(pin passive line
					(at -5.08 -27.94 0)
					(length 5.08)
					(name "CSI1_D0_N"
						(effects
							(font
								(size 1.27 1.27)
							)
						)
					)
					(number "3"
						(effects
							(font
								(size 1.27 1.27)
							)
						)
					)
				)
				(pin passive line
					(at -5.08 -43.18 0)
					(length 5.08)
					(name "CSI2_CLK_P"
						(effects
							(font
								(size 1.27 1.27)
							)
						)
					)
					(number "30"
						(effects
							(font
								(size 1.27 1.27)
							)
						)
					)
				)
				(pin passive line
					(at -5.08 -68.58 0)
					(length 5.08)
					(name "CSI3_D1_N"
						(effects
							(font
								(size 1.27 1.27)
							)
						)
					)
					(number "33"
						(effects
							(font
								(size 1.27 1.27)
							)
						)
					)
				)
				(pin passive line
					(at -5.08 -50.8 0)
					(length 5.08)
					(name "CSI2_D1_N"
						(effects
							(font
								(size 1.27 1.27)
							)
						)
					)
					(number "34"
						(effects
							(font
								(size 1.27 1.27)
							)
						)
					)
				)
				(pin passive line
					(at -5.08 -71.12 0)
					(length 5.08)
					(name "CSI3_D1_P"
						(effects
							(font
								(size 1.27 1.27)
							)
						)
					)
					(number "35"
						(effects
							(font
								(size 1.27 1.27)
							)
						)
					)
				)
				(pin passive line
					(at -5.08 -53.34 0)
					(length 5.08)
					(name "CSI2_D1_P"
						(effects
							(font
								(size 1.27 1.27)
							)
						)
					)
					(number "36"
						(effects
							(font
								(size 1.27 1.27)
							)
						)
					)
				)
				(pin passive line
					(at -5.08 -10.16 0)
					(length 5.08)
					(name "CSI0_D0_N"
						(effects
							(font
								(size 1.27 1.27)
							)
						)
					)
					(number "4"
						(effects
							(font
								(size 1.27 1.27)
							)
						)
					)
				)
				(pin passive line
					(at -5.08 -30.48 0)
					(length 5.08)
					(name "CSI1_D0_P"
						(effects
							(font
								(size 1.27 1.27)
							)
						)
					)
					(number "5"
						(effects
							(font
								(size 1.27 1.27)
							)
						)
					)
				)
				(pin passive line
					(at -5.08 -12.7 0)
					(length 5.08)
					(name "CSI0_D0_P"
						(effects
							(font
								(size 1.27 1.27)
							)
						)
					)
					(number "6"
						(effects
							(font
								(size 1.27 1.27)
							)
						)
					)
				)
				(pin passive line
					(at -5.08 -96.52 0)
					(length 5.08)
					(name "DSI_D0_N"
						(effects
							(font
								(size 1.27 1.27)
							)
						)
					)
					(number "70"
						(effects
							(font
								(size 1.27 1.27)
							)
						)
					)
				)
				(pin passive line
					(at -5.08 -99.06 0)
					(length 5.08)
					(name "DSI_D0_P"
						(effects
							(font
								(size 1.27 1.27)
							)
						)
					)
					(number "72"
						(effects
							(font
								(size 1.27 1.27)
							)
						)
					)
				)
				(pin passive line
					(at -5.08 -101.6 0)
					(length 5.08)
					(name "DSI_CLK_N"
						(effects
							(font
								(size 1.27 1.27)
							)
						)
					)
					(number "76"
						(effects
							(font
								(size 1.27 1.27)
							)
						)
					)
				)
				(pin passive line
					(at -5.08 -104.14 0)
					(length 5.08)
					(name "DSI_CLK_P"
						(effects
							(font
								(size 1.27 1.27)
							)
						)
					)
					(number "78"
						(effects
							(font
								(size 1.27 1.27)
							)
						)
					)
				)
				(pin passive line
					(at -5.08 -106.68 0)
					(length 5.08)
					(name "DSI_D1_N"
						(effects
							(font
								(size 1.27 1.27)
							)
						)
					)
					(number "82"
						(effects
							(font
								(size 1.27 1.27)
							)
						)
					)
				)
				(pin passive line
					(at -5.08 -109.22 0)
					(length 5.08)
					(name "DSI_D1_P"
						(effects
							(font
								(size 1.27 1.27)
							)
						)
					)
					(number "84"
						(effects
							(font
								(size 1.27 1.27)
							)
						)
					)
				)
				(pin passive line
					(at -5.08 -22.86 0)
					(length 5.08)
					(name "CSI1_CLK_N"
						(effects
							(font
								(size 1.27 1.27)
							)
						)
					)
					(number "9"
						(effects
							(font
								(size 1.27 1.27)
							)
						)
					)
				)
			)
			(symbol "Jetson-Orin-9.2H-socket_1_3_1"
				(polyline
					(pts
						(xy 13.335 -116.2) (xy 13.335 -120.01)
					)
					(stroke
						(width 0)
						(type default)
					)
					(fill
						(type none)
					)
				)
				(polyline
					(pts
						(xy 13.335 -103.505) (xy 13.335 -112.395)
					)
					(stroke
						(width 0)
						(type default)
					)
					(fill
						(type none)
					)
				)
				(polyline
					(pts
						(xy 13.335 -90.805) (xy 13.335 -99.695)
					)
					(stroke
						(width 0)
						(type default)
					)
					(fill
						(type none)
					)
				)
				(polyline
					(pts
						(xy 13.335 -75.565) (xy 13.335 -87)
					)
					(stroke
						(width 0)
						(type default)
					)
					(fill
						(type none)
					)
				)
				(polyline
					(pts
						(xy 13.335 -60.32) (xy 13.335 -71.755)
					)
					(stroke
						(width 0)
						(type default)
					)
					(fill
						(type none)
					)
				)
				(polyline
					(pts
						(xy 13.335 -52.7) (xy 13.335 -56.51)
					)
					(stroke
						(width 0)
						(type default)
					)
					(fill
						(type none)
					)
				)
				(polyline
					(pts
						(xy 13.335 -45.085) (xy 13.335 -48.895)
					)
					(stroke
						(width 0)
						(type default)
					)
					(fill
						(type none)
					)
				)
				(polyline
					(pts
						(xy 13.335 -37.46) (xy 13.335 -41.27)
					)
					(stroke
						(width 0)
						(type default)
					)
					(fill
						(type none)
					)
				)
				(polyline
					(pts
						(xy 13.335 -29.845) (xy 13.335 -33.655)
					)
					(stroke
						(width 0)
						(type default)
					)
					(fill
						(type none)
					)
				)
				(polyline
					(pts
						(xy 13.335 -17.145) (xy 13.335 -26.035)
					)
					(stroke
						(width 0)
						(type default)
					)
					(fill
						(type none)
					)
				)
				(polyline
					(pts
						(xy 13.335 -4.44) (xy 13.335 -13.33)
					)
					(stroke
						(width 0)
						(type default)
					)
					(fill
						(type none)
					)
				)
				(rectangle
					(start 0 0)
					(end 31.75 -124.46)
					(stroke
						(width 0.254)
						(type default)
					)
					(fill
						(type background)
					)
				)
				(arc
					(start 12.7 -120.645)
					(mid 13.149 -120.459)
					(end 13.335 -120.01)
					(stroke
						(width 0)
						(type default)
					)
					(fill
						(type none)
					)
				)
				(arc
					(start 12.7 -113.03)
					(mid 13.1498 -112.8448)
					(end 13.335 -112.395)
					(stroke
						(width 0)
						(type default)
					)
					(fill
						(type none)
					)
				)
				(arc
					(start 12.7 -100.33)
					(mid 13.1498 -100.1448)
					(end 13.335 -99.695)
					(stroke
						(width 0)
						(type default)
					)
					(fill
						(type none)
					)
				)
				(arc
					(start 12.7 -87.63)
					(mid 13.1498 -87.4448)
					(end 13.335 -86.995)
					(stroke
						(width 0)
						(type default)
					)
					(fill
						(type none)
					)
				)
				(arc
					(start 12.7 -72.385)
					(mid 13.149 -72.199)
					(end 13.335 -71.75)
					(stroke
						(width 0)
						(type default)
					)
					(fill
						(type none)
					)
				)
				(arc
					(start 12.7 -57.145)
					(mid 13.149 -56.959)
					(end 13.335 -56.51)
					(stroke
						(width 0)
						(type default)
					)
					(fill
						(type none)
					)
				)
				(arc
					(start 12.7 -49.53)
					(mid 13.1498 -49.3448)
					(end 13.335 -48.895)
					(stroke
						(width 0)
						(type default)
					)
					(fill
						(type none)
					)
				)
				(arc
					(start 12.7 -41.905)
					(mid 13.149 -41.719)
					(end 13.335 -41.27)
					(stroke
						(width 0)
						(type default)
					)
					(fill
						(type none)
					)
				)
				(arc
					(start 12.7 -34.29)
					(mid 13.1498 -34.1048)
					(end 13.335 -33.655)
					(stroke
						(width 0)
						(type default)
					)
					(fill
						(type none)
					)
				)
				(arc
					(start 12.7 -26.67)
					(mid 13.1498 -26.4848)
					(end 13.335 -26.035)
					(stroke
						(width 0)
						(type default)
					)
					(fill
						(type none)
					)
				)
				(arc
					(start 12.7 -13.965)
					(mid 13.149 -13.779)
					(end 13.335 -13.33)
					(stroke
						(width 0)
						(type default)
					)
					(fill
						(type none)
					)
				)
				(arc
					(start 13.335 -116.2)
					(mid 13.149 -115.751)
					(end 12.7 -115.565)
					(stroke
						(width 0)
						(type default)
					)
					(fill
						(type none)
					)
				)
				(arc
					(start 13.335 -103.505)
					(mid 13.149 -103.056)
					(end 12.7 -102.87)
					(stroke
						(width 0)
						(type default)
					)
					(fill
						(type none)
					)
				)
				(arc
					(start 13.335 -90.805)
					(mid 13.149 -90.356)
					(end 12.7 -90.17)
					(stroke
						(width 0)
						(type default)
					)
					(fill
						(type none)
					)
				)
				(arc
					(start 13.335 -75.565)
					(mid 13.149 -75.116)
					(end 12.7 -74.93)
					(stroke
						(width 0)
						(type default)
					)
					(fill
						(type none)
					)
				)
				(arc
					(start 13.335 -60.32)
					(mid 13.149 -59.871)
					(end 12.7 -59.685)
					(stroke
						(width 0)
						(type default)
					)
					(fill
						(type none)
					)
				)
				(arc
					(start 13.335 -52.7)
					(mid 13.149 -52.251)
					(end 12.7 -52.065)
					(stroke
						(width 0)
						(type default)
					)
					(fill
						(type none)
					)
				)
				(arc
					(start 13.335 -45.085)
					(mid 13.149 -44.636)
					(end 12.7 -44.45)
					(stroke
						(width 0)
						(type default)
					)
					(fill
						(type none)
					)
				)
				(arc
					(start 13.335 -37.46)
					(mid 13.149 -37.011)
					(end 12.7 -36.825)
					(stroke
						(width 0)
						(type default)
					)
					(fill
						(type none)
					)
				)
				(arc
					(start 13.335 -29.845)
					(mid 13.149 -29.396)
					(end 12.7 -29.21)
					(stroke
						(width 0)
						(type default)
					)
					(fill
						(type none)
					)
				)
				(arc
					(start 13.335 -17.145)
					(mid 13.149 -16.696)
					(end 12.7 -16.51)
					(stroke
						(width 0)
						(type default)
					)
					(fill
						(type none)
					)
				)
				(arc
					(start 13.335 -4.44)
					(mid 13.149 -3.991)
					(end 12.7 -3.805)
					(stroke
						(width 0)
						(type default)
					)
					(fill
						(type none)
					)
				)
				(text "1.8V CMOS"
					(at 13.97 -107.95 0)
					(effects
						(font
							(size 1.27 1.27)
						)
						(justify left)
					)
				)
				(text "1.8V CMOS"
					(at 13.97 -95.25 0)
					(effects
						(font
							(size 1.27 1.27)
						)
						(justify left)
					)
				)
				(text "1.8V CMOS"
					(at 13.97 -81.285 0)
					(effects
						(font
							(size 1.27 1.27)
						)
						(justify left)
					)
				)
				(text "1.8V CMOS"
					(at 13.97 -66.04 0)
					(effects
						(font
							(size 1.27 1.27)
						)
						(justify left)
					)
				)
				(text "1.8V CMOS"
					(at 13.97 -31.75 0)
					(effects
						(font
							(size 1.27 1.27)
						)
						(justify left)
					)
				)
				(text "1.8V CMOS"
					(at 13.97 -21.59 0)
					(effects
						(font
							(size 1.27 1.27)
						)
						(justify left)
					)
				)
				(text "1.8V CMOS"
					(at 13.97 -8.885 0)
					(effects
						(font
							(size 1.27 1.27)
						)
						(justify left)
					)
				)
				(text "1.8V PU Bidir"
					(at 13.97 -54.605 0)
					(effects
						(font
							(size 1.27 1.27)
						)
						(justify left)
					)
				)
				(text "3.3V CMOS"
					(at 13.97 -118.105 0)
					(effects
						(font
							(size 1.27 1.27)
						)
						(justify left)
					)
				)
				(text "3.3V PU Bidir"
					(at 13.97 -46.99 0)
					(effects
						(font
							(size 1.27 1.27)
						)
						(justify left)
					)
				)
				(text "3.3V PU Bidir"
					(at 13.97 -39.365 0)
					(effects
						(font
							(size 1.27 1.27)
						)
						(justify left)
					)
				)
				(pin passive line
					(at -5.08 -12.7 0)
					(length 5.08)
					(name "UART0_RXD"
						(effects
							(font
								(size 1.27 1.27)
							)
						)
					)
					(number "101"
						(effects
							(font
								(size 1.27 1.27)
							)
						)
					)
				)
				(pin passive line
					(at -5.08 -5.08 0)
					(length 5.08)
					(name "UART0_RTS*"
						(effects
							(font
								(size 1.27 1.27)
							)
						)
					)
					(number "103"
						(effects
							(font
								(size 1.27 1.27)
							)
						)
					)
				)
				(pin passive line
					(at -5.08 -78.74 0)
					(length 5.08)
					(name "SPI1_MOSI"
						(effects
							(font
								(size 1.27 1.27)
							)
						)
					)
					(number "104"
						(effects
							(font
								(size 1.27 1.27)
							)
						)
					)
				)
				(pin passive line
					(at -5.08 -7.62 0)
					(length 5.08)
					(name "UART0_CTS*"
						(effects
							(font
								(size 1.27 1.27)
							)
						)
					)
					(number "105"
						(effects
							(font
								(size 1.27 1.27)
							)
						)
					)
				)
				(pin passive line
					(at -5.08 -76.2 0)
					(length 5.08)
					(name "SPI1_SCK"
						(effects
							(font
								(size 1.27 1.27)
							)
						)
					)
					(number "106"
						(effects
							(font
								(size 1.27 1.27)
							)
						)
					)
				)
				(pin passive line
					(at -5.08 -81.28 0)
					(length 5.08)
					(name "SPI1_MISO"
						(effects
							(font
								(size 1.27 1.27)
							)
						)
					)
					(number "108"
						(effects
							(font
								(size 1.27 1.27)
							)
						)
					)
				)
				(pin passive line
					(at -5.08 -83.82 0)
					(length 5.08)
					(name "SPI1_CS0*"
						(effects
							(font
								(size 1.27 1.27)
							)
						)
					)
					(number "110"
						(effects
							(font
								(size 1.27 1.27)
							)
						)
					)
				)
				(pin passive line
					(at -5.08 -86.36 0)
					(length 5.08)
					(name "SPI1_CS1*"
						(effects
							(font
								(size 1.27 1.27)
							)
						)
					)
					(number "112"
						(effects
							(font
								(size 1.27 1.27)
							)
						)
					)
				)
				(pin passive line
					(at -5.08 -116.84 0)
					(length 5.08)
					(name "CAN_RX"
						(effects
							(font
								(size 1.27 1.27)
							)
						)
					)
					(number "143"
						(effects
							(font
								(size 1.27 1.27)
							)
						)
					)
				)
				(pin passive line
					(at -5.08 -119.38 0)
					(length 5.08)
					(name "CAN_TX"
						(effects
							(font
								(size 1.27 1.27)
							)
						)
					)
					(number "145"
						(effects
							(font
								(size 1.27 1.27)
							)
						)
					)
				)
				(pin passive line
					(at -5.08 -38.1 0)
					(length 5.08)
					(name "I2C0_SCL"
						(effects
							(font
								(size 1.27 1.27)
							)
						)
					)
					(number "185"
						(effects
							(font
								(size 1.27 1.27)
							)
						)
					)
				)
				(pin passive line
					(at -5.08 -40.64 0)
					(length 5.08)
					(name "I2C0_SDA"
						(effects
							(font
								(size 1.27 1.27)
							)
						)
					)
					(number "187"
						(effects
							(font
								(size 1.27 1.27)
							)
						)
					)
				)
				(pin passive line
					(at -5.08 -45.72 0)
					(length 5.08)
					(name "I2C1_SCL"
						(effects
							(font
								(size 1.27 1.27)
							)
						)
					)
					(number "189"
						(effects
							(font
								(size 1.27 1.27)
							)
						)
					)
				)
				(pin passive line
					(at -5.08 -48.26 0)
					(length 5.08)
					(name "I2C1_SDA"
						(effects
							(font
								(size 1.27 1.27)
							)
						)
					)
					(number "191"
						(effects
							(font
								(size 1.27 1.27)
							)
						)
					)
				)
				(pin passive line
					(at -5.08 -93.98 0)
					(length 5.08)
					(name "I2S0_DOUT"
						(effects
							(font
								(size 1.27 1.27)
							)
						)
					)
					(number "193"
						(effects
							(font
								(size 1.27 1.27)
							)
						)
					)
				)
				(pin passive line
					(at -5.08 -96.52 0)
					(length 5.08)
					(name "I2S0_DIN"
						(effects
							(font
								(size 1.27 1.27)
							)
						)
					)
					(number "195"
						(effects
							(font
								(size 1.27 1.27)
							)
						)
					)
				)
				(pin passive line
					(at -5.08 -99.06 0)
					(length 5.08)
					(name "I2S0_FS"
						(effects
							(font
								(size 1.27 1.27)
							)
						)
					)
					(number "197"
						(effects
							(font
								(size 1.27 1.27)
							)
						)
					)
				)
				(pin passive line
					(at -5.08 -91.44 0)
					(length 5.08)
					(name "I2S0_SCLK"
						(effects
							(font
								(size 1.27 1.27)
							)
						)
					)
					(number "199"
						(effects
							(font
								(size 1.27 1.27)
							)
						)
					)
				)
				(pin passive line
					(at -5.08 -22.86 0)
					(length 5.08)
					(name "UART1_TXD"
						(effects
							(font
								(size 1.27 1.27)
							)
						)
					)
					(number "203"
						(effects
							(font
								(size 1.27 1.27)
							)
						)
					)
				)
				(pin passive line
					(at -5.08 -25.4 0)
					(length 5.08)
					(name "UART1_RXD"
						(effects
							(font
								(size 1.27 1.27)
							)
						)
					)
					(number "205"
						(effects
							(font
								(size 1.27 1.27)
							)
						)
					)
				)
				(pin passive line
					(at -5.08 -17.78 0)
					(length 5.08)
					(name "UART1_RTS*"
						(effects
							(font
								(size 1.27 1.27)
							)
						)
					)
					(number "207"
						(effects
							(font
								(size 1.27 1.27)
							)
						)
					)
				)
				(pin passive line
					(at -5.08 -20.32 0)
					(length 5.08)
					(name "UART1_CTS*"
						(effects
							(font
								(size 1.27 1.27)
							)
						)
					)
					(number "209"
						(effects
							(font
								(size 1.27 1.27)
							)
						)
					)
				)
				(pin passive line
					(at -5.08 -106.68 0)
					(length 5.08)
					(name "I2S1_DOUT"
						(effects
							(font
								(size 1.27 1.27)
							)
						)
					)
					(number "220"
						(effects
							(font
								(size 1.27 1.27)
							)
						)
					)
				)
				(pin passive line
					(at -5.08 -109.22 0)
					(length 5.08)
					(name "I2S1_DIN"
						(effects
							(font
								(size 1.27 1.27)
							)
						)
					)
					(number "222"
						(effects
							(font
								(size 1.27 1.27)
							)
						)
					)
				)
				(pin passive line
					(at -5.08 -111.76 0)
					(length 5.08)
					(name "I2S1_FS"
						(effects
							(font
								(size 1.27 1.27)
							)
						)
					)
					(number "224"
						(effects
							(font
								(size 1.27 1.27)
							)
						)
					)
				)
				(pin passive line
					(at -5.08 -104.14 0)
					(length 5.08)
					(name "I2S1_SCLK"
						(effects
							(font
								(size 1.27 1.27)
							)
						)
					)
					(number "226"
						(effects
							(font
								(size 1.27 1.27)
							)
						)
					)
				)
				(pin passive line
					(at -5.08 -53.34 0)
					(length 5.08)
					(name "I2C2_SCL"
						(effects
							(font
								(size 1.27 1.27)
							)
						)
					)
					(number "232"
						(effects
							(font
								(size 1.27 1.27)
							)
						)
					)
				)
				(pin passive line
					(at -5.08 -55.88 0)
					(length 5.08)
					(name "I2C2_SDA"
						(effects
							(font
								(size 1.27 1.27)
							)
						)
					)
					(number "234"
						(effects
							(font
								(size 1.27 1.27)
							)
						)
					)
				)
				(pin passive line
					(at -5.08 -30.48 0)
					(length 5.08)
					(name "UART2_TXD"
						(effects
							(font
								(size 1.27 1.27)
							)
						)
					)
					(number "236"
						(effects
							(font
								(size 1.27 1.27)
							)
						)
					)
				)
				(pin passive line
					(at -5.08 -33.02 0)
					(length 5.08)
					(name "UART2_RXD"
						(effects
							(font
								(size 1.27 1.27)
							)
						)
					)
					(number "238"
						(effects
							(font
								(size 1.27 1.27)
							)
						)
					)
				)
				(pin passive line
					(at -5.08 -63.5 0)
					(length 5.08)
					(name "SPI0_MOSI"
						(effects
							(font
								(size 1.27 1.27)
							)
						)
					)
					(number "89"
						(effects
							(font
								(size 1.27 1.27)
							)
						)
					)
				)
				(pin passive line
					(at -5.08 -60.96 0)
					(length 5.08)
					(name "SPI0_SCK"
						(effects
							(font
								(size 1.27 1.27)
							)
						)
					)
					(number "91"
						(effects
							(font
								(size 1.27 1.27)
							)
						)
					)
				)
				(pin passive line
					(at -5.08 -66.04 0)
					(length 5.08)
					(name "SPI0_MISO"
						(effects
							(font
								(size 1.27 1.27)
							)
						)
					)
					(number "93"
						(effects
							(font
								(size 1.27 1.27)
							)
						)
					)
				)
				(pin passive line
					(at -5.08 -68.58 0)
					(length 5.08)
					(name "SPI0_CS0*"
						(effects
							(font
								(size 1.27 1.27)
							)
						)
					)
					(number "95"
						(effects
							(font
								(size 1.27 1.27)
							)
						)
					)
				)
				(pin passive line
					(at -5.08 -71.12 0)
					(length 5.08)
					(name "SPI0_CS1*"
						(effects
							(font
								(size 1.27 1.27)
							)
						)
					)
					(number "97"
						(effects
							(font
								(size 1.27 1.27)
							)
						)
					)
				)
				(pin passive line
					(at -5.08 -10.16 0)
					(length 5.08)
					(name "UART0_TXD"
						(effects
							(font
								(size 1.27 1.27)
							)
						)
					)
					(number "99"
						(effects
							(font
								(size 1.27 1.27)
							)
						)
					)
				)
			)
			(symbol "Jetson-Orin-9.2H-socket_1_4_1"
				(rectangle
					(start 0 0)
					(end 31.75 -71.12)
					(stroke
						(width 0.254)
						(type default)
					)
					(fill
						(type background)
					)
				)
				(arc
					(start 13.335 -6.35)
					(mid 13.521 -6.799)
					(end 13.97 -6.985)
					(stroke
						(width 0)
						(type default)
					)
					(fill
						(type none)
					)
				)
				(text "1.8V OD Bidir, 3.3V Tolerant"
					(at 13.97 -6.985 0)
					(effects
						(font
							(size 0.762 0.762)
						)
						(justify left)
					)
				)
				(pin passive line
					(at -5.08 -48.26 0)
					(length 5.08)
					(name "USB0_D_N"
						(effects
							(font
								(size 1.27 1.27)
							)
						)
					)
					(number "109"
						(effects
							(font
								(size 1.27 1.27)
							)
						)
					)
				)
				(pin passive line
					(at -5.08 -50.8 0)
					(length 5.08)
					(name "USB0_D_P"
						(effects
							(font
								(size 1.27 1.27)
							)
						)
					)
					(number "111"
						(effects
							(font
								(size 1.27 1.27)
							)
						)
					)
				)
				(pin passive line
					(at -5.08 -55.88 0)
					(length 5.08)
					(name "USB1_D_N"
						(effects
							(font
								(size 1.27 1.27)
							)
						)
					)
					(number "115"
						(effects
							(font
								(size 1.27 1.27)
							)
						)
					)
				)
				(pin passive line
					(at -5.08 -58.42 0)
					(length 5.08)
					(name "USB1_D_P"
						(effects
							(font
								(size 1.27 1.27)
							)
						)
					)
					(number "117"
						(effects
							(font
								(size 1.27 1.27)
							)
						)
					)
				)
				(pin passive line
					(at -5.08 -63.5 0)
					(length 5.08)
					(name "USB2_D_N"
						(effects
							(font
								(size 1.27 1.27)
							)
						)
					)
					(number "121"
						(effects
							(font
								(size 1.27 1.27)
							)
						)
					)
				)
				(pin passive line
					(at -5.08 -66.04 0)
					(length 5.08)
					(name "USB2_D_P"
						(effects
							(font
								(size 1.27 1.27)
							)
						)
					)
					(number "123"
						(effects
							(font
								(size 1.27 1.27)
							)
						)
					)
				)
				(pin passive line
					(at -5.08 -15.24 0)
					(length 5.08)
					(name "USBSS0_RX_N"
						(effects
							(font
								(size 1.27 1.27)
							)
						)
					)
					(number "161"
						(effects
							(font
								(size 1.27 1.27)
							)
						)
					)
				)
				(pin passive line
					(at -5.08 -17.78 0)
					(length 5.08)
					(name "USBSS0_RX_P"
						(effects
							(font
								(size 1.27 1.27)
							)
						)
					)
					(number "163"
						(effects
							(font
								(size 1.27 1.27)
							)
						)
					)
				)
				(pin passive line
					(at -5.08 -10.16 0)
					(length 5.08)
					(name "USBSS0_TX_N"
						(effects
							(font
								(size 1.27 1.27)
							)
						)
					)
					(number "166"
						(effects
							(font
								(size 1.27 1.27)
							)
						)
					)
				)
				(pin passive line
					(at -5.08 -12.7 0)
					(length 5.08)
					(name "USBSS0_TX_P"
						(effects
							(font
								(size 1.27 1.27)
							)
						)
					)
					(number "168"
						(effects
							(font
								(size 1.27 1.27)
							)
						)
					)
				)
				(pin passive line
					(at -5.08 -27.94 0)
					(length 5.08)
					(name "USBSS1_RX_N"
						(effects
							(font
								(size 1.27 1.27)
							)
						)
					)
					(number "39"
						(effects
							(font
								(size 1.27 1.27)
							)
						)
					)
				)
				(pin passive line
					(at -5.08 -30.48 0)
					(length 5.08)
					(name "USBSS1_RX_P"
						(effects
							(font
								(size 1.27 1.27)
							)
						)
					)
					(number "41"
						(effects
							(font
								(size 1.27 1.27)
							)
						)
					)
				)
				(pin passive line
					(at -5.08 -22.86 0)
					(length 5.08)
					(name "USBSS1_TX_N"
						(effects
							(font
								(size 1.27 1.27)
							)
						)
					)
					(number "45"
						(effects
							(font
								(size 1.27 1.27)
							)
						)
					)
				)
				(pin passive line
					(at -5.08 -25.4 0)
					(length 5.08)
					(name "USBSS1_TX_P"
						(effects
							(font
								(size 1.27 1.27)
							)
						)
					)
					(number "47"
						(effects
							(font
								(size 1.27 1.27)
							)
						)
					)
				)
				(pin passive line
					(at -5.08 -40.64 0)
					(length 5.08)
					(name "USBSS2_RX_N"
						(effects
							(font
								(size 1.27 1.27)
							)
						)
					)
					(number "51"
						(effects
							(font
								(size 1.27 1.27)
							)
						)
					)
				)
				(pin passive line
					(at -5.08 -43.18 0)
					(length 5.08)
					(name "USBSS2_RX_P"
						(effects
							(font
								(size 1.27 1.27)
							)
						)
					)
					(number "53"
						(effects
							(font
								(size 1.27 1.27)
							)
						)
					)
				)
				(pin passive line
					(at -5.08 -35.56 0)
					(length 5.08)
					(name "USBSS2_TX_N"
						(effects
							(font
								(size 1.27 1.27)
							)
						)
					)
					(number "57"
						(effects
							(font
								(size 1.27 1.27)
							)
						)
					)
				)
				(pin passive line
					(at -5.08 -38.1 0)
					(length 5.08)
					(name "USBSS2_TX_P"
						(effects
							(font
								(size 1.27 1.27)
							)
						)
					)
					(number "59"
						(effects
							(font
								(size 1.27 1.27)
							)
						)
					)
				)
				(pin passive line
					(at -5.08 -5.08 0)
					(length 5.08)
					(name "USB_VBUS_EN0/GPIO00"
						(effects
							(font
								(size 1.27 1.27)
							)
						)
					)
					(number "87"
						(effects
							(font
								(size 1.27 1.27)
							)
						)
					)
					(alternate "GPIO00" passive line)
					(alternate "GPIO00(USB_VBUS_EN0)" passive line)
				)
			)
			(symbol "Jetson-Orin-9.2H-socket_1_5_1"
				(polyline
					(pts
						(xy 0 -48.26) (xy 31.75 -48.26)
					)
					(stroke
						(width 0)
						(type default)
					)
					(fill
						(type none)
					)
				)
				(rectangle
					(start 0 0)
					(end 31.75 -60.96)
					(stroke
						(width 0.254)
						(type default)
					)
					(fill
						(type background)
					)
				)
				(text "1.8V Input"
					(at 10.795 -7.62 0)
					(effects
						(font
							(size 0.762 0.762)
						)
						(justify left)
					)
				)
				(text "1k PU to 1.8V Bidir"
					(at 10.795 -5.08 0)
					(effects
						(font
							(size 0.762 0.762)
						)
						(justify left)
					)
				)
				(text "RSVD"
					(at 26.67 -49.53 0)
					(effects
						(font
							(size 1.27 1.27)
							(bold yes)
						)
					)
				)
				(pin passive line
					(at -5.08 -15.24 0)
					(length 5.08)
					(name "DP1_AUX_P"
						(effects
							(font
								(size 1.27 1.27)
							)
						)
					)
					(number "100"
						(effects
							(font
								(size 1.27 1.27)
							)
						)
					)
				)
				(pin passive line
					(at -5.08 -20.32 0)
					(length 5.08)
					(name "DP1_TXD0_N"
						(effects
							(font
								(size 1.27 1.27)
							)
						)
					)
					(number "63"
						(effects
							(font
								(size 1.27 1.27)
							)
						)
					)
				)
				(pin passive line
					(at -5.08 -22.86 0)
					(length 5.08)
					(name "DP1_TXD0_P"
						(effects
							(font
								(size 1.27 1.27)
							)
						)
					)
					(number "65"
						(effects
							(font
								(size 1.27 1.27)
							)
						)
					)
				)
				(pin passive line
					(at -5.08 -27.94 0)
					(length 5.08)
					(name "DP1_TXD1_N"
						(effects
							(font
								(size 1.27 1.27)
							)
						)
					)
					(number "69"
						(effects
							(font
								(size 1.27 1.27)
							)
						)
					)
				)
				(pin passive line
					(at -5.08 -30.48 0)
					(length 5.08)
					(name "DP1_TXD1_P"
						(effects
							(font
								(size 1.27 1.27)
							)
						)
					)
					(number "71"
						(effects
							(font
								(size 1.27 1.27)
							)
						)
					)
				)
				(pin passive line
					(at -5.08 -35.56 0)
					(length 5.08)
					(name "DP1_TXD2_N"
						(effects
							(font
								(size 1.27 1.27)
							)
						)
					)
					(number "75"
						(effects
							(font
								(size 1.27 1.27)
							)
						)
					)
				)
				(pin passive line
					(at -5.08 -38.1 0)
					(length 5.08)
					(name "DP1_TXD2_P"
						(effects
							(font
								(size 1.27 1.27)
							)
						)
					)
					(number "77"
						(effects
							(font
								(size 1.27 1.27)
							)
						)
					)
				)
				(pin passive line
					(at -5.08 -43.18 0)
					(length 5.08)
					(name "DP1_TXD3_N"
						(effects
							(font
								(size 1.27 1.27)
							)
						)
					)
					(number "81"
						(effects
							(font
								(size 1.27 1.27)
							)
						)
					)
				)
				(pin passive line
					(at -5.08 -45.72 0)
					(length 5.08)
					(name "DP1_TXD3_P"
						(effects
							(font
								(size 1.27 1.27)
							)
						)
					)
					(number "83"
						(effects
							(font
								(size 1.27 1.27)
							)
						)
					)
				)
				(pin passive line
					(at -5.08 -50.8 0)
					(length 5.08)
					(name "DP0_HPD"
						(effects
							(font
								(size 1.27 1.27)
							)
						)
					)
					(number "88"
						(effects
							(font
								(size 1.27 1.27)
							)
						)
					)
				)
				(pin passive line
					(at -5.08 -53.34 0)
					(length 5.08)
					(name "DP0_AUX_N"
						(effects
							(font
								(size 1.27 1.27)
							)
						)
					)
					(number "90"
						(effects
							(font
								(size 1.27 1.27)
							)
						)
					)
				)
				(pin passive line
					(at -5.08 -55.88 0)
					(length 5.08)
					(name "DP0_AUX_P"
						(effects
							(font
								(size 1.27 1.27)
							)
						)
					)
					(number "92"
						(effects
							(font
								(size 1.27 1.27)
							)
						)
					)
				)
				(pin passive line
					(at -5.08 -5.08 0)
					(length 5.08)
					(name "HDMI_CEC"
						(effects
							(font
								(size 1.27 1.27)
							)
						)
					)
					(number "94"
						(effects
							(font
								(size 1.27 1.27)
							)
						)
					)
				)
				(pin passive line
					(at -5.08 -7.62 0)
					(length 5.08)
					(name "DP1_HPD"
						(effects
							(font
								(size 1.27 1.27)
							)
						)
					)
					(number "96"
						(effects
							(font
								(size 1.27 1.27)
							)
						)
					)
				)
				(pin passive line
					(at -5.08 -12.7 0)
					(length 5.08)
					(name "DP1_AUX_N"
						(effects
							(font
								(size 1.27 1.27)
							)
						)
					)
					(number "98"
						(effects
							(font
								(size 1.27 1.27)
							)
						)
					)
				)
			)
			(symbol "Jetson-Orin-9.2H-socket_1_6_1"
				(rectangle
					(start 0 0)
					(end 31.75 -149.86)
					(stroke
						(width 0.254)
						(type default)
					)
					(fill
						(type background)
					)
				)
				(text "47k PU to 3.3V"
					(at 12.7 -5.08 0)
					(effects
						(font
							(size 0.762 0.762)
						)
						(justify left)
					)
				)
				(pin passive line
					(at -5.08 -27.94 0)
					(length 5.08)
					(name "PCIE0_RX0_N"
						(effects
							(font
								(size 1.27 1.27)
							)
						)
					)
					(number "131"
						(effects
							(font
								(size 1.27 1.27)
							)
						)
					)
				)
				(pin passive line
					(at -5.08 -30.48 0)
					(length 5.08)
					(name "PCIE0_RX0_P"
						(effects
							(font
								(size 1.27 1.27)
							)
						)
					)
					(number "133"
						(effects
							(font
								(size 1.27 1.27)
							)
						)
					)
				)
				(pin passive line
					(at -5.08 -22.86 0)
					(length 5.08)
					(name "PCIE0_TX0_N"
						(effects
							(font
								(size 1.27 1.27)
							)
						)
					)
					(number "134"
						(effects
							(font
								(size 1.27 1.27)
							)
						)
					)
				)
				(pin passive line
					(at -5.08 -25.4 0)
					(length 5.08)
					(name "PCIE0_TX0_P"
						(effects
							(font
								(size 1.27 1.27)
							)
						)
					)
					(number "136"
						(effects
							(font
								(size 1.27 1.27)
							)
						)
					)
				)
				(pin passive line
					(at -5.08 -40.64 0)
					(length 5.08)
					(name "PCIE0_RX1_N"
						(effects
							(font
								(size 1.27 1.27)
							)
						)
					)
					(number "137"
						(effects
							(font
								(size 1.27 1.27)
							)
						)
					)
				)
				(pin passive line
					(at -5.08 -43.18 0)
					(length 5.08)
					(name "PCIE0_RX1_P"
						(effects
							(font
								(size 1.27 1.27)
							)
						)
					)
					(number "139"
						(effects
							(font
								(size 1.27 1.27)
							)
						)
					)
				)
				(pin passive line
					(at -5.08 -35.56 0)
					(length 5.08)
					(name "PCIE0_TX1_N"
						(effects
							(font
								(size 1.27 1.27)
							)
						)
					)
					(number "140"
						(effects
							(font
								(size 1.27 1.27)
							)
						)
					)
				)
				(pin passive line
					(at -5.08 -38.1 0)
					(length 5.08)
					(name "PCIE0_TX1_P"
						(effects
							(font
								(size 1.27 1.27)
							)
						)
					)
					(number "142"
						(effects
							(font
								(size 1.27 1.27)
							)
						)
					)
				)
				(pin passive line
					(at -5.08 -48.26 0)
					(length 5.08)
					(name "PCIE0_TX2_N"
						(effects
							(font
								(size 1.27 1.27)
							)
						)
					)
					(number "148"
						(effects
							(font
								(size 1.27 1.27)
							)
						)
					)
				)
				(pin passive line
					(at -5.08 -53.34 0)
					(length 5.08)
					(name "PCIE0_RX2_N"
						(effects
							(font
								(size 1.27 1.27)
							)
						)
					)
					(number "149"
						(effects
							(font
								(size 1.27 1.27)
							)
						)
					)
				)
				(pin passive line
					(at -5.08 -50.8 0)
					(length 5.08)
					(name "PCIE0_TX2_P"
						(effects
							(font
								(size 1.27 1.27)
							)
						)
					)
					(number "150"
						(effects
							(font
								(size 1.27 1.27)
							)
						)
					)
				)
				(pin passive line
					(at -5.08 -55.88 0)
					(length 5.08)
					(name "PCIE0_RX2_P"
						(effects
							(font
								(size 1.27 1.27)
							)
						)
					)
					(number "151"
						(effects
							(font
								(size 1.27 1.27)
							)
						)
					)
				)
				(pin passive line
					(at -5.08 -60.96 0)
					(length 5.08)
					(name "PCIE0_TX3_N"
						(effects
							(font
								(size 1.27 1.27)
							)
						)
					)
					(number "154"
						(effects
							(font
								(size 1.27 1.27)
							)
						)
					)
				)
				(pin passive line
					(at -5.08 -66.04 0)
					(length 5.08)
					(name "PCIE0_RX3_N"
						(effects
							(font
								(size 1.27 1.27)
							)
						)
					)
					(number "155"
						(effects
							(font
								(size 1.27 1.27)
							)
						)
					)
				)
				(pin passive line
					(at -5.08 -63.5 0)
					(length 5.08)
					(name "PCIE0_TX3_P"
						(effects
							(font
								(size 1.27 1.27)
							)
						)
					)
					(number "156"
						(effects
							(font
								(size 1.27 1.27)
							)
						)
					)
				)
				(pin passive line
					(at -5.08 -68.58 0)
					(length 5.08)
					(name "PCIE0_RX3_P"
						(effects
							(font
								(size 1.27 1.27)
							)
						)
					)
					(number "157"
						(effects
							(font
								(size 1.27 1.27)
							)
						)
					)
				)
				(pin passive line
					(at -5.08 -15.24 0)
					(length 5.08)
					(name "PCIE0_CLK_N"
						(effects
							(font
								(size 1.27 1.27)
							)
						)
					)
					(number "160"
						(effects
							(font
								(size 1.27 1.27)
							)
						)
					)
				)
				(pin passive line
					(at -5.08 -17.78 0)
					(length 5.08)
					(name "PCIE0_CLK_P"
						(effects
							(font
								(size 1.27 1.27)
							)
						)
					)
					(number "162"
						(effects
							(font
								(size 1.27 1.27)
							)
						)
					)
				)
				(pin passive line
					(at -5.08 -91.44 0)
					(length 5.08)
					(name "PCIE1_RX0_N"
						(effects
							(font
								(size 1.27 1.27)
							)
						)
					)
					(number "167"
						(effects
							(font
								(size 1.27 1.27)
							)
						)
					)
				)
				(pin passive line
					(at -5.08 -93.98 0)
					(length 5.08)
					(name "PCIE1_RX0_P"
						(effects
							(font
								(size 1.27 1.27)
							)
						)
					)
					(number "169"
						(effects
							(font
								(size 1.27 1.27)
							)
						)
					)
				)
				(pin passive line
					(at -5.08 -86.36 0)
					(length 5.08)
					(name "PCIE1_TX0_N"
						(effects
							(font
								(size 1.27 1.27)
							)
						)
					)
					(number "172"
						(effects
							(font
								(size 1.27 1.27)
							)
						)
					)
				)
				(pin passive line
					(at -5.08 -78.74 0)
					(length 5.08)
					(name "PCIE1_CLK_N"
						(effects
							(font
								(size 1.27 1.27)
							)
						)
					)
					(number "173"
						(effects
							(font
								(size 1.27 1.27)
							)
						)
					)
				)
				(pin passive line
					(at -5.08 -88.9 0)
					(length 5.08)
					(name "PCIE1_TX0_P"
						(effects
							(font
								(size 1.27 1.27)
							)
						)
					)
					(number "174"
						(effects
							(font
								(size 1.27 1.27)
							)
						)
					)
				)
				(pin passive line
					(at -5.08 -81.28 0)
					(length 5.08)
					(name "PCIE1_CLK_P"
						(effects
							(font
								(size 1.27 1.27)
							)
						)
					)
					(number "175"
						(effects
							(font
								(size 1.27 1.27)
							)
						)
					)
				)
				(pin passive line
					(at -5.08 -5.08 0)
					(length 5.08)
					(name "PCIE_WAKE*"
						(effects
							(font
								(size 1.27 1.27)
							)
						)
					)
					(number "179"
						(effects
							(font
								(size 1.27 1.27)
							)
						)
					)
				)
				(pin passive line
					(at -5.08 -12.7 0)
					(length 5.08)
					(name "PCIE0_CLKREQ*"
						(effects
							(font
								(size 1.27 1.27)
							)
						)
					)
					(number "180"
						(effects
							(font
								(size 1.27 1.27)
							)
						)
					)
				)
				(pin passive line
					(at -5.08 -10.16 0)
					(length 5.08)
					(name "PCIE0_RST*"
						(effects
							(font
								(size 1.27 1.27)
							)
						)
					)
					(number "181"
						(effects
							(font
								(size 1.27 1.27)
							)
						)
					)
				)
				(pin passive line
					(at -5.08 -76.2 0)
					(length 5.08)
					(name "PCIE1_CLKREQ*"
						(effects
							(font
								(size 1.27 1.27)
							)
						)
					)
					(number "182"
						(effects
							(font
								(size 1.27 1.27)
							)
						)
					)
				)
				(pin passive line
					(at -5.08 -73.66 0)
					(length 5.08)
					(name "PCIE1_RST*"
						(effects
							(font
								(size 1.27 1.27)
							)
						)
					)
					(number "183"
						(effects
							(font
								(size 1.27 1.27)
							)
						)
					)
				)
				(pin passive line
					(at -5.08 -99.06 0)
					(length 5.08)
					(name "PCIE2_RST*"
						(effects
							(font
								(size 1.27 1.27)
							)
						)
					)
					(number "219"
						(effects
							(font
								(size 1.27 1.27)
							)
						)
					)
				)
				(pin passive line
					(at -5.08 -101.6 0)
					(length 5.08)
					(name "PCIE2_CLKREQ*"
						(effects
							(font
								(size 1.27 1.27)
							)
						)
					)
					(number "221"
						(effects
							(font
								(size 1.27 1.27)
							)
						)
					)
				)
				(pin passive line
					(at -5.08 -124.46 0)
					(length 5.08)
					(name "PCIE3_RST*"
						(effects
							(font
								(size 1.27 1.27)
							)
						)
					)
					(number "223"
						(effects
							(font
								(size 1.27 1.27)
							)
						)
					)
				)
				(pin passive line
					(at -5.08 -127 0)
					(length 5.08)
					(name "PCIE3_CLKREQ*"
						(effects
							(font
								(size 1.27 1.27)
							)
						)
					)
					(number "225"
						(effects
							(font
								(size 1.27 1.27)
							)
						)
					)
				)
				(pin passive line
					(at -5.08 -129.54 0)
					(length 5.08)
					(name "PCIE3_CLK_N"
						(effects
							(font
								(size 1.27 1.27)
							)
						)
					)
					(number "227"
						(effects
							(font
								(size 1.27 1.27)
							)
						)
					)
				)
				(pin passive line
					(at -5.08 -132.08 0)
					(length 5.08)
					(name "PCIE3_CLK_P"
						(effects
							(font
								(size 1.27 1.27)
							)
						)
					)
					(number "229"
						(effects
							(font
								(size 1.27 1.27)
							)
						)
					)
				)
				(pin passive line
					(at -5.08 -116.84 0)
					(length 5.08)
					(name "PCIE2_RX0_N"
						(effects
							(font
								(size 1.27 1.27)
							)
						)
					)
					(number "40"
						(effects
							(font
								(size 1.27 1.27)
							)
						)
					)
				)
				(pin passive line
					(at -5.08 -119.38 0)
					(length 5.08)
					(name "PCIE2_RX0_P"
						(effects
							(font
								(size 1.27 1.27)
							)
						)
					)
					(number "42"
						(effects
							(font
								(size 1.27 1.27)
							)
						)
					)
				)
				(pin passive line
					(at -5.08 -111.76 0)
					(length 5.08)
					(name "PCIE2_TX0_N"
						(effects
							(font
								(size 1.27 1.27)
							)
						)
					)
					(number "46"
						(effects
							(font
								(size 1.27 1.27)
							)
						)
					)
				)
				(pin passive line
					(at -5.08 -114.3 0)
					(length 5.08)
					(name "PCIE2_TX0_P"
						(effects
							(font
								(size 1.27 1.27)
							)
						)
					)
					(number "48"
						(effects
							(font
								(size 1.27 1.27)
							)
						)
					)
				)
				(pin passive line
					(at -5.08 -104.14 0)
					(length 5.08)
					(name "PCIE2_CLK_N"
						(effects
							(font
								(size 1.27 1.27)
							)
						)
					)
					(number "52"
						(effects
							(font
								(size 1.27 1.27)
							)
						)
					)
				)
				(pin passive line
					(at -5.08 -106.68 0)
					(length 5.08)
					(name "PCIE2_CLK_P"
						(effects
							(font
								(size 1.27 1.27)
							)
						)
					)
					(number "54"
						(effects
							(font
								(size 1.27 1.27)
							)
						)
					)
				)
				(pin passive line
					(at -5.08 -142.24 0)
					(length 5.08)
					(name "PCIE2_RX1_N/PCIE3_RX0_N"
						(effects
							(font
								(size 1.27 1.27)
							)
						)
					)
					(number "58"
						(effects
							(font
								(size 1.27 1.27)
							)
						)
					)
					(alternate "PCIE2_RX1_N" passive line)
					(alternate "PCIE3_RX0_N" passive line)
				)
				(pin passive line
					(at -5.08 -144.78 0)
					(length 5.08)
					(name "PCIE2_RX1_P/PCIE3_RX0_P"
						(effects
							(font
								(size 1.27 1.27)
							)
						)
					)
					(number "60"
						(effects
							(font
								(size 1.27 1.27)
							)
						)
					)
					(alternate "PCIE2_RX1_P" passive line)
					(alternate "PCIE3_RX0_P" passive line)
				)
				(pin passive line
					(at -5.08 -137.16 0)
					(length 5.08)
					(name "PCIE2_TX1_N/PCIE3_TX0_N"
						(effects
							(font
								(size 1.27 1.27)
							)
						)
					)
					(number "64"
						(effects
							(font
								(size 1.27 1.27)
							)
						)
					)
					(alternate "PCIE2_TX1_N" passive line)
					(alternate "PCIE3_TX0_N" passive line)
				)
				(pin passive line
					(at -5.08 -139.7 0)
					(length 5.08)
					(name "PCIE2_TX1_P/PCIE3_TX0_P"
						(effects
							(font
								(size 1.27 1.27)
							)
						)
					)
					(number "66"
						(effects
							(font
								(size 1.27 1.27)
							)
						)
					)
					(alternate "PCIE2_TX1_P" passive line)
					(alternate "PCIE3_TX0_P" passive line)
				)
			)
			(symbol "Jetson-Orin-9.2H-socket_1_7_1"
				(rectangle
					(start 0 0)
					(end 31.75 -43.18)
					(stroke
						(width 0.254)
						(type default)
					)
					(fill
						(type background)
					)
				)
				(pin passive line
					(at -5.08 -12.7 0)
					(length 5.08)
					(name "GBE_MDI0_N"
						(effects
							(font
								(size 1.27 1.27)
							)
						)
					)
					(number "184"
						(effects
							(font
								(size 1.27 1.27)
							)
						)
					)
				)
				(pin passive line
					(at -5.08 -15.24 0)
					(length 5.08)
					(name "GBE_MDI0_P"
						(effects
							(font
								(size 1.27 1.27)
							)
						)
					)
					(number "186"
						(effects
							(font
								(size 1.27 1.27)
							)
						)
					)
				)
				(pin passive line
					(at -5.08 -5.08 0)
					(length 5.08)
					(name "GBE_LED_LINK"
						(effects
							(font
								(size 1.27 1.27)
							)
						)
					)
					(number "188"
						(effects
							(font
								(size 1.27 1.27)
							)
						)
					)
				)
				(pin passive line
					(at -5.08 -20.32 0)
					(length 5.08)
					(name "GBE_MDI1_N"
						(effects
							(font
								(size 1.27 1.27)
							)
						)
					)
					(number "190"
						(effects
							(font
								(size 1.27 1.27)
							)
						)
					)
				)
				(pin passive line
					(at -5.08 -22.86 0)
					(length 5.08)
					(name "GBE_MDI1_P"
						(effects
							(font
								(size 1.27 1.27)
							)
						)
					)
					(number "192"
						(effects
							(font
								(size 1.27 1.27)
							)
						)
					)
				)
				(pin passive line
					(at -5.08 -7.62 0)
					(length 5.08)
					(name "GBE_LED_ACT"
						(effects
							(font
								(size 1.27 1.27)
							)
						)
					)
					(number "194"
						(effects
							(font
								(size 1.27 1.27)
							)
						)
					)
				)
				(pin passive line
					(at -5.08 -27.94 0)
					(length 5.08)
					(name "GBE_MDI2_N"
						(effects
							(font
								(size 1.27 1.27)
							)
						)
					)
					(number "196"
						(effects
							(font
								(size 1.27 1.27)
							)
						)
					)
				)
				(pin passive line
					(at -5.08 -30.48 0)
					(length 5.08)
					(name "GBE_MDI2_P"
						(effects
							(font
								(size 1.27 1.27)
							)
						)
					)
					(number "198"
						(effects
							(font
								(size 1.27 1.27)
							)
						)
					)
				)
				(pin passive line
					(at -5.08 -35.56 0)
					(length 5.08)
					(name "GBE_MDI3_N"
						(effects
							(font
								(size 1.27 1.27)
							)
						)
					)
					(number "202"
						(effects
							(font
								(size 1.27 1.27)
							)
						)
					)
				)
				(pin passive line
					(at -5.08 -38.1 0)
					(length 5.08)
					(name "GBE_MDI3_P"
						(effects
							(font
								(size 1.27 1.27)
							)
						)
					)
					(number "204"
						(effects
							(font
								(size 1.27 1.27)
							)
						)
					)
				)
			)
			(symbol "Jetson-Orin-9.2H-socket_1_8_1"
				(polyline
					(pts
						(xy 19.685 -4.445) (xy 19.685 -33.655)
					)
					(stroke
						(width 0)
						(type default)
					)
					(fill
						(type none)
					)
				)
				(rectangle
					(start 0 0)
					(end 31.75 -38.1)
					(stroke
						(width 0.254)
						(type default)
					)
					(fill
						(type background)
					)
				)
				(arc
					(start 19.05 -34.29)
					(mid 19.4998 -34.1048)
					(end 19.685 -33.655)
					(stroke
						(width 0)
						(type default)
					)
					(fill
						(type none)
					)
				)
				(arc
					(start 19.685 -4.445)
					(mid 19.499 -3.996)
					(end 19.05 -3.81)
					(stroke
						(width 0)
						(type default)
					)
					(fill
						(type none)
					)
				)
				(text "1.8V CMOS"
					(at 20.32 -17.78 0)
					(effects
						(font
							(size 1.27 1.27)
						)
						(justify left)
					)
				)
				(pin passive line
					(at -5.08 -5.08 0)
					(length 5.08)
					(name "GPIO01/CLK"
						(effects
							(font
								(size 1.27 1.27)
							)
						)
					)
					(number "118"
						(effects
							(font
								(size 1.27 1.27)
							)
						)
					)
					(alternate "GPIO01" passive line)
					(alternate "GPIO01(CLK)" passive line)
				)
				(pin passive line
					(at -5.08 -7.62 0)
					(length 5.08)
					(name "GPIO02"
						(effects
							(font
								(size 1.27 1.27)
							)
						)
					)
					(number "124"
						(effects
							(font
								(size 1.27 1.27)
							)
						)
					)
				)
				(pin passive line
					(at -5.08 -10.16 0)
					(length 5.08)
					(name "GPIO03"
						(effects
							(font
								(size 1.27 1.27)
							)
						)
					)
					(number "126"
						(effects
							(font
								(size 1.27 1.27)
							)
						)
					)
				)
				(pin passive line
					(at -5.08 -12.7 0)
					(length 5.08)
					(name "GPIO04"
						(effects
							(font
								(size 1.27 1.27)
							)
						)
					)
					(number "127"
						(effects
							(font
								(size 1.27 1.27)
							)
						)
					)
				)
				(pin passive line
					(at -5.08 -15.24 0)
					(length 5.08)
					(name "GPIO05"
						(effects
							(font
								(size 1.27 1.27)
							)
						)
					)
					(number "128"
						(effects
							(font
								(size 1.27 1.27)
							)
						)
					)
				)
				(pin passive line
					(at -5.08 -17.78 0)
					(length 5.08)
					(name "GPIO06"
						(effects
							(font
								(size 1.27 1.27)
							)
						)
					)
					(number "130"
						(effects
							(font
								(size 1.27 1.27)
							)
						)
					)
				)
				(pin passive line
					(at -5.08 -20.32 0)
					(length 5.08)
					(name "GPIO07/PWM"
						(effects
							(font
								(size 1.27 1.27)
							)
						)
					)
					(number "206"
						(effects
							(font
								(size 1.27 1.27)
							)
						)
					)
					(alternate "GPIO07" passive line)
					(alternate "GPIO07(PWM)" passive line)
				)
				(pin passive line
					(at -5.08 -22.86 0)
					(length 5.08)
					(name "GPIO09/AUD_MCLK"
						(effects
							(font
								(size 1.27 1.27)
							)
						)
					)
					(number "211"
						(effects
							(font
								(size 1.27 1.27)
							)
						)
					)
					(alternate "GPIO09" passive line)
					(alternate "GPIO09(AUD_MCLK)" passive line)
				)
				(pin passive line
					(at -5.08 -25.4 0)
					(length 5.08)
					(name "GPIO10"
						(effects
							(font
								(size 1.27 1.27)
							)
						)
					)
					(number "212"
						(effects
							(font
								(size 1.27 1.27)
							)
						)
					)
				)
				(pin passive line
					(at -5.08 -27.94 0)
					(length 5.08)
					(name "GPIO11/CLK"
						(effects
							(font
								(size 1.27 1.27)
							)
						)
					)
					(number "216"
						(effects
							(font
								(size 1.27 1.27)
							)
						)
					)
					(alternate "GPIO11" passive line)
					(alternate "GPIO11(CLK)" passive line)
				)
				(pin passive line
					(at -5.08 -30.48 0)
					(length 5.08)
					(name "GPIO12/PWM"
						(effects
							(font
								(size 1.27 1.27)
							)
						)
					)
					(number "218"
						(effects
							(font
								(size 1.27 1.27)
							)
						)
					)
					(alternate "GPIO12" passive line)
					(alternate "GPIO12(PWM)" passive line)
				)
				(pin passive line
					(at -5.08 -33.02 0)
					(length 5.08)
					(name "GPIO13/PWM"
						(effects
							(font
								(size 1.27 1.27)
							)
						)
					)
					(number "228"
						(effects
							(font
								(size 1.27 1.27)
							)
						)
					)
					(alternate "GPIO13" passive line)
					(alternate "GPIO13(PWM)" passive line)
				)
			)
		)
	(symbol "jetson-orin-baseboard:TP_0.75mm_SMD_10"
			(pin_numbers hide)
			(pin_names hide)
			(exclude_from_sim no)
			(in_bom yes)
			(on_board yes)
			(property "Reference" "TP"
				(at 17.78 -5.08 0)
				(effects
					(font
						(size 1.27 1.27)
						(thickness 0.15)
					)
					(justify left bottom)
				)
			)
			(property "Value" "TP_0.75mm_SMD_10"
				(at 17.78 -7.62 0)
				(effects
					(font
						(size 1.27 1.27)
						(thickness 0.15)
					)
					(justify left bottom)
					(hide yes)
				)
			)
			(property "Footprint" "jetson-orin-baseboard-footprints:TP_SMD_0.75mm"
				(at 17.78 -10.16 0)
				(effects
					(font
						(size 1.27 1.27)
						(thickness 0.15)
					)
					(justify left bottom)
					(hide yes)
				)
			)
			(property "Datasheet" ""
				(at 17.78 -12.7 0)
				(effects
					(font
						(size 1.27 1.27)
						(thickness 0.15)
					)
					(justify left bottom)
					(hide yes)
				)
			)
			(property "Description" "Test Point 0.75mm"
				(at 0 0 0)
				(effects
					(font
						(size 1.27 1.27)
					)
					(hide yes)
				)
			)
			(property "MPN" ""
				(at 17.78 -15.24 0)
				(effects
					(font
						(size 1.27 1.27)
						(thickness 0.15)
					)
					(justify left bottom)
					(hide yes)
				)
			)
			(property "Manufacturer" ""
				(at 17.78 -17.78 0)
				(effects
					(font
						(size 1.27 1.27)
						(thickness 0.15)
					)
					(justify left bottom)
					(hide yes)
				)
			)
			(property "Author" "Antmicro"
				(at 17.78 -20.32 0)
				(effects
					(font
						(size 1.27 1.27)
						(thickness 0.15)
					)
					(justify left bottom)
					(hide yes)
				)
			)
			(property "License" "Apache-2.0"
				(at 17.78 -22.86 0)
				(effects
					(font
						(size 1.27 1.27)
						(thickness 0.15)
					)
					(justify left bottom)
					(hide yes)
				)
			)
			(symbol "TP_0.75mm_SMD_10_1_1"
				(circle
					(center 3.175 0)
					(radius 0.635)
					(stroke
						(width 0.254)
						(type default)
					)
					(fill
						(type none)
					)
				)
				(pin passive line
					(at 0 0 0)
					(length 2.54)
					(name "1"
						(effects
							(font
								(size 1.27 1.27)
							)
						)
					)
					(number "1"
						(effects
							(font
								(size 1.27 1.27)
							)
						)
					)
				)
			)
		)
)
